(kicad_pcb
	(version 20260206)
	(generator "pcbnew")
	(generator_version "10.0")
	(general
		(thickness 1.6)
		(legacy_teardrops no)
	)
	(paper "A4")
	(layers
		(0 "F.Cu" signal "TOP")
		(4 "In1.Cu" signal "L2GND")
		(6 "In2.Cu" signal "L3")
		(8 "In3.Cu" signal "L4")
		(10 "In4.Cu" signal "L5GND")
		(2 "B.Cu" signal "BOTTOM")
		(9 "F.Adhes" user "F.Adhesive")
		(11 "B.Adhes" user "B.Adhesive")
		(13 "F.Paste" user "Package Geometry/Pastemask Top")
		(15 "B.Paste" user "Package Geometry/Pastemask Bottom")
		(5 "F.SilkS" user "Ref Des/Silkscreen Top")
		(7 "B.SilkS" user "Ref Des/Silkscreen Bottom")
		(1 "F.Mask" user "Board Geometry/Soldermask Top")
		(3 "B.Mask" user "Board Geometry/Soldermask Bottom")
		(17 "Dwgs.User" user "User.Drawings")
		(19 "Cmts.User" user "User.Comments")
		(21 "Eco1.User" user "User.Eco1")
		(23 "Eco2.User" user "User.Eco2")
		(25 "Edge.Cuts" user "Board Geometry/Outline")
		(27 "Margin" user)
		(31 "F.CrtYd" user "Package Geometry/Place Bound Top")
		(29 "B.CrtYd" user "Package Geometry/Place Bound Bottom")
		(35 "F.Fab" user "Ref Des/Assembly Top")
		(33 "B.Fab" user "Ref Des/Assembly Bottom")
	)
	(setup
		(pad_to_mask_clearance 0)
		(allow_soldermask_bridges_in_footprints no)
		(tenting
			(front yes)
			(back yes)
		)
		(covering
			(front no)
			(back no)
		)
		(plugging
			(front no)
			(back no)
		)
		(capping no)
		(filling no)
		(pcbplotparams
			(layerselection 0x00000000_00000000_55555555_5755f5ff)
			(plot_on_all_layers_selection 0x00000000_00000000_00000000_00000000)
			(disableapertmacros no)
			(usegerberextensions no)
			(usegerberattributes yes)
			(usegerberadvancedattributes yes)
			(creategerberjobfile yes)
			(dashed_line_dash_ratio 12)
			(dashed_line_gap_ratio 3)
			(svgprecision 4)
			(plotframeref no)
			(mode 1)
			(useauxorigin no)
			(pdf_front_fp_property_popups yes)
			(pdf_back_fp_property_popups yes)
			(pdf_metadata yes)
			(pdf_single_document no)
			(dxfpolygonmode yes)
			(dxfimperialunits yes)
			(dxfusepcbnewfont yes)
			(psnegative no)
			(psa4output no)
			(plot_black_and_white yes)
			(sketchpadsonfab no)
			(plotpadnumbers no)
			(hidednponfab no)
			(sketchdnponfab yes)
			(crossoutdnponfab yes)
			(subtractmaskfromsilk no)
			(outputformat 1)
			(mirror no)
			(drillshape 1)
			(scaleselection 1)
			(outputdirectory "")
		)
	)
	(footprint ""
		(layer "F.Cu")
		(at 83.058 -36.068 90)
		(property "Reference" "R140"
			(at 0 0 90)
			(layer "F.SilkS")
			(hide yes)
			(effects
				(font
					(size 1.27 1.27)
				)
			)
		)
		(property "Value" "200KR2F-L-GP"
			(at 0.064008 -3.993896 90)
			(unlocked yes)
			(layer "F.Fab")
			(hide yes)
			(effects
				(font
					(size 1.016 1.016)
					(thickness 0.1524)
				)
			)
		)
		(property "Device Type" "R402H16"
			(at 0.064008 -5.517896 90)
			(unlocked yes)
			(layer "F.Fab")
			(hide yes)
			(effects
				(font
					(size 1.016 1.016)
					(thickness 0.1524)
				)
			)
		)
		(duplicate_pad_numbers_are_jumpers no)
		(fp_line
			(start 0.508 -0.9398)
			(end -0.508 -0.9398)
			(stroke
				(width 0.1524)
				(type default)
			)
			(layer "F.SilkS")
		)
		(fp_line
			(start -0.508 -0.9398)
			(end -0.508 0.9398)
			(stroke
				(width 0.1524)
				(type default)
			)
			(layer "F.SilkS")
		)
		(fp_rect
			(start -0.508 0.9398)
			(end 0.508 -0.9398)
			(stroke
				(width 0)
				(type default)
			)
			(fill no)
			(layer "F.CrtYd")
		)
		(fp_rect
			(start -0.508 0.9398)
			(end 0.508 -0.9398)
			(stroke
				(width 0)
				(type default)
			)
			(fill no)
			(layer "F.Fab")
		)
		(pad "1" smd custom
			(at 0 -0.4445 90)
			(size 0.1397 0.1397)
			(layers "F.Cu" "F.Mask" "F.Paste")
			(net "SW_SW_R_0")
			(options
				(clearance outline)
				(anchor circle)
			)
			(primitives
				(gr_poly
					(pts
						(arc
							(start -0.1778 -0.2794)
							(mid -0.249642 -0.249642)
							(end -0.2794 -0.1778)
						)
						(arc
							(start -0.2794 0.1778)
							(mid -0.249642 0.249642)
							(end -0.1778 0.2794)
						)
						(arc
							(start 0.1778 0.2794)
							(mid 0.249642 0.249642)
							(end 0.2794 0.1778)
						)
						(arc
							(start 0.2794 -0.1778)
							(mid 0.249642 -0.249642)
							(end 0.1778 -0.2794)
						)
					)
					(width 0)
					(fill yes)
				)
			)
		)
		(pad "2" smd custom
			(at 0 0.4445 90)
			(size 0.1397 0.1397)
			(layers "F.Cu" "F.Mask" "F.Paste")
			(net "SW_SW_R_N_0")
			(options
				(clearance outline)
				(anchor circle)
			)
			(primitives
				(gr_poly
					(pts
						(arc
							(start -0.1778 -0.2794)
							(mid -0.249642 -0.249642)
							(end -0.2794 -0.1778)
						)
						(arc
							(start -0.2794 0.1778)
							(mid -0.249642 0.249642)
							(end -0.1778 0.2794)
						)
						(arc
							(start 0.1778 0.2794)
							(mid 0.249642 0.249642)
							(end 0.2794 0.1778)
						)
						(arc
							(start 0.2794 -0.1778)
							(mid 0.249642 -0.249642)
							(end 0.1778 -0.2794)
						)
					)
					(width 0)
					(fill yes)
				)
			)
		)
	)
	(footprint ""
		(layer "F.Cu")
		(at 51.347624 -8.483346 90)
		(property "Reference" "C15"
			(at 0 0 90)
			(layer "F.SilkS")
			(hide yes)
			(effects
				(font
					(size 1.27 1.27)
				)
			)
		)
		(property "Value" "SC10U10V5KX-L1-GP"
			(at -0.0762 -6.1214 90)
			(unlocked yes)
			(layer "F.Fab")
			(hide yes)
			(effects
				(font
					(size 1.016 1.016)
					(thickness 0.1524)
				)
			)
		)
		(property "Device Type" "C805H58"
			(at -0.0762 -8.1534 90)
			(unlocked yes)
			(layer "F.Fab")
			(hide yes)
			(effects
				(font
					(size 1.016 1.016)
					(thickness 0.1524)
				)
			)
		)
		(duplicate_pad_numbers_are_jumpers no)
		(fp_line
			(start 0.635 0)
			(end -0.635 0)
			(stroke
				(width 0.508)
				(type default)
			)
			(layer "F.SilkS")
		)
		(fp_rect
			(start -0.9652 1.778)
			(end 0.9652 -1.778)
			(stroke
				(width 0)
				(type default)
			)
			(fill no)
			(layer "F.CrtYd")
		)
		(fp_poly
			(pts
				(xy -0.9652 -1.778) (xy 0.9652 -1.778) (xy 0.9652 1.778) (xy -0.9652 1.778)
			)
			(stroke
				(width 0)
				(type default)
			)
			(fill no)
			(layer "F.Fab")
		)
		(pad "1" smd rect
			(at 0 -0.9652 90)
			(size 1.397 1.143)
			(layers "F.Cu" "F.Mask" "F.Paste")
			(net "P5V_SW_L")
		)
		(pad "2" smd rect
			(at 0 0.9652 90)
			(size 1.397 1.143)
			(layers "F.Cu" "F.Mask" "F.Paste")
			(net "GND")
		)
	)
	(footprint ""
		(layer "F.Cu")
		(at 122.8598 -57.277)
		(property "Reference" "R2"
			(at 0 0 0)
			(layer "F.SilkS")
			(hide yes)
			(effects
				(font
					(size 1.27 1.27)
				)
			)
		)
		(property "Value" "10KR2J-3-GP"
			(at 0.064008 -3.993896 0)
			(unlocked yes)
			(layer "F.Fab")
			(hide yes)
			(effects
				(font
					(size 1.016 1.016)
					(thickness 0.1524)
				)
			)
		)
		(property "Device Type" "R402H16"
			(at 0.064008 -5.517896 0)
			(unlocked yes)
			(layer "F.Fab")
			(hide yes)
			(effects
				(font
					(size 1.016 1.016)
					(thickness 0.1524)
				)
			)
		)
		(duplicate_pad_numbers_are_jumpers no)
		(fp_line
			(start -0.508 -0.9398)
			(end -0.508 0.9398)
			(stroke
				(width 0.1524)
				(type default)
			)
			(layer "F.SilkS")
		)
		(fp_line
			(start 0.508 -0.9398)
			(end -0.508 -0.9398)
			(stroke
				(width 0.1524)
				(type default)
			)
			(layer "F.SilkS")
		)
		(fp_rect
			(start -0.508 0.9398)
			(end 0.508 -0.9398)
			(stroke
				(width 0)
				(type default)
			)
			(fill no)
			(layer "F.CrtYd")
		)
		(fp_rect
			(start -0.508 0.9398)
			(end 0.508 -0.9398)
			(stroke
				(width 0)
				(type default)
			)
			(fill no)
			(layer "F.Fab")
		)
		(pad "1" smd custom
			(at 0 -0.4445)
			(size 0.1397 0.1397)
			(layers "F.Cu" "F.Mask" "F.Paste")
			(net "P3V3")
			(options
				(clearance outline)
				(anchor circle)
			)
			(primitives
				(gr_poly
					(pts
						(arc
							(start -0.1778 -0.2794)
							(mid -0.249642 -0.249642)
							(end -0.2794 -0.1778)
						)
						(arc
							(start -0.2794 0.1778)
							(mid -0.249642 0.249642)
							(end -0.1778 0.2794)
						)
						(arc
							(start 0.1778 0.2794)
							(mid 0.249642 0.249642)
							(end 0.2794 0.1778)
						)
						(arc
							(start 0.2794 -0.1778)
							(mid 0.249642 -0.249642)
							(end 0.1778 -0.2794)
						)
					)
					(width 0)
					(fill yes)
				)
			)
		)
		(pad "2" smd custom
			(at 0 0.4445)
			(size 0.1397 0.1397)
			(layers "F.Cu" "F.Mask" "F.Paste")
			(net "HBA_PRSNT0_N")
			(options
				(clearance outline)
				(anchor circle)
			)
			(primitives
				(gr_poly
					(pts
						(arc
							(start -0.1778 -0.2794)
							(mid -0.249642 -0.249642)
							(end -0.2794 -0.1778)
						)
						(arc
							(start -0.2794 0.1778)
							(mid -0.249642 0.249642)
							(end -0.1778 0.2794)
						)
						(arc
							(start 0.1778 0.2794)
							(mid 0.249642 0.249642)
							(end 0.2794 0.1778)
						)
						(arc
							(start 0.2794 -0.1778)
							(mid 0.249642 -0.249642)
							(end 0.1778 -0.2794)
						)
					)
					(width 0)
					(fill yes)
				)
			)
		)
	)
	(footprint ""
		(layer "F.Cu")
		(at 77.0001 -61.699902)
		(property "Reference" "H4"
			(at 0 0 0)
			(layer "F.SilkS")
			(hide yes)
			(effects
				(font
					(size 1.27 1.27)
				)
			)
		)
		(property "Value" "HOLET217B237R130-GP"
			(at -5.08 -0.4572 0)
			(unlocked yes)
			(layer "F.Fab")
			(hide yes)
			(effects
				(font
					(size 1.016 1.016)
					(thickness 0.1524)
				)
			)
		)
		(property "Device Type" "HOLET217B237R130"
			(at -5.08 -1.9812 0)
			(unlocked yes)
			(layer "F.Fab")
			(hide yes)
			(effects
				(font
					(size 1.016 1.016)
					(thickness 0.1524)
				)
			)
		)
		(duplicate_pad_numbers_are_jumpers no)
		(fp_poly
			(pts
				(arc
					(start 3.3147 0)
					(mid -3.3147 0)
					(end 3.3147 0)
				)
			)
			(stroke
				(width 0)
				(type default)
			)
			(fill no)
			(layer "B.CrtYd")
		)
		(fp_poly
			(pts
				(arc
					(start 3.0607 0)
					(mid -3.0607 0)
					(end 3.0607 0)
				)
			)
			(stroke
				(width 0)
				(type default)
			)
			(fill no)
			(layer "F.CrtYd")
		)
		(fp_poly
			(pts
				(arc
					(start 3.3147 0)
					(mid -3.3147 0)
					(end 3.3147 0)
				)
			)
			(stroke
				(width 0)
				(type default)
			)
			(fill no)
			(layer "B.Fab")
		)
		(fp_poly
			(pts
				(arc
					(start 3.0607 0)
					(mid -3.0607 0)
					(end 3.0607 0)
				)
			)
			(stroke
				(width 0)
				(type default)
			)
			(fill no)
			(layer "F.Fab")
		)
		(pad "1" thru_hole circle
			(at 0 0)
			(size 5.5118 5.5118)
			(drill 3.302)
			(layers "*.Cu" "*.Mask")
			(remove_unused_layers no)
			(net "GND")
			(clearance -0.5969)
			(thermal_gap 0.3048)
			(padstack
				(mode front_inner_back)
				(layer "Inner"
					(shape circle)
					(size 3.7084 3.7084)
					(clearance 0.3048)
				)
				(layer "B.Cu"
					(shape circle)
					(size 6.0198 6.0198)
					(clearance -0.8509)
				)
			)
		)
	)
	(footprint ""
		(layer "F.Cu")
		(at 78.105 -33.909 90)
		(property "Reference" "R138"
			(at 0 0 90)
			(layer "F.SilkS")
			(hide yes)
			(effects
				(font
					(size 1.27 1.27)
				)
			)
		)
		(property "Value" "4K7R2J-2-GP"
			(at 0.064008 -3.993896 90)
			(unlocked yes)
			(layer "F.Fab")
			(hide yes)
			(effects
				(font
					(size 1.016 1.016)
					(thickness 0.1524)
				)
			)
		)
		(property "Device Type" "R402H16"
			(at 0.064008 -5.517896 90)
			(unlocked yes)
			(layer "F.Fab")
			(hide yes)
			(effects
				(font
					(size 1.016 1.016)
					(thickness 0.1524)
				)
			)
		)
		(duplicate_pad_numbers_are_jumpers no)
		(fp_line
			(start 0.508 -0.9398)
			(end -0.508 -0.9398)
			(stroke
				(width 0.1524)
				(type default)
			)
			(layer "F.SilkS")
		)
		(fp_line
			(start -0.508 -0.9398)
			(end -0.508 0.9398)
			(stroke
				(width 0.1524)
				(type default)
			)
			(layer "F.SilkS")
		)
		(fp_rect
			(start -0.508 0.9398)
			(end 0.508 -0.9398)
			(stroke
				(width 0)
				(type default)
			)
			(fill no)
			(layer "F.CrtYd")
		)
		(fp_rect
			(start -0.508 0.9398)
			(end 0.508 -0.9398)
			(stroke
				(width 0)
				(type default)
			)
			(fill no)
			(layer "F.Fab")
		)
		(pad "1" smd custom
			(at 0 -0.4445 90)
			(size 0.1397 0.1397)
			(layers "F.Cu" "F.Mask" "F.Paste")
			(net "P3V3")
			(options
				(clearance outline)
				(anchor circle)
			)
			(primitives
				(gr_poly
					(pts
						(arc
							(start -0.1778 -0.2794)
							(mid -0.249642 -0.249642)
							(end -0.2794 -0.1778)
						)
						(arc
							(start -0.2794 0.1778)
							(mid -0.249642 0.249642)
							(end -0.1778 0.2794)
						)
						(arc
							(start 0.1778 0.2794)
							(mid 0.249642 0.249642)
							(end 0.2794 0.1778)
						)
						(arc
							(start 0.2794 -0.1778)
							(mid 0.249642 -0.249642)
							(end 0.1778 -0.2794)
						)
					)
					(width 0)
					(fill yes)
				)
			)
		)
		(pad "2" smd custom
			(at 0 0.4445 90)
			(size 0.1397 0.1397)
			(layers "F.Cu" "F.Mask" "F.Paste")
			(net "PWR_EN_D_0")
			(options
				(clearance outline)
				(anchor circle)
			)
			(primitives
				(gr_poly
					(pts
						(arc
							(start -0.1778 -0.2794)
							(mid -0.249642 -0.249642)
							(end -0.2794 -0.1778)
						)
						(arc
							(start -0.2794 0.1778)
							(mid -0.249642 0.249642)
							(end -0.1778 0.2794)
						)
						(arc
							(start 0.1778 0.2794)
							(mid 0.249642 0.249642)
							(end 0.2794 0.1778)
						)
						(arc
							(start 0.2794 -0.1778)
							(mid 0.249642 -0.249642)
							(end 0.1778 -0.2794)
						)
					)
					(width 0)
					(fill yes)
				)
			)
		)
	)
	(footprint ""
		(layer "F.Cu")
		(at 48.1838 -8.1534 -90)
		(property "Reference" "R9"
			(at 0 0 270)
			(layer "F.SilkS")
			(hide yes)
			(effects
				(font
					(size 1.27 1.27)
				)
			)
		)
		(property "Value" "10R3F-GP"
			(at -0.0254 -2.5146 270)
			(unlocked yes)
			(layer "F.Fab")
			(hide yes)
			(effects
				(font
					(size 1.016 1.016)
					(thickness 0.1524)
				)
			)
		)
		(property "Device Type" "R603H22"
			(at -0.0254 -4.0386 270)
			(unlocked yes)
			(layer "F.Fab")
			(hide yes)
			(effects
				(font
					(size 1.016 1.016)
					(thickness 0.1524)
				)
			)
		)
		(duplicate_pad_numbers_are_jumpers no)
		(fp_line
			(start -0.4826 0)
			(end -0.2032 0)
			(stroke
				(width 0.2032)
				(type default)
			)
			(layer "F.SilkS")
		)
		(fp_line
			(start 0.2032 0)
			(end 0.4826 0)
			(stroke
				(width 0.2032)
				(type default)
			)
			(layer "F.SilkS")
		)
		(fp_rect
			(start -0.5842 1.3335)
			(end 0.5842 -1.3335)
			(stroke
				(width 0)
				(type default)
			)
			(fill no)
			(layer "F.CrtYd")
		)
		(fp_rect
			(start -0.5842 1.3335)
			(end 0.5842 -1.3335)
			(stroke
				(width 0)
				(type default)
			)
			(fill no)
			(layer "F.Fab")
		)
		(pad "1" smd custom
			(at 0 -0.762 270)
			(size 0.2159 0.2159)
			(layers "F.Cu" "F.Mask" "F.Paste")
			(net "P5V_SW_L")
			(options
				(clearance outline)
				(anchor circle)
			)
			(primitives
				(gr_poly
					(pts
						(arc
							(start -0.3302 -0.4318)
							(mid -0.402042 -0.402042)
							(end -0.4318 -0.3302)
						)
						(arc
							(start -0.4318 0.3302)
							(mid -0.402042 0.402042)
							(end -0.3302 0.4318)
						)
						(arc
							(start 0.3302 0.4318)
							(mid 0.402042 0.402042)
							(end 0.4318 0.3302)
						)
						(arc
							(start 0.4318 -0.3302)
							(mid 0.402042 -0.402042)
							(end 0.3302 -0.4318)
						)
					)
					(width 0)
					(fill yes)
				)
			)
		)
		(pad "2" smd custom
			(at 0 0.762 270)
			(size 0.2159 0.2159)
			(layers "F.Cu" "F.Mask" "F.Paste")
			(net "5V_PRE_3")
			(options
				(clearance outline)
				(anchor circle)
			)
			(primitives
				(gr_poly
					(pts
						(arc
							(start -0.3302 -0.4318)
							(mid -0.402042 -0.402042)
							(end -0.4318 -0.3302)
						)
						(arc
							(start -0.4318 0.3302)
							(mid -0.402042 0.402042)
							(end -0.3302 0.4318)
						)
						(arc
							(start 0.3302 0.4318)
							(mid 0.402042 0.402042)
							(end 0.4318 0.3302)
						)
						(arc
							(start 0.4318 -0.3302)
							(mid 0.402042 -0.402042)
							(end 0.3302 -0.4318)
						)
					)
					(width 0)
					(fill yes)
				)
			)
		)
	)
	(footprint ""
		(layer "F.Cu")
		(at 47.117 -19.05 -90)
		(property "Reference" "R10"
			(at 0 0 270)
			(layer "F.SilkS")
			(hide yes)
			(effects
				(font
					(size 1.27 1.27)
				)
			)
		)
		(property "Value" "10R3F-GP"
			(at -0.0254 -2.5146 270)
			(unlocked yes)
			(layer "F.Fab")
			(hide yes)
			(effects
				(font
					(size 1.016 1.016)
					(thickness 0.1524)
				)
			)
		)
		(property "Device Type" "R603H22"
			(at -0.0254 -4.0386 270)
			(unlocked yes)
			(layer "F.Fab")
			(hide yes)
			(effects
				(font
					(size 1.016 1.016)
					(thickness 0.1524)
				)
			)
		)
		(duplicate_pad_numbers_are_jumpers no)
		(fp_line
			(start -0.4826 0)
			(end -0.2032 0)
			(stroke
				(width 0.2032)
				(type default)
			)
			(layer "F.SilkS")
		)
		(fp_line
			(start 0.2032 0)
			(end 0.4826 0)
			(stroke
				(width 0.2032)
				(type default)
			)
			(layer "F.SilkS")
		)
		(fp_rect
			(start -0.5842 1.3335)
			(end 0.5842 -1.3335)
			(stroke
				(width 0)
				(type default)
			)
			(fill no)
			(layer "F.CrtYd")
		)
		(fp_rect
			(start -0.5842 1.3335)
			(end 0.5842 -1.3335)
			(stroke
				(width 0)
				(type default)
			)
			(fill no)
			(layer "F.Fab")
		)
		(pad "1" smd custom
			(at 0 -0.762 270)
			(size 0.2159 0.2159)
			(layers "F.Cu" "F.Mask" "F.Paste")
			(net "P5V_SW_L")
			(options
				(clearance outline)
				(anchor circle)
			)
			(primitives
				(gr_poly
					(pts
						(arc
							(start -0.3302 -0.4318)
							(mid -0.402042 -0.402042)
							(end -0.4318 -0.3302)
						)
						(arc
							(start -0.4318 0.3302)
							(mid -0.402042 0.402042)
							(end -0.3302 0.4318)
						)
						(arc
							(start 0.3302 0.4318)
							(mid 0.402042 0.402042)
							(end 0.4318 0.3302)
						)
						(arc
							(start 0.4318 -0.3302)
							(mid 0.402042 -0.402042)
							(end 0.3302 -0.4318)
						)
					)
					(width 0)
					(fill yes)
				)
			)
		)
		(pad "2" smd custom
			(at 0 0.762 270)
			(size 0.2159 0.2159)
			(layers "F.Cu" "F.Mask" "F.Paste")
			(net "5V_PRE_2")
			(options
				(clearance outline)
				(anchor circle)
			)
			(primitives
				(gr_poly
					(pts
						(arc
							(start -0.3302 -0.4318)
							(mid -0.402042 -0.402042)
							(end -0.4318 -0.3302)
						)
						(arc
							(start -0.4318 0.3302)
							(mid -0.402042 0.402042)
							(end -0.3302 0.4318)
						)
						(arc
							(start 0.3302 0.4318)
							(mid 0.402042 0.402042)
							(end 0.4318 0.3302)
						)
						(arc
							(start 0.4318 -0.3302)
							(mid 0.402042 -0.402042)
							(end 0.3302 -0.4318)
						)
					)
					(width 0)
					(fill yes)
				)
			)
		)
	)
	(footprint ""
		(layer "F.Cu")
		(at 3.999992 -4.020058)
		(property "Reference" "H1"
			(at 0 0 0)
			(layer "F.SilkS")
			(hide yes)
			(effects
				(font
					(size 1.27 1.27)
				)
			)
		)
		(property "Value" "HOLET217B237R166-GP"
			(at -5.08 -0.4572 0)
			(unlocked yes)
			(layer "F.Fab")
			(hide yes)
			(effects
				(font
					(size 1.016 1.016)
					(thickness 0.1524)
				)
			)
		)
		(property "Device Type" "HOLET217B237R166"
			(at -5.08 -1.9812 0)
			(unlocked yes)
			(layer "F.Fab")
			(hide yes)
			(effects
				(font
					(size 1.016 1.016)
					(thickness 0.1524)
				)
			)
		)
		(duplicate_pad_numbers_are_jumpers no)
		(fp_poly
			(pts
				(arc
					(start 3.3147 0)
					(mid -3.3147 0)
					(end 3.3147 0)
				)
			)
			(stroke
				(width 0)
				(type default)
			)
			(fill no)
			(layer "B.CrtYd")
		)
		(fp_poly
			(pts
				(arc
					(start 3.0607 0)
					(mid -3.0607 0)
					(end 3.0607 0)
				)
			)
			(stroke
				(width 0)
				(type default)
			)
			(fill no)
			(layer "F.CrtYd")
		)
		(fp_poly
			(pts
				(arc
					(start 3.3147 0)
					(mid -3.3147 0)
					(end 3.3147 0)
				)
			)
			(stroke
				(width 0)
				(type default)
			)
			(fill no)
			(layer "B.Fab")
		)
		(fp_poly
			(pts
				(arc
					(start 3.0607 0)
					(mid -3.0607 0)
					(end 3.0607 0)
				)
			)
			(stroke
				(width 0)
				(type default)
			)
			(fill no)
			(layer "F.Fab")
		)
		(pad "1" thru_hole circle
			(at 0 0)
			(size 5.5118 5.5118)
			(drill 4.2164)
			(layers "*.Cu" "*.Mask")
			(remove_unused_layers no)
			(net "GND")
			(clearance -0.1397)
			(thermal_gap 0.3048)
			(padstack
				(mode front_inner_back)
				(layer "Inner"
					(shape circle)
					(size 4.6228 4.6228)
					(clearance 0.3048)
				)
				(layer "B.Cu"
					(shape circle)
					(size 6.0198 6.0198)
					(clearance -0.3937)
				)
			)
		)
	)
	(footprint ""
		(layer "F.Cu")
		(at 60.694824 -10.667746 90)
		(property "Reference" "C23"
			(at 0 0 90)
			(layer "F.SilkS")
			(hide yes)
			(effects
				(font
					(size 1.27 1.27)
				)
			)
		)
		(property "Value" "SC10U25V6KX-1GP"
			(at -0.0762 -5.1308 90)
			(unlocked yes)
			(layer "F.Fab")
			(hide yes)
			(effects
				(font
					(size 1.016 1.016)
					(thickness 0.1524)
				)
			)
		)
		(property "Device Type" "C1206H71"
			(at -0.127 -6.6548 90)
			(unlocked yes)
			(layer "F.Fab")
			(hide yes)
			(effects
				(font
					(size 1.016 1.016)
					(thickness 0.1524)
				)
			)
		)
		(duplicate_pad_numbers_are_jumpers no)
		(fp_line
			(start 1.016 -2.2352)
			(end 1.016 -0.8382)
			(stroke
				(width 0.1524)
				(type default)
			)
			(layer "F.SilkS")
		)
		(fp_line
			(start -1.016 -2.2352)
			(end 1.016 -2.2352)
			(stroke
				(width 0.1524)
				(type default)
			)
			(layer "F.SilkS")
		)
		(fp_line
			(start -1.016 -0.8382)
			(end -1.016 -2.2352)
			(stroke
				(width 0.1524)
				(type default)
			)
			(layer "F.SilkS")
		)
		(fp_line
			(start 1.016 0.8382)
			(end 1.016 2.2352)
			(stroke
				(width 0.1524)
				(type default)
			)
			(layer "F.SilkS")
		)
		(fp_line
			(start 1.016 2.2352)
			(end -1.016 2.2352)
			(stroke
				(width 0.1524)
				(type default)
			)
			(layer "F.SilkS")
		)
		(fp_line
			(start -1.016 2.2352)
			(end -1.016 0.8382)
			(stroke
				(width 0.1524)
				(type default)
			)
			(layer "F.SilkS")
		)
		(fp_rect
			(start -1.0922 2.3114)
			(end 1.0922 -2.3114)
			(stroke
				(width 0)
				(type default)
			)
			(fill no)
			(layer "F.CrtYd")
		)
		(fp_poly
			(pts
				(xy 1.0922 -2.3114) (xy 1.0922 2.3114) (xy -1.0922 2.3114) (xy -1.0922 -2.3114)
			)
			(stroke
				(width 0)
				(type default)
			)
			(fill no)
			(layer "F.Fab")
		)
		(pad "1" smd rect
			(at 0 -1.397 90)
			(size 1.651 1.27)
			(layers "F.Cu" "F.Mask" "F.Paste")
			(net "P12V_SW_L")
		)
		(pad "2" smd rect
			(at 0 1.397 90)
			(size 1.651 1.27)
			(layers "F.Cu" "F.Mask" "F.Paste")
			(net "GND")
		)
	)
	(footprint ""
		(layer "F.Cu")
		(at 77.724 -50.927 -90)
		(property "Reference" "C5"
			(at 0 0 270)
			(layer "F.SilkS")
			(hide yes)
			(effects
				(font
					(size 1.27 1.27)
				)
			)
		)
		(property "Value" "SC10U10V5KX-L1-GP"
			(at -0.0762 -6.1214 270)
			(unlocked yes)
			(layer "F.Fab")
			(hide yes)
			(effects
				(font
					(size 1.016 1.016)
					(thickness 0.1524)
				)
			)
		)
		(property "Device Type" "C805H58"
			(at -0.0762 -8.1534 270)
			(unlocked yes)
			(layer "F.Fab")
			(hide yes)
			(effects
				(font
					(size 1.016 1.016)
					(thickness 0.1524)
				)
			)
		)
		(duplicate_pad_numbers_are_jumpers no)
		(fp_line
			(start 0.635 0)
			(end -0.635 0)
			(stroke
				(width 0.508)
				(type default)
			)
			(layer "F.SilkS")
		)
		(fp_rect
			(start -0.9652 1.778)
			(end 0.9652 -1.778)
			(stroke
				(width 0)
				(type default)
			)
			(fill no)
			(layer "F.CrtYd")
		)
		(fp_poly
			(pts
				(xy -0.9652 -1.778) (xy 0.9652 -1.778) (xy 0.9652 1.778) (xy -0.9652 1.778)
			)
			(stroke
				(width 0)
				(type default)
			)
			(fill no)
			(layer "F.Fab")
		)
		(pad "1" smd rect
			(at 0 -0.9652 270)
			(size 1.397 1.143)
			(layers "F.Cu" "F.Mask" "F.Paste")
			(net "P5V_SW_R")
		)
		(pad "2" smd rect
			(at 0 0.9652 270)
			(size 1.397 1.143)
			(layers "F.Cu" "F.Mask" "F.Paste")
			(net "GND")
		)
	)
	(footprint ""
		(layer "F.Cu")
		(at 59.46902 -21.733256 90)
		(property "Reference" "C20"
			(at 0 0 90)
			(layer "F.SilkS")
			(hide yes)
			(effects
				(font
					(size 1.27 1.27)
				)
			)
		)
		(property "Value" "SC10U25V6KX-1GP"
			(at -0.0762 -5.1308 90)
			(unlocked yes)
			(layer "F.Fab")
			(hide yes)
			(effects
				(font
					(size 1.016 1.016)
					(thickness 0.1524)
				)
			)
		)
		(property "Device Type" "C1206H71"
			(at -0.127 -6.6548 90)
			(unlocked yes)
			(layer "F.Fab")
			(hide yes)
			(effects
				(font
					(size 1.016 1.016)
					(thickness 0.1524)
				)
			)
		)
		(duplicate_pad_numbers_are_jumpers no)
		(fp_line
			(start 1.016 -2.2352)
			(end 1.016 -0.8382)
			(stroke
				(width 0.1524)
				(type default)
			)
			(layer "F.SilkS")
		)
		(fp_line
			(start -1.016 -2.2352)
			(end 1.016 -2.2352)
			(stroke
				(width 0.1524)
				(type default)
			)
			(layer "F.SilkS")
		)
		(fp_line
			(start -1.016 -0.8382)
			(end -1.016 -2.2352)
			(stroke
				(width 0.1524)
				(type default)
			)
			(layer "F.SilkS")
		)
		(fp_line
			(start 1.016 0.8382)
			(end 1.016 2.2352)
			(stroke
				(width 0.1524)
				(type default)
			)
			(layer "F.SilkS")
		)
		(fp_line
			(start 1.016 2.2352)
			(end -1.016 2.2352)
			(stroke
				(width 0.1524)
				(type default)
			)
			(layer "F.SilkS")
		)
		(fp_line
			(start -1.016 2.2352)
			(end -1.016 0.8382)
			(stroke
				(width 0.1524)
				(type default)
			)
			(layer "F.SilkS")
		)
		(fp_rect
			(start -1.0922 2.3114)
			(end 1.0922 -2.3114)
			(stroke
				(width 0)
				(type default)
			)
			(fill no)
			(layer "F.CrtYd")
		)
		(fp_poly
			(pts
				(xy 1.0922 -2.3114) (xy 1.0922 2.3114) (xy -1.0922 2.3114) (xy -1.0922 -2.3114)
			)
			(stroke
				(width 0)
				(type default)
			)
			(fill no)
			(layer "F.Fab")
		)
		(pad "1" smd rect
			(at 0 -1.397 90)
			(size 1.651 1.27)
			(layers "F.Cu" "F.Mask" "F.Paste")
			(net "P12V_SW_L")
		)
		(pad "2" smd rect
			(at 0 1.397 90)
			(size 1.651 1.27)
			(layers "F.Cu" "F.Mask" "F.Paste")
			(net "GND")
		)
	)
	(footprint ""
		(layer "F.Cu")
		(at 121.8946 -57.277 180)
		(property "Reference" "C3"
			(at 0 0 180)
			(layer "F.SilkS")
			(hide yes)
			(effects
				(font
					(size 1.27 1.27)
				)
			)
		)
		(property "Value" "SCD01U50V2KX-1GP"
			(at 1.1811 -2.7051 180)
			(unlocked yes)
			(layer "F.Fab")
			(hide yes)
			(effects
				(font
					(size 1.016 1.016)
					(thickness 0.1524)
				)
			)
		)
		(property "Device Type" "C402H22"
			(at 1.1811 -4.2291 180)
			(unlocked yes)
			(layer "F.Fab")
			(hide yes)
			(effects
				(font
					(size 1.016 1.016)
					(thickness 0.1524)
				)
			)
		)
		(duplicate_pad_numbers_are_jumpers no)
		(fp_rect
			(start -0.4318 0.9525)
			(end 0.4318 -0.9525)
			(stroke
				(width 0)
				(type default)
			)
			(fill no)
			(layer "F.CrtYd")
		)
		(fp_rect
			(start -0.4318 0.9525)
			(end 0.4318 -0.9525)
			(stroke
				(width 0)
				(type default)
			)
			(fill no)
			(layer "F.Fab")
		)
		(pad "1" smd custom
			(at 0 -0.4445 180)
			(size 0.1524 0.1524)
			(layers "F.Cu" "F.Mask" "F.Paste")
			(net "HBA_PRSNT0_N")
			(options
				(clearance outline)
				(anchor circle)
			)
			(primitives
				(gr_poly
					(pts
						(arc
							(start 0.3048 -0.2032)
							(mid 0.275042 -0.275042)
							(end 0.2032 -0.3048)
						)
						(arc
							(start -0.2032 -0.3048)
							(mid -0.275042 -0.275042)
							(end -0.3048 -0.2032)
						)
						(arc
							(start -0.3048 0.2032)
							(mid -0.275042 0.275042)
							(end -0.2032 0.3048)
						)
						(arc
							(start 0.2032 0.3048)
							(mid 0.275042 0.275042)
							(end 0.3048 0.2032)
						)
					)
					(width 0)
					(fill yes)
				)
			)
		)
		(pad "2" smd custom
			(at 0 0.4445 180)
			(size 0.1524 0.1524)
			(layers "F.Cu" "F.Mask" "F.Paste")
			(net "GND")
			(options
				(clearance outline)
				(anchor circle)
			)
			(primitives
				(gr_poly
					(pts
						(arc
							(start 0.3048 -0.2032)
							(mid 0.275042 -0.275042)
							(end 0.2032 -0.3048)
						)
						(arc
							(start -0.2032 -0.3048)
							(mid -0.275042 -0.275042)
							(end -0.3048 -0.2032)
						)
						(arc
							(start -0.3048 0.2032)
							(mid -0.275042 0.275042)
							(end -0.2032 0.3048)
						)
						(arc
							(start 0.2032 0.3048)
							(mid 0.275042 0.275042)
							(end 0.3048 0.2032)
						)
					)
					(width 0)
					(fill yes)
				)
			)
		)
	)
	(footprint ""
		(layer "F.Cu")
		(at 89.027 -7.493 90)
		(property "Reference" "R146"
			(at 0 0 90)
			(layer "F.SilkS")
			(hide yes)
			(effects
				(font
					(size 1.27 1.27)
				)
			)
		)
		(property "Value" "4K7R2J-2-GP"
			(at 0.064008 -3.993896 90)
			(unlocked yes)
			(layer "F.Fab")
			(hide yes)
			(effects
				(font
					(size 1.016 1.016)
					(thickness 0.1524)
				)
			)
		)
		(property "Device Type" "R402H16"
			(at 0.064008 -5.517896 90)
			(unlocked yes)
			(layer "F.Fab")
			(hide yes)
			(effects
				(font
					(size 1.016 1.016)
					(thickness 0.1524)
				)
			)
		)
		(duplicate_pad_numbers_are_jumpers no)
		(fp_line
			(start 0.508 -0.9398)
			(end -0.508 -0.9398)
			(stroke
				(width 0.1524)
				(type default)
			)
			(layer "F.SilkS")
		)
		(fp_line
			(start -0.508 -0.9398)
			(end -0.508 0.9398)
			(stroke
				(width 0.1524)
				(type default)
			)
			(layer "F.SilkS")
		)
		(fp_rect
			(start -0.508 0.9398)
			(end 0.508 -0.9398)
			(stroke
				(width 0)
				(type default)
			)
			(fill no)
			(layer "F.CrtYd")
		)
		(fp_rect
			(start -0.508 0.9398)
			(end 0.508 -0.9398)
			(stroke
				(width 0)
				(type default)
			)
			(fill no)
			(layer "F.Fab")
		)
		(pad "1" smd custom
			(at 0 -0.4445 90)
			(size 0.1397 0.1397)
			(layers "F.Cu" "F.Mask" "F.Paste")
			(net "P12V")
			(options
				(clearance outline)
				(anchor circle)
			)
			(primitives
				(gr_poly
					(pts
						(arc
							(start -0.1778 -0.2794)
							(mid -0.249642 -0.249642)
							(end -0.2794 -0.1778)
						)
						(arc
							(start -0.2794 0.1778)
							(mid -0.249642 0.249642)
							(end -0.1778 0.2794)
						)
						(arc
							(start 0.1778 0.2794)
							(mid 0.249642 0.249642)
							(end 0.2794 0.1778)
						)
						(arc
							(start 0.2794 -0.1778)
							(mid 0.249642 -0.249642)
							(end 0.1778 -0.2794)
						)
					)
					(width 0)
					(fill yes)
				)
			)
		)
		(pad "2" smd custom
			(at 0 0.4445 90)
			(size 0.1397 0.1397)
			(layers "F.Cu" "F.Mask" "F.Paste")
			(net "SW_SW_L_0")
			(options
				(clearance outline)
				(anchor circle)
			)
			(primitives
				(gr_poly
					(pts
						(arc
							(start -0.1778 -0.2794)
							(mid -0.249642 -0.249642)
							(end -0.2794 -0.1778)
						)
						(arc
							(start -0.2794 0.1778)
							(mid -0.249642 0.249642)
							(end -0.1778 0.2794)
						)
						(arc
							(start 0.1778 0.2794)
							(mid 0.249642 0.249642)
							(end 0.2794 0.1778)
						)
						(arc
							(start 0.2794 -0.1778)
							(mid 0.249642 -0.249642)
							(end 0.1778 -0.2794)
						)
					)
					(width 0)
					(fill yes)
				)
			)
		)
	)
	(footprint ""
		(layer "F.Cu")
		(at 56.884824 -9.727946 -90)
		(property "Reference" "C24"
			(at 0 0 270)
			(layer "F.SilkS")
			(hide yes)
			(effects
				(font
					(size 1.27 1.27)
				)
			)
		)
		(property "Value" "SCD1U25V2KX-GP"
			(at 1.1811 -2.7051 270)
			(unlocked yes)
			(layer "F.Fab")
			(hide yes)
			(effects
				(font
					(size 1.016 1.016)
					(thickness 0.1524)
				)
			)
		)
		(property "Device Type" "C402H22"
			(at 1.1811 -4.2291 270)
			(unlocked yes)
			(layer "F.Fab")
			(hide yes)
			(effects
				(font
					(size 1.016 1.016)
					(thickness 0.1524)
				)
			)
		)
		(duplicate_pad_numbers_are_jumpers no)
		(fp_rect
			(start -0.4318 0.9525)
			(end 0.4318 -0.9525)
			(stroke
				(width 0)
				(type default)
			)
			(fill no)
			(layer "F.CrtYd")
		)
		(fp_rect
			(start -0.4318 0.9525)
			(end 0.4318 -0.9525)
			(stroke
				(width 0)
				(type default)
			)
			(fill no)
			(layer "F.Fab")
		)
		(pad "1" smd custom
			(at 0 -0.4445 270)
			(size 0.1524 0.1524)
			(layers "F.Cu" "F.Mask" "F.Paste")
			(net "P12V_SW_L")
			(options
				(clearance outline)
				(anchor circle)
			)
			(primitives
				(gr_poly
					(pts
						(arc
							(start 0.3048 -0.2032)
							(mid 0.275042 -0.275042)
							(end 0.2032 -0.3048)
						)
						(arc
							(start -0.2032 -0.3048)
							(mid -0.275042 -0.275042)
							(end -0.3048 -0.2032)
						)
						(arc
							(start -0.3048 0.2032)
							(mid -0.275042 0.275042)
							(end -0.2032 0.3048)
						)
						(arc
							(start 0.2032 0.3048)
							(mid 0.275042 0.275042)
							(end 0.3048 0.2032)
						)
					)
					(width 0)
					(fill yes)
				)
			)
		)
		(pad "2" smd custom
			(at 0 0.4445 270)
			(size 0.1524 0.1524)
			(layers "F.Cu" "F.Mask" "F.Paste")
			(net "GND")
			(options
				(clearance outline)
				(anchor circle)
			)
			(primitives
				(gr_poly
					(pts
						(arc
							(start 0.3048 -0.2032)
							(mid 0.275042 -0.275042)
							(end 0.2032 -0.3048)
						)
						(arc
							(start -0.2032 -0.3048)
							(mid -0.275042 -0.275042)
							(end -0.3048 -0.2032)
						)
						(arc
							(start -0.3048 0.2032)
							(mid -0.275042 0.275042)
							(end -0.2032 0.3048)
						)
						(arc
							(start 0.2032 0.3048)
							(mid 0.275042 0.275042)
							(end 0.3048 0.2032)
						)
					)
					(width 0)
					(fill yes)
				)
			)
		)
	)
	(footprint ""
		(layer "F.Cu")
		(at 80.01 -8.128 90)
		(property "Reference" "R154"
			(at 0 0 90)
			(layer "F.SilkS")
			(hide yes)
			(effects
				(font
					(size 1.27 1.27)
				)
			)
		)
		(property "Value" "10KR2J-3-GP"
			(at 0.064008 -3.993896 90)
			(unlocked yes)
			(layer "F.Fab")
			(hide yes)
			(effects
				(font
					(size 1.016 1.016)
					(thickness 0.1524)
				)
			)
		)
		(property "Device Type" "R402H16"
			(at 0.064008 -5.517896 90)
			(unlocked yes)
			(layer "F.Fab")
			(hide yes)
			(effects
				(font
					(size 1.016 1.016)
					(thickness 0.1524)
				)
			)
		)
		(duplicate_pad_numbers_are_jumpers no)
		(fp_line
			(start 0.508 -0.9398)
			(end -0.508 -0.9398)
			(stroke
				(width 0.1524)
				(type default)
			)
			(layer "F.SilkS")
		)
		(fp_line
			(start -0.508 -0.9398)
			(end -0.508 0.9398)
			(stroke
				(width 0.1524)
				(type default)
			)
			(layer "F.SilkS")
		)
		(fp_rect
			(start -0.508 0.9398)
			(end 0.508 -0.9398)
			(stroke
				(width 0)
				(type default)
			)
			(fill no)
			(layer "F.CrtYd")
		)
		(fp_rect
			(start -0.508 0.9398)
			(end 0.508 -0.9398)
			(stroke
				(width 0)
				(type default)
			)
			(fill no)
			(layer "F.Fab")
		)
		(pad "1" smd custom
			(at 0 -0.4445 90)
			(size 0.1397 0.1397)
			(layers "F.Cu" "F.Mask" "F.Paste")
			(net "VIN_P3")
			(options
				(clearance outline)
				(anchor circle)
			)
			(primitives
				(gr_poly
					(pts
						(arc
							(start -0.1778 -0.2794)
							(mid -0.249642 -0.249642)
							(end -0.2794 -0.1778)
						)
						(arc
							(start -0.2794 0.1778)
							(mid -0.249642 0.249642)
							(end -0.1778 0.2794)
						)
						(arc
							(start 0.1778 0.2794)
							(mid 0.249642 0.249642)
							(end 0.2794 0.1778)
						)
						(arc
							(start 0.2794 -0.1778)
							(mid 0.249642 -0.249642)
							(end 0.1778 -0.2794)
						)
					)
					(width 0)
					(fill yes)
				)
			)
		)
		(pad "2" smd custom
			(at 0 0.4445 90)
			(size 0.1397 0.1397)
			(layers "F.Cu" "F.Mask" "F.Paste")
			(net "GND")
			(options
				(clearance outline)
				(anchor circle)
			)
			(primitives
				(gr_poly
					(pts
						(arc
							(start -0.1778 -0.2794)
							(mid -0.249642 -0.249642)
							(end -0.2794 -0.1778)
						)
						(arc
							(start -0.2794 0.1778)
							(mid -0.249642 0.249642)
							(end -0.1778 0.2794)
						)
						(arc
							(start 0.1778 0.2794)
							(mid 0.249642 0.249642)
							(end 0.2794 0.1778)
						)
						(arc
							(start 0.2794 -0.1778)
							(mid 0.249642 -0.249642)
							(end 0.1778 -0.2794)
						)
					)
					(width 0)
					(fill yes)
				)
			)
		)
	)
	(footprint ""
		(layer "F.Cu")
		(at 33.219898 -15.120112 180)
		(property "Reference" "SATA3"
			(at 0 0 180)
			(layer "F.SilkS")
			(hide yes)
			(effects
				(font
					(size 1.27 1.27)
				)
			)
		)
		(property "Value" "FCI-CONN29-2R-GP-U"
			(at -35.2552 -14.1859 180)
			(unlocked yes)
			(layer "F.Fab")
			(hide yes)
			(effects
				(font
					(size 1.016 1.016)
					(thickness 0.1524)
				)
			)
		)
		(property "Device Type" "PREFIT-29P-458055-UH395"
			(at -35.2552 -15.7099 180)
			(unlocked yes)
			(layer "F.Fab")
			(hide yes)
			(effects
				(font
					(size 1.016 1.016)
					(thickness 0.1524)
				)
			)
		)
		(duplicate_pad_numbers_are_jumpers no)
		(fp_line
			(start 18.0467 3.0099)
			(end -28.2067 3.0099)
			(stroke
				(width 0.1524)
				(type default)
			)
			(layer "F.SilkS")
		)
		(fp_line
			(start 18.0467 -3.0099)
			(end 18.0467 3.0099)
			(stroke
				(width 0.1524)
				(type default)
			)
			(layer "F.SilkS")
		)
		(fp_line
			(start -28.2067 3.0099)
			(end -28.2067 -3.0099)
			(stroke
				(width 0.1524)
				(type default)
			)
			(layer "F.SilkS")
		)
		(fp_line
			(start -28.2067 -3.0099)
			(end 18.0467 -3.0099)
			(stroke
				(width 0.1524)
				(type default)
			)
			(layer "F.SilkS")
		)
		(fp_poly
			(pts
				(xy -28.2067 3.0099) (xy -28.2067 -3.0099) (xy -21.9202 -3.0099) (xy -21.9202 -1.4478) (xy -28.1305 -1.4478)
				(xy -28.1305 1.4478) (xy -10.6934 1.4478) (xy -10.6934 -0.381) (xy -3.0607 -0.381) (xy -3.0607 2.4384)
				(xy 3.1115 2.4384) (xy 3.1115 1.4478) (xy 17.9705 1.4478) (xy 17.9705 -1.4351) (xy 11.7602 -1.4351)
				(xy 11.7602 -2.2098) (xy -2.2606 -2.2098) (xy -2.2606 -3.0099) (xy 18.0467 -3.0099) (xy 18.0467 3.0099)
			)
			(stroke
				(width 0)
				(type default)
			)
			(fill yes)
			(layer "F.SilkS")
		)
		(fp_poly
			(pts
				(arc
					(start 2.2098 1.25095)
					(mid 2.0828 1.12395)
					(end 2.2098 0.99695)
				)
				(arc
					(start 2.5908 0.99695)
					(mid 2.7178 1.12395)
					(end 2.5908 1.25095)
				)
			)
			(stroke
				(width 0)
				(type default)
			)
			(fill yes)
			(layer "F.SilkS")
		)
		(fp_poly
			(pts
				(arc
					(start 1.4097 1.25095)
					(mid 1.2827 1.12395)
					(end 1.4097 0.99695)
				)
				(arc
					(start 1.7907 0.99695)
					(mid 1.9177 1.12395)
					(end 1.7907 1.25095)
				)
			)
			(stroke
				(width 0)
				(type default)
			)
			(fill yes)
			(layer "F.SilkS")
		)
		(fp_poly
			(pts
				(arc
					(start 0.6096 1.25095)
					(mid 0.4826 1.12395)
					(end 0.6096 0.99695)
				)
				(arc
					(start 0.9906 0.99695)
					(mid 1.1176 1.12395)
					(end 0.9906 1.25095)
				)
			)
			(stroke
				(width 0)
				(type default)
			)
			(fill yes)
			(layer "F.SilkS")
		)
		(fp_poly
			(pts
				(arc
					(start -0.1905 1.25095)
					(mid -0.3175 1.12395)
					(end -0.1905 0.99695)
				)
				(arc
					(start 0.1905 0.99695)
					(mid 0.3175 1.12395)
					(end 0.1905 1.25095)
				)
			)
			(stroke
				(width 0)
				(type default)
			)
			(fill yes)
			(layer "F.SilkS")
		)
		(fp_poly
			(pts
				(arc
					(start -0.9906 1.25095)
					(mid -1.1176 1.12395)
					(end -0.9906 0.99695)
				)
				(arc
					(start -0.6096 0.99695)
					(mid -0.4826 1.12395)
					(end -0.6096 1.25095)
				)
			)
			(stroke
				(width 0)
				(type default)
			)
			(fill yes)
			(layer "F.SilkS")
		)
		(fp_poly
			(pts
				(arc
					(start -1.7907 1.25095)
					(mid -1.9177 1.12395)
					(end -1.7907 0.99695)
				)
				(arc
					(start -1.4097 0.99695)
					(mid -1.2827 1.12395)
					(end -1.4097 1.25095)
				)
			)
			(stroke
				(width 0)
				(type default)
			)
			(fill yes)
			(layer "F.SilkS")
		)
		(fp_poly
			(pts
				(arc
					(start -2.5908 1.25095)
					(mid -2.7178 1.12395)
					(end -2.5908 0.99695)
				)
				(arc
					(start -2.2098 0.99695)
					(mid -2.0828 1.12395)
					(end -2.2098 1.25095)
				)
			)
			(stroke
				(width 0)
				(type default)
			)
			(fill yes)
			(layer "F.SilkS")
		)
		(fp_poly
			(pts
				(arc
					(start 10.4902 0.2032)
					(mid 10.287 0)
					(end 10.4902 -0.2032)
				)
				(arc
					(start 11.0998 -0.2032)
					(mid 11.303 0)
					(end 11.0998 0.2032)
				)
			)
			(stroke
				(width 0)
				(type default)
			)
			(fill yes)
			(layer "F.SilkS")
		)
		(fp_poly
			(pts
				(arc
					(start 9.2202 0.2032)
					(mid 9.017 0)
					(end 9.2202 -0.2032)
				)
				(arc
					(start 9.8298 -0.2032)
					(mid 10.033 0)
					(end 9.8298 0.2032)
				)
			)
			(stroke
				(width 0)
				(type default)
			)
			(fill yes)
			(layer "F.SilkS")
		)
		(fp_poly
			(pts
				(arc
					(start 7.9502 0.2032)
					(mid 7.747 0)
					(end 7.9502 -0.2032)
				)
				(arc
					(start 8.5598 -0.2032)
					(mid 8.763 0)
					(end 8.5598 0.2032)
				)
			)
			(stroke
				(width 0)
				(type default)
			)
			(fill yes)
			(layer "F.SilkS")
		)
		(fp_poly
			(pts
				(arc
					(start 6.6802 0.2032)
					(mid 6.477 0)
					(end 6.6802 -0.2032)
				)
				(arc
					(start 7.2898 -0.2032)
					(mid 7.493 0)
					(end 7.2898 0.2032)
				)
			)
			(stroke
				(width 0)
				(type default)
			)
			(fill yes)
			(layer "F.SilkS")
		)
		(fp_poly
			(pts
				(arc
					(start 5.4102 0.2032)
					(mid 5.207 0)
					(end 5.4102 -0.2032)
				)
				(arc
					(start 6.0198 -0.2032)
					(mid 6.223 0)
					(end 6.0198 0.2032)
				)
			)
			(stroke
				(width 0)
				(type default)
			)
			(fill yes)
			(layer "F.SilkS")
		)
		(fp_poly
			(pts
				(arc
					(start 4.1402 0.2032)
					(mid 3.937 0)
					(end 4.1402 -0.2032)
				)
				(arc
					(start 4.7498 -0.2032)
					(mid 4.953 0)
					(end 4.7498 0.2032)
				)
			)
			(stroke
				(width 0)
				(type default)
			)
			(fill yes)
			(layer "F.SilkS")
		)
		(fp_poly
			(pts
				(arc
					(start 2.8702 0.2032)
					(mid 2.667 0)
					(end 2.8702 -0.2032)
				)
				(arc
					(start 3.4798 -0.2032)
					(mid 3.683 0)
					(end 3.4798 0.2032)
				)
			)
			(stroke
				(width 0)
				(type default)
			)
			(fill yes)
			(layer "F.SilkS")
		)
		(fp_poly
			(pts
				(arc
					(start -3.4798 -2.4638)
					(mid -3.683 -2.667)
					(end -3.4798 -2.8702)
				)
				(arc
					(start -2.8702 -2.8702)
					(mid -2.667 -2.667)
					(end -2.8702 -2.4638)
				)
			)
			(stroke
				(width 0)
				(type default)
			)
			(fill yes)
			(layer "F.SilkS")
		)
		(fp_poly
			(pts
				(arc
					(start -4.7498 -2.4638)
					(mid -4.953 -2.667)
					(end -4.7498 -2.8702)
				)
				(arc
					(start -4.1402 -2.8702)
					(mid -3.937 -2.667)
					(end -4.1402 -2.4638)
				)
			)
			(stroke
				(width 0)
				(type default)
			)
			(fill yes)
			(layer "F.SilkS")
		)
		(fp_poly
			(pts
				(arc
					(start -6.0198 -2.4638)
					(mid -6.223 -2.667)
					(end -6.0198 -2.8702)
				)
				(arc
					(start -5.4102 -2.8702)
					(mid -5.207 -2.667)
					(end -5.4102 -2.4638)
				)
			)
			(stroke
				(width 0)
				(type default)
			)
			(fill yes)
			(layer "F.SilkS")
		)
		(fp_poly
			(pts
				(arc
					(start -7.2898 -2.4638)
					(mid -7.493 -2.667)
					(end -7.2898 -2.8702)
				)
				(arc
					(start -6.6802 -2.8702)
					(mid -6.477 -2.667)
					(end -6.6802 -2.4638)
				)
			)
			(stroke
				(width 0)
				(type default)
			)
			(fill yes)
			(layer "F.SilkS")
		)
		(fp_poly
			(pts
				(arc
					(start -8.5598 -2.4638)
					(mid -8.763 -2.667)
					(end -8.5598 -2.8702)
				)
				(arc
					(start -7.9502 -2.8702)
					(mid -7.747 -2.667)
					(end -7.9502 -2.4638)
				)
			)
			(stroke
				(width 0)
				(type default)
			)
			(fill yes)
			(layer "F.SilkS")
		)
		(fp_poly
			(pts
				(arc
					(start -9.8298 -2.4638)
					(mid -10.033 -2.667)
					(end -9.8298 -2.8702)
				)
				(arc
					(start -9.2202 -2.8702)
					(mid -9.017 -2.667)
					(end -9.2202 -2.4638)
				)
			)
			(stroke
				(width 0)
				(type default)
			)
			(fill yes)
			(layer "F.SilkS")
		)
		(fp_poly
			(pts
				(arc
					(start -11.0998 -2.4638)
					(mid -11.303 -2.667)
					(end -11.0998 -2.8702)
				)
				(arc
					(start -10.4902 -2.8702)
					(mid -10.287 -2.667)
					(end -10.4902 -2.4638)
				)
			)
			(stroke
				(width 0)
				(type default)
			)
			(fill yes)
			(layer "F.SilkS")
		)
		(fp_poly
			(pts
				(arc
					(start -12.3698 -2.4638)
					(mid -12.573 -2.667)
					(end -12.3698 -2.8702)
				)
				(arc
					(start -11.7602 -2.8702)
					(mid -11.557 -2.667)
					(end -11.7602 -2.4638)
				)
			)
			(stroke
				(width 0)
				(type default)
			)
			(fill yes)
			(layer "F.SilkS")
		)
		(fp_poly
			(pts
				(arc
					(start -13.6398 -2.4638)
					(mid -13.843 -2.667)
					(end -13.6398 -2.8702)
				)
				(arc
					(start -13.0302 -2.8702)
					(mid -12.827 -2.667)
					(end -13.0302 -2.4638)
				)
			)
			(stroke
				(width 0)
				(type default)
			)
			(fill yes)
			(layer "F.SilkS")
		)
		(fp_poly
			(pts
				(arc
					(start -14.9098 -2.4638)
					(mid -15.113 -2.667)
					(end -14.9098 -2.8702)
				)
				(arc
					(start -14.3002 -2.8702)
					(mid -14.097 -2.667)
					(end -14.3002 -2.4638)
				)
			)
			(stroke
				(width 0)
				(type default)
			)
			(fill yes)
			(layer "F.SilkS")
		)
		(fp_poly
			(pts
				(arc
					(start -16.1798 -2.4638)
					(mid -16.383 -2.667)
					(end -16.1798 -2.8702)
				)
				(arc
					(start -15.5702 -2.8702)
					(mid -15.367 -2.667)
					(end -15.5702 -2.4638)
				)
			)
			(stroke
				(width 0)
				(type default)
			)
			(fill yes)
			(layer "F.SilkS")
		)
		(fp_poly
			(pts
				(arc
					(start -17.4498 -2.4638)
					(mid -17.653 -2.667)
					(end -17.4498 -2.8702)
				)
				(arc
					(start -16.8402 -2.8702)
					(mid -16.637 -2.667)
					(end -16.8402 -2.4638)
				)
			)
			(stroke
				(width 0)
				(type default)
			)
			(fill yes)
			(layer "F.SilkS")
		)
		(fp_poly
			(pts
				(arc
					(start -18.7198 -2.4638)
					(mid -18.923 -2.667)
					(end -18.7198 -2.8702)
				)
				(arc
					(start -18.1102 -2.8702)
					(mid -17.907 -2.667)
					(end -18.1102 -2.4638)
				)
			)
			(stroke
				(width 0)
				(type default)
			)
			(fill yes)
			(layer "F.SilkS")
		)
		(fp_poly
			(pts
				(arc
					(start -19.9898 -2.4638)
					(mid -20.193 -2.667)
					(end -19.9898 -2.8702)
				)
				(arc
					(start -19.3802 -2.8702)
					(mid -19.177 -2.667)
					(end -19.3802 -2.4638)
				)
			)
			(stroke
				(width 0)
				(type default)
			)
			(fill yes)
			(layer "F.SilkS")
		)
		(fp_poly
			(pts
				(arc
					(start -21.2598 -2.4638)
					(mid -21.463 -2.667)
					(end -21.2598 -2.8702)
				)
				(arc
					(start -20.6502 -2.8702)
					(mid -20.447 -2.667)
					(end -20.6502 -2.4638)
				)
			)
			(stroke
				(width 0)
				(type default)
			)
			(fill yes)
			(layer "F.SilkS")
		)
		(fp_poly
			(pts
				(arc
					(start 17.87525 0.6096)
					(mid 17.57045 0.9144)
					(end 17.26565 0.6096)
				)
				(arc
					(start 17.26565 -0.6096)
					(mid 17.57045 -0.9144)
					(end 17.87525 -0.6096)
				)
			)
			(stroke
				(width 0)
				(type default)
			)
			(fill yes)
			(layer "F.SilkS")
		)
		(fp_poly
			(pts
				(arc
					(start -27.42565 0.6096)
					(mid -27.73045 0.9144)
					(end -28.03525 0.6096)
				)
				(arc
					(start -28.03525 -0.6096)
					(mid -27.73045 -0.9144)
					(end -27.42565 -0.6096)
				)
			)
			(stroke
				(width 0)
				(type default)
			)
			(fill yes)
			(layer "F.SilkS")
		)
		(fp_rect
			(start -32.2707 7.5438)
			(end 22.1107 -6.7056)
			(stroke
				(width 0)
				(type default)
			)
			(fill no)
			(layer "B.CrtYd")
		)
		(fp_rect
			(start -27.9527 2.7559)
			(end 17.7927 -2.7559)
			(stroke
				(width 0)
				(type default)
			)
			(fill no)
			(layer "F.CrtYd")
		)
		(fp_poly
			(pts
				(xy -28.4607 3.2639) (xy -28.4607 -3.2639) (xy 18.3007 -3.2639) (xy 18.3007 2.7051) (xy 17.7927 2.7051)
				(xy 17.7927 -2.7559) (xy -27.9527 -2.7559) (xy -27.9527 2.7559) (xy 17.7927 2.7559) (xy 17.7927 2.7178)
				(xy 18.3007 2.7178) (xy 18.3007 3.2639)
			)
			(stroke
				(width 0)
				(type default)
			)
			(fill no)
			(layer "F.CrtYd")
		)
		(fp_poly
			(pts
				(xy -32.9565 7.7597) (xy -32.9565 -7.7597) (xy 22.7965 -7.7597) (xy 22.7965 2.7051) (xy 18.3007 2.7051)
				(xy 18.3007 -3.2639) (xy -28.4607 -3.2639) (xy -28.4607 3.2639) (xy 18.3007 3.2639) (xy 18.3007 2.7178)
				(xy 22.7965 2.7178) (xy 22.7965 7.7597)
			)
			(stroke
				(width 0)
				(type default)
			)
			(fill no)
			(layer "F.CrtYd")
		)
		(fp_rect
			(start -32.2707 7.5438)
			(end 22.1107 -6.7056)
			(stroke
				(width 0)
				(type default)
			)
			(fill no)
			(layer "B.Fab")
		)
		(fp_rect
			(start -37.2745 12.5476)
			(end 27.1145 -11.7094)
			(stroke
				(width 0)
				(type default)
			)
			(fill no)
			(layer "B.Fab")
		)
		(fp_rect
			(start -28.4607 3.2639)
			(end 18.3007 -3.2639)
			(stroke
				(width 0)
				(type default)
			)
			(fill no)
			(layer "F.Fab")
		)
		(fp_rect
			(start -32.9565 7.7597)
			(end 22.7965 -7.7597)
			(stroke
				(width 0)
				(type default)
			)
			(fill no)
			(layer "F.Fab")
		)
		(fp_rect
			(start -37.9603 12.7635)
			(end 27.8003 -12.7635)
			(stroke
				(width 0)
				(type default)
			)
			(fill no)
			(layer "F.Fab")
		)
		(fp_text user "Press Fit"
			(at -21.3614 0.5715 180)
			(unlocked yes)
			(layer "F.SilkS")
			(effects
				(font
					(size 1.016 1.016)
					(thickness 0.1524)
				)
				(justify left)
			)
		)
		(fp_text user "Can not place BGA,CSP,Wave Solder Comonent."
			(at -28.9433 10.1219 180)
			(unlocked yes)
			(layer "B.Fab")
			(effects
				(font
					(size 1.016 1.016)
					(thickness 0.1524)
				)
				(justify left)
			)
		)
		(fp_text user "High Limit 2mm"
			(at -13.8811 6.6421 180)
			(unlocked yes)
			(layer "F.Fab")
			(effects
				(font
					(size 1.016 1.016)
					(thickness 0.1524)
				)
				(justify left)
			)
		)
		(fp_text user "Can not place BGA,CSP,Wave Solder Comonent."
			(at -28.9433 10.1219 180)
			(unlocked yes)
			(layer "F.Fab")
			(effects
				(font
					(size 1.016 1.016)
					(thickness 0.1524)
				)
				(justify left)
			)
		)
		(pad "" np_thru_hole circle
			(at -23.95474 0 180)
			(size 0.254 0.254)
			(drill 1.3462)
			(layers "*.Cu" "*.Mask")
			(clearance 0.9017)
			(thermal_gap 0.9017)
		)
		(pad "30" thru_hole circle
			(at -26.07945 0 180)
			(size 2.3622 2.3622)
			(drill 1.949958)
			(layers "*.Cu" "*.Mask")
			(remove_unused_layers no)
			(net "Net_63")
			(clearance 0.1524)
			(thermal_gap 0.1524)
		)
		(pad "31" thru_hole circle
			(at 15.91945 0 180)
			(size 2.3622 2.3622)
			(drill 1.949958)
			(layers "*.Cu" "*.Mask")
			(remove_unused_layers no)
			(net "Net_54")
			(clearance 0.1524)
			(thermal_gap 0.1524)
		)
		(pad "P1" thru_hole circle
			(at -3.175 -1.27 180)
			(size 0.8636 0.8636)
			(drill 0.499872)
			(layers "*.Cu" "*.Mask")
			(remove_unused_layers no)
			(net "Net_59")
			(clearance 0.1778)
			(thermal_gap 0.1778)
		)
		(pad "P2" thru_hole circle
			(at -4.445 -1.27 180)
			(size 0.8636 0.8636)
			(drill 0.499872)
			(layers "*.Cu" "*.Mask")
			(remove_unused_layers no)
			(net "Net_61")
			(clearance 0.1778)
			(thermal_gap 0.1778)
		)
		(pad "P3" thru_hole circle
			(at -5.715 -1.27 180)
			(size 0.8636 0.8636)
			(drill 0.499872)
			(layers "*.Cu" "*.Mask")
			(remove_unused_layers no)
			(net "Net_60")
			(clearance 0.1778)
			(thermal_gap 0.1778)
		)
		(pad "P4" thru_hole circle
			(at -6.985 -1.27 180)
			(size 0.8636 0.8636)
			(drill 0.499872)
			(layers "*.Cu" "*.Mask")
			(remove_unused_layers no)
			(net "GND")
			(clearance 0.1778)
			(thermal_gap 0.1778)
		)
		(pad "P5" thru_hole circle
			(at -8.255 -1.27 180)
			(size 0.8636 0.8636)
			(drill 0.499872)
			(layers "*.Cu" "*.Mask")
			(remove_unused_layers no)
			(net "GND")
			(clearance 0.1778)
			(thermal_gap 0.1778)
		)
		(pad "P6" thru_hole circle
			(at -9.525 -1.27 180)
			(size 0.8636 0.8636)
			(drill 0.499872)
			(layers "*.Cu" "*.Mask")
			(remove_unused_layers no)
			(net "GND")
			(clearance 0.1778)
			(thermal_gap 0.1778)
		)
		(pad "P7" thru_hole circle
			(at -10.795 -1.27 180)
			(size 0.8636 0.8636)
			(drill 0.499872)
			(layers "*.Cu" "*.Mask")
			(remove_unused_layers no)
			(net "5V_PRE_2")
			(clearance 0.1778)
			(thermal_gap 0.1778)
		)
		(pad "P8" thru_hole circle
			(at -12.065 -1.27 180)
			(size 0.8636 0.8636)
			(drill 0.499872)
			(layers "*.Cu" "*.Mask")
			(remove_unused_layers no)
			(net "P5V_SW_L")
			(clearance 0.1778)
			(thermal_gap 0.1778)
		)
		(pad "P9" thru_hole circle
			(at -13.335 -1.27 180)
			(size 0.8636 0.8636)
			(drill 0.499872)
			(layers "*.Cu" "*.Mask")
			(remove_unused_layers no)
			(net "P5V_SW_L")
			(clearance 0.1778)
			(thermal_gap 0.1778)
		)
		(pad "P10" thru_hole circle
			(at -14.605 -1.27 180)
			(size 0.8636 0.8636)
			(drill 0.499872)
			(layers "*.Cu" "*.Mask")
			(remove_unused_layers no)
			(net "HBA_PRSNT2_N")
			(clearance 0.1778)
			(thermal_gap 0.1778)
		)
		(pad "P11" thru_hole circle
			(at -15.875 -1.27 180)
			(size 0.8636 0.8636)
			(drill 0.499872)
			(layers "*.Cu" "*.Mask")
			(remove_unused_layers no)
			(net "HDD_ACT_LED2")
			(clearance 0.1778)
			(thermal_gap 0.1778)
		)
		(pad "P12" thru_hole circle
			(at -17.145 -1.27 180)
			(size 0.8636 0.8636)
			(drill 0.499872)
			(layers "*.Cu" "*.Mask")
			(remove_unused_layers no)
			(net "GND")
			(clearance 0.1778)
			(thermal_gap 0.1778)
		)
		(pad "P13" thru_hole circle
			(at -18.415 -1.27 180)
			(size 0.8636 0.8636)
			(drill 0.499872)
			(layers "*.Cu" "*.Mask")
			(remove_unused_layers no)
			(net "12V_PRE_2")
			(clearance 0.1778)
			(thermal_gap 0.1778)
		)
		(pad "P14" thru_hole circle
			(at -19.685 -1.27 180)
			(size 0.8636 0.8636)
			(drill 0.499872)
			(layers "*.Cu" "*.Mask")
			(remove_unused_layers no)
			(net "P12V_SW_L")
			(clearance 0.1778)
			(thermal_gap 0.1778)
		)
		(pad "P15" thru_hole circle
			(at -20.955 -1.27 180)
			(size 0.8636 0.8636)
			(drill 0.499872)
			(layers "*.Cu" "*.Mask")
			(remove_unused_layers no)
			(net "P12V_SW_L")
			(clearance 0.1778)
			(thermal_gap 0.1778)
		)
		(pad "S1" thru_hole circle
			(at 10.795 -1.27 180)
			(size 0.8636 0.8636)
			(drill 0.499872)
			(layers "*.Cu" "*.Mask")
			(remove_unused_layers no)
			(net "GND")
			(clearance 0.1778)
			(thermal_gap 0.1778)
		)
		(pad "S2" thru_hole circle
			(at 9.525 -1.27 180)
			(size 0.8636 0.8636)
			(drill 0.499872)
			(layers "*.Cu" "*.Mask")
			(remove_unused_layers no)
			(net "HBA_MB_TX_P2")
			(clearance 0.1778)
			(thermal_gap 0.1778)
		)
		(pad "S3" thru_hole circle
			(at 8.255 -1.27 180)
			(size 0.8636 0.8636)
			(drill 0.499872)
			(layers "*.Cu" "*.Mask")
			(remove_unused_layers no)
			(net "HBA_MB_TX_N2")
			(clearance 0.1778)
			(thermal_gap 0.1778)
		)
		(pad "S4" thru_hole circle
			(at 6.985 -1.27 180)
			(size 0.8636 0.8636)
			(drill 0.499872)
			(layers "*.Cu" "*.Mask")
			(remove_unused_layers no)
			(net "GND")
			(clearance 0.1778)
			(thermal_gap 0.1778)
		)
		(pad "S5" thru_hole circle
			(at 5.715 -1.27 180)
			(size 0.8636 0.8636)
			(drill 0.499872)
			(layers "*.Cu" "*.Mask")
			(remove_unused_layers no)
			(net "HBA_MB_RX_N2")
			(clearance 0.1778)
			(thermal_gap 0.1778)
		)
		(pad "S6" thru_hole circle
			(at 4.445 -1.27 180)
			(size 0.8636 0.8636)
			(drill 0.499872)
			(layers "*.Cu" "*.Mask")
			(remove_unused_layers no)
			(net "HBA_MB_RX_P2")
			(clearance 0.1778)
			(thermal_gap 0.1778)
		)
		(pad "S7" thru_hole circle
			(at 3.175 -1.27 180)
			(size 0.8636 0.8636)
			(drill 0.499872)
			(layers "*.Cu" "*.Mask")
			(remove_unused_layers no)
			(net "GND")
			(clearance 0.1778)
			(thermal_gap 0.1778)
		)
		(pad "S8" thru_hole oval
			(at 2.4003 2.13995 180)
			(size 0.6096 0.8128)
			(drill 0.399796)
			(layers "*.Cu" "*.Mask")
			(remove_unused_layers no)
			(net "GND")
			(clearance 0.254)
			(thermal_gap 0.254)
		)
		(pad "S9" thru_hole oval
			(at 1.6002 2.13995 180)
			(size 0.6096 0.8128)
			(drill 0.399796)
			(layers "*.Cu" "*.Mask")
			(remove_unused_layers no)
			(net "Net_58")
			(clearance 0.254)
			(thermal_gap 0.254)
		)
		(pad "S10" thru_hole oval
			(at 0.8001 2.13995 180)
			(size 0.6096 0.8128)
			(drill 0.399796)
			(layers "*.Cu" "*.Mask")
			(remove_unused_layers no)
			(net "Net_57")
			(clearance 0.254)
			(thermal_gap 0.254)
		)
		(pad "S11" thru_hole oval
			(at 0 2.13995 180)
			(size 0.6096 0.8128)
			(drill 0.399796)
			(layers "*.Cu" "*.Mask")
			(remove_unused_layers no)
			(net "Net_42")
			(clearance 0.254)
			(thermal_gap 0.254)
		)
		(pad "S12" thru_hole oval
			(at -0.8001 2.13995 180)
			(size 0.6096 0.8128)
			(drill 0.399796)
			(layers "*.Cu" "*.Mask")
			(remove_unused_layers no)
			(net "Net_56")
			(clearance 0.254)
			(thermal_gap 0.254)
		)
		(pad "S13" thru_hole oval
			(at -1.6002 2.13995 180)
			(size 0.6096 0.8128)
			(drill 0.399796)
			(layers "*.Cu" "*.Mask")
			(remove_unused_layers no)
			(net "Net_55")
			(clearance 0.254)
			(thermal_gap 0.254)
		)
		(pad "S14" thru_hole oval
			(at -2.4003 2.13995 180)
			(size 0.6096 0.8128)
			(drill 0.399796)
			(layers "*.Cu" "*.Mask")
			(remove_unused_layers no)
			(net "GND")
			(clearance 0.254)
			(thermal_gap 0.254)
		)
		(zone
			(layers "F.Cu" "B.Cu" "In1.Cu" "In2.Cu" "In3.Cu" "In4.Cu")
			(hatch none 0.5)
			(connect_pads
				(clearance 0)
			)
			(min_thickness 0.25)
			(keepout
				(tracks not_allowed)
				(vias allowed)
				(pads allowed)
				(copperpour not_allowed)
				(footprints allowed)
			)
			(placement
				(enabled no)
				(sheetname "")
			)
			(fill
				(thermal_gap 0.5)
				(thermal_bridge_width 0.5)
				(island_removal_mode 0)
			)
			(polygon
				(pts
					(arc
						(start 58.152538 -15.120112)
						(mid 56.196738 -15.120112)
						(end 58.152538 -15.120112)
					)
				)
			)
		)
	)
	(footprint ""
		(layer "F.Cu")
		(at 54.598824 -8.584946)
		(property "Reference" "R7"
			(at 0 0 0)
			(layer "F.SilkS")
			(hide yes)
			(effects
				(font
					(size 1.27 1.27)
				)
			)
		)
		(property "Value" "10KR2J-3-GP"
			(at 0.064008 -3.993896 0)
			(unlocked yes)
			(layer "F.Fab")
			(hide yes)
			(effects
				(font
					(size 1.016 1.016)
					(thickness 0.1524)
				)
			)
		)
		(property "Device Type" "R402H16"
			(at 0.064008 -5.517896 0)
			(unlocked yes)
			(layer "F.Fab")
			(hide yes)
			(effects
				(font
					(size 1.016 1.016)
					(thickness 0.1524)
				)
			)
		)
		(duplicate_pad_numbers_are_jumpers no)
		(fp_line
			(start -0.508 -0.9398)
			(end -0.508 0.9398)
			(stroke
				(width 0.1524)
				(type default)
			)
			(layer "F.SilkS")
		)
		(fp_line
			(start 0.508 -0.9398)
			(end -0.508 -0.9398)
			(stroke
				(width 0.1524)
				(type default)
			)
			(layer "F.SilkS")
		)
		(fp_rect
			(start -0.508 0.9398)
			(end 0.508 -0.9398)
			(stroke
				(width 0)
				(type default)
			)
			(fill no)
			(layer "F.CrtYd")
		)
		(fp_rect
			(start -0.508 0.9398)
			(end 0.508 -0.9398)
			(stroke
				(width 0)
				(type default)
			)
			(fill no)
			(layer "F.Fab")
		)
		(pad "1" smd custom
			(at 0 -0.4445)
			(size 0.1397 0.1397)
			(layers "F.Cu" "F.Mask" "F.Paste")
			(net "P3V3")
			(options
				(clearance outline)
				(anchor circle)
			)
			(primitives
				(gr_poly
					(pts
						(arc
							(start -0.1778 -0.2794)
							(mid -0.249642 -0.249642)
							(end -0.2794 -0.1778)
						)
						(arc
							(start -0.2794 0.1778)
							(mid -0.249642 0.249642)
							(end -0.1778 0.2794)
						)
						(arc
							(start 0.1778 0.2794)
							(mid 0.249642 0.249642)
							(end 0.2794 0.1778)
						)
						(arc
							(start 0.2794 -0.1778)
							(mid 0.249642 -0.249642)
							(end 0.1778 -0.2794)
						)
					)
					(width 0)
					(fill yes)
				)
			)
		)
		(pad "2" smd custom
			(at 0 0.4445)
			(size 0.1397 0.1397)
			(layers "F.Cu" "F.Mask" "F.Paste")
			(net "HBA_PRSNT3_N")
			(options
				(clearance outline)
				(anchor circle)
			)
			(primitives
				(gr_poly
					(pts
						(arc
							(start -0.1778 -0.2794)
							(mid -0.249642 -0.249642)
							(end -0.2794 -0.1778)
						)
						(arc
							(start -0.2794 0.1778)
							(mid -0.249642 0.249642)
							(end -0.1778 0.2794)
						)
						(arc
							(start 0.1778 0.2794)
							(mid 0.249642 0.249642)
							(end 0.2794 0.1778)
						)
						(arc
							(start 0.2794 -0.1778)
							(mid 0.249642 -0.249642)
							(end 0.1778 -0.2794)
						)
					)
					(width 0)
					(fill yes)
				)
			)
		)
	)
	(footprint ""
		(layer "F.Cu")
		(at 11.811 -19.304 -90)
		(property "Reference" "C25"
			(at 0 0 270)
			(layer "F.SilkS")
			(hide yes)
			(effects
				(font
					(size 1.27 1.27)
				)
			)
		)
		(property "Value" "SCD1U25V2KX-GP"
			(at 1.1811 -2.7051 270)
			(unlocked yes)
			(layer "F.Fab")
			(hide yes)
			(effects
				(font
					(size 1.016 1.016)
					(thickness 0.1524)
				)
			)
		)
		(property "Device Type" "C402H22"
			(at 1.1811 -4.2291 270)
			(unlocked yes)
			(layer "F.Fab")
			(hide yes)
			(effects
				(font
					(size 1.016 1.016)
					(thickness 0.1524)
				)
			)
		)
		(duplicate_pad_numbers_are_jumpers no)
		(fp_rect
			(start -0.4318 0.9525)
			(end 0.4318 -0.9525)
			(stroke
				(width 0)
				(type default)
			)
			(fill no)
			(layer "F.CrtYd")
		)
		(fp_rect
			(start -0.4318 0.9525)
			(end 0.4318 -0.9525)
			(stroke
				(width 0)
				(type default)
			)
			(fill no)
			(layer "F.Fab")
		)
		(pad "1" smd custom
			(at 0 -0.4445 270)
			(size 0.1524 0.1524)
			(layers "F.Cu" "F.Mask" "F.Paste")
			(net "P5V")
			(options
				(clearance outline)
				(anchor circle)
			)
			(primitives
				(gr_poly
					(pts
						(arc
							(start 0.3048 -0.2032)
							(mid 0.275042 -0.275042)
							(end 0.2032 -0.3048)
						)
						(arc
							(start -0.2032 -0.3048)
							(mid -0.275042 -0.275042)
							(end -0.3048 -0.2032)
						)
						(arc
							(start -0.3048 0.2032)
							(mid -0.275042 0.275042)
							(end -0.2032 0.3048)
						)
						(arc
							(start 0.2032 0.3048)
							(mid 0.275042 0.275042)
							(end 0.3048 0.2032)
						)
					)
					(width 0)
					(fill yes)
				)
			)
		)
		(pad "2" smd custom
			(at 0 0.4445 270)
			(size 0.1524 0.1524)
			(layers "F.Cu" "F.Mask" "F.Paste")
			(net "GND")
			(options
				(clearance outline)
				(anchor circle)
			)
			(primitives
				(gr_poly
					(pts
						(arc
							(start 0.3048 -0.2032)
							(mid 0.275042 -0.275042)
							(end 0.2032 -0.3048)
						)
						(arc
							(start -0.2032 -0.3048)
							(mid -0.275042 -0.275042)
							(end -0.3048 -0.2032)
						)
						(arc
							(start -0.3048 0.2032)
							(mid -0.275042 0.275042)
							(end -0.2032 0.3048)
						)
						(arc
							(start 0.2032 0.3048)
							(mid 0.275042 0.275042)
							(end 0.3048 0.2032)
						)
					)
					(width 0)
					(fill yes)
				)
			)
		)
	)
	(footprint ""
		(layer "F.Cu")
		(at 75.0062 -40.3098 -90)
		(property "Reference" "C9"
			(at 0 0 270)
			(layer "F.SilkS")
			(hide yes)
			(effects
				(font
					(size 1.27 1.27)
				)
			)
		)
		(property "Value" "SC10U25V6KX-1GP"
			(at -0.0762 -5.1308 270)
			(unlocked yes)
			(layer "F.Fab")
			(hide yes)
			(effects
				(font
					(size 1.016 1.016)
					(thickness 0.1524)
				)
			)
		)
		(property "Device Type" "C1206H71"
			(at -0.127 -6.6548 270)
			(unlocked yes)
			(layer "F.Fab")
			(hide yes)
			(effects
				(font
					(size 1.016 1.016)
					(thickness 0.1524)
				)
			)
		)
		(duplicate_pad_numbers_are_jumpers no)
		(fp_line
			(start -1.016 2.2352)
			(end -1.016 0.8382)
			(stroke
				(width 0.1524)
				(type default)
			)
			(layer "F.SilkS")
		)
		(fp_line
			(start 1.016 2.2352)
			(end -1.016 2.2352)
			(stroke
				(width 0.1524)
				(type default)
			)
			(layer "F.SilkS")
		)
		(fp_line
			(start 1.016 0.8382)
			(end 1.016 2.2352)
			(stroke
				(width 0.1524)
				(type default)
			)
			(layer "F.SilkS")
		)
		(fp_line
			(start -1.016 -0.8382)
			(end -1.016 -2.2352)
			(stroke
				(width 0.1524)
				(type default)
			)
			(layer "F.SilkS")
		)
		(fp_line
			(start -1.016 -2.2352)
			(end 1.016 -2.2352)
			(stroke
				(width 0.1524)
				(type default)
			)
			(layer "F.SilkS")
		)
		(fp_line
			(start 1.016 -2.2352)
			(end 1.016 -0.8382)
			(stroke
				(width 0.1524)
				(type default)
			)
			(layer "F.SilkS")
		)
		(fp_rect
			(start -1.0922 2.3114)
			(end 1.0922 -2.3114)
			(stroke
				(width 0)
				(type default)
			)
			(fill no)
			(layer "F.CrtYd")
		)
		(fp_poly
			(pts
				(xy 1.0922 -2.3114) (xy 1.0922 2.3114) (xy -1.0922 2.3114) (xy -1.0922 -2.3114)
			)
			(stroke
				(width 0)
				(type default)
			)
			(fill no)
			(layer "F.Fab")
		)
		(pad "1" smd rect
			(at 0 -1.397 270)
			(size 1.651 1.27)
			(layers "F.Cu" "F.Mask" "F.Paste")
			(net "P12V_SW_R")
		)
		(pad "2" smd rect
			(at 0 1.397 270)
			(size 1.651 1.27)
			(layers "F.Cu" "F.Mask" "F.Paste")
			(net "GND")
		)
	)
	(footprint ""
		(layer "F.Cu")
		(at 124.841 -40.2082 -90)
		(property "Reference" "R3"
			(at 0 0 270)
			(layer "F.SilkS")
			(hide yes)
			(effects
				(font
					(size 1.27 1.27)
				)
			)
		)
		(property "Value" "10R3F-GP"
			(at -0.0254 -2.5146 270)
			(unlocked yes)
			(layer "F.Fab")
			(hide yes)
			(effects
				(font
					(size 1.016 1.016)
					(thickness 0.1524)
				)
			)
		)
		(property "Device Type" "R603H22"
			(at -0.0254 -4.0386 270)
			(unlocked yes)
			(layer "F.Fab")
			(hide yes)
			(effects
				(font
					(size 1.016 1.016)
					(thickness 0.1524)
				)
			)
		)
		(duplicate_pad_numbers_are_jumpers no)
		(fp_line
			(start -0.4826 0)
			(end -0.2032 0)
			(stroke
				(width 0.2032)
				(type default)
			)
			(layer "F.SilkS")
		)
		(fp_line
			(start 0.2032 0)
			(end 0.4826 0)
			(stroke
				(width 0.2032)
				(type default)
			)
			(layer "F.SilkS")
		)
		(fp_rect
			(start -0.5842 1.3335)
			(end 0.5842 -1.3335)
			(stroke
				(width 0)
				(type default)
			)
			(fill no)
			(layer "F.CrtYd")
		)
		(fp_rect
			(start -0.5842 1.3335)
			(end 0.5842 -1.3335)
			(stroke
				(width 0)
				(type default)
			)
			(fill no)
			(layer "F.Fab")
		)
		(pad "1" smd custom
			(at 0 -0.762 270)
			(size 0.2159 0.2159)
			(layers "F.Cu" "F.Mask" "F.Paste")
			(net "P5V_SW_R")
			(options
				(clearance outline)
				(anchor circle)
			)
			(primitives
				(gr_poly
					(pts
						(arc
							(start -0.3302 -0.4318)
							(mid -0.402042 -0.402042)
							(end -0.4318 -0.3302)
						)
						(arc
							(start -0.4318 0.3302)
							(mid -0.402042 0.402042)
							(end -0.3302 0.4318)
						)
						(arc
							(start 0.3302 0.4318)
							(mid 0.402042 0.402042)
							(end 0.4318 0.3302)
						)
						(arc
							(start 0.4318 -0.3302)
							(mid 0.402042 -0.402042)
							(end 0.3302 -0.4318)
						)
					)
					(width 0)
					(fill yes)
				)
			)
		)
		(pad "2" smd custom
			(at 0 0.762 270)
			(size 0.2159 0.2159)
			(layers "F.Cu" "F.Mask" "F.Paste")
			(net "5V_PRE_1")
			(options
				(clearance outline)
				(anchor circle)
			)
			(primitives
				(gr_poly
					(pts
						(arc
							(start -0.3302 -0.4318)
							(mid -0.402042 -0.402042)
							(end -0.4318 -0.3302)
						)
						(arc
							(start -0.4318 0.3302)
							(mid -0.402042 0.402042)
							(end -0.3302 0.4318)
						)
						(arc
							(start 0.3302 0.4318)
							(mid 0.402042 0.402042)
							(end 0.4318 0.3302)
						)
						(arc
							(start 0.4318 -0.3302)
							(mid 0.402042 -0.402042)
							(end 0.3302 -0.4318)
						)
					)
					(width 0)
					(fill yes)
				)
			)
		)
	)
	(footprint ""
		(layer "F.Cu")
		(at 53.721 -19.431)
		(property "Reference" "R8"
			(at 0 0 0)
			(layer "F.SilkS")
			(hide yes)
			(effects
				(font
					(size 1.27 1.27)
				)
			)
		)
		(property "Value" "10KR2J-3-GP"
			(at 0.064008 -3.993896 0)
			(unlocked yes)
			(layer "F.Fab")
			(hide yes)
			(effects
				(font
					(size 1.016 1.016)
					(thickness 0.1524)
				)
			)
		)
		(property "Device Type" "R402H16"
			(at 0.064008 -5.517896 0)
			(unlocked yes)
			(layer "F.Fab")
			(hide yes)
			(effects
				(font
					(size 1.016 1.016)
					(thickness 0.1524)
				)
			)
		)
		(duplicate_pad_numbers_are_jumpers no)
		(fp_line
			(start -0.508 -0.9398)
			(end -0.508 0.9398)
			(stroke
				(width 0.1524)
				(type default)
			)
			(layer "F.SilkS")
		)
		(fp_line
			(start 0.508 -0.9398)
			(end -0.508 -0.9398)
			(stroke
				(width 0.1524)
				(type default)
			)
			(layer "F.SilkS")
		)
		(fp_rect
			(start -0.508 0.9398)
			(end 0.508 -0.9398)
			(stroke
				(width 0)
				(type default)
			)
			(fill no)
			(layer "F.CrtYd")
		)
		(fp_rect
			(start -0.508 0.9398)
			(end 0.508 -0.9398)
			(stroke
				(width 0)
				(type default)
			)
			(fill no)
			(layer "F.Fab")
		)
		(pad "1" smd custom
			(at 0 -0.4445)
			(size 0.1397 0.1397)
			(layers "F.Cu" "F.Mask" "F.Paste")
			(net "P3V3")
			(options
				(clearance outline)
				(anchor circle)
			)
			(primitives
				(gr_poly
					(pts
						(arc
							(start -0.1778 -0.2794)
							(mid -0.249642 -0.249642)
							(end -0.2794 -0.1778)
						)
						(arc
							(start -0.2794 0.1778)
							(mid -0.249642 0.249642)
							(end -0.1778 0.2794)
						)
						(arc
							(start 0.1778 0.2794)
							(mid 0.249642 0.249642)
							(end 0.2794 0.1778)
						)
						(arc
							(start 0.2794 -0.1778)
							(mid 0.249642 -0.249642)
							(end 0.1778 -0.2794)
						)
					)
					(width 0)
					(fill yes)
				)
			)
		)
		(pad "2" smd custom
			(at 0 0.4445)
			(size 0.1397 0.1397)
			(layers "F.Cu" "F.Mask" "F.Paste")
			(net "HBA_PRSNT2_N")
			(options
				(clearance outline)
				(anchor circle)
			)
			(primitives
				(gr_poly
					(pts
						(arc
							(start -0.1778 -0.2794)
							(mid -0.249642 -0.249642)
							(end -0.2794 -0.1778)
						)
						(arc
							(start -0.2794 0.1778)
							(mid -0.249642 0.249642)
							(end -0.1778 0.2794)
						)
						(arc
							(start 0.1778 0.2794)
							(mid 0.249642 0.249642)
							(end 0.2794 0.1778)
						)
						(arc
							(start 0.2794 -0.1778)
							(mid 0.249642 -0.249642)
							(end 0.1778 -0.2794)
						)
					)
					(width 0)
					(fill yes)
				)
			)
		)
	)
	(footprint ""
		(layer "F.Cu")
		(at 51.428396 -9.891014 90)
		(property "Reference" "C18"
			(at 0 0 90)
			(layer "F.SilkS")
			(hide yes)
			(effects
				(font
					(size 1.27 1.27)
				)
			)
		)
		(property "Value" "SCD1U25V2KX-GP"
			(at 1.1811 -2.7051 90)
			(unlocked yes)
			(layer "F.Fab")
			(hide yes)
			(effects
				(font
					(size 1.016 1.016)
					(thickness 0.1524)
				)
			)
		)
		(property "Device Type" "C402H22"
			(at 1.1811 -4.2291 90)
			(unlocked yes)
			(layer "F.Fab")
			(hide yes)
			(effects
				(font
					(size 1.016 1.016)
					(thickness 0.1524)
				)
			)
		)
		(duplicate_pad_numbers_are_jumpers no)
		(fp_rect
			(start -0.4318 0.9525)
			(end 0.4318 -0.9525)
			(stroke
				(width 0)
				(type default)
			)
			(fill no)
			(layer "F.CrtYd")
		)
		(fp_rect
			(start -0.4318 0.9525)
			(end 0.4318 -0.9525)
			(stroke
				(width 0)
				(type default)
			)
			(fill no)
			(layer "F.Fab")
		)
		(pad "1" smd custom
			(at 0 -0.4445 90)
			(size 0.1524 0.1524)
			(layers "F.Cu" "F.Mask" "F.Paste")
			(net "P5V_SW_L")
			(options
				(clearance outline)
				(anchor circle)
			)
			(primitives
				(gr_poly
					(pts
						(arc
							(start 0.3048 -0.2032)
							(mid 0.275042 -0.275042)
							(end 0.2032 -0.3048)
						)
						(arc
							(start -0.2032 -0.3048)
							(mid -0.275042 -0.275042)
							(end -0.3048 -0.2032)
						)
						(arc
							(start -0.3048 0.2032)
							(mid -0.275042 0.275042)
							(end -0.2032 0.3048)
						)
						(arc
							(start 0.2032 0.3048)
							(mid 0.275042 0.275042)
							(end 0.3048 0.2032)
						)
					)
					(width 0)
					(fill yes)
				)
			)
		)
		(pad "2" smd custom
			(at 0 0.4445 90)
			(size 0.1524 0.1524)
			(layers "F.Cu" "F.Mask" "F.Paste")
			(net "GND")
			(options
				(clearance outline)
				(anchor circle)
			)
			(primitives
				(gr_poly
					(pts
						(arc
							(start 0.3048 -0.2032)
							(mid 0.275042 -0.275042)
							(end 0.2032 -0.3048)
						)
						(arc
							(start -0.2032 -0.3048)
							(mid -0.275042 -0.275042)
							(end -0.3048 -0.2032)
						)
						(arc
							(start -0.3048 0.2032)
							(mid -0.275042 0.275042)
							(end -0.2032 0.3048)
						)
						(arc
							(start 0.2032 0.3048)
							(mid 0.275042 0.275042)
							(end 0.3048 0.2032)
						)
					)
					(width 0)
					(fill yes)
				)
			)
		)
	)
	(footprint ""
		(layer "F.Cu")
		(at 125.640084 -56.909208 -90)
		(property "Reference" "R6"
			(at 0 0 270)
			(layer "F.SilkS")
			(hide yes)
			(effects
				(font
					(size 1.27 1.27)
				)
			)
		)
		(property "Value" "10R3F-GP"
			(at -0.0254 -2.5146 270)
			(unlocked yes)
			(layer "F.Fab")
			(hide yes)
			(effects
				(font
					(size 1.016 1.016)
					(thickness 0.1524)
				)
			)
		)
		(property "Device Type" "R603H22"
			(at -0.0254 -4.0386 270)
			(unlocked yes)
			(layer "F.Fab")
			(hide yes)
			(effects
				(font
					(size 1.016 1.016)
					(thickness 0.1524)
				)
			)
		)
		(duplicate_pad_numbers_are_jumpers no)
		(fp_line
			(start -0.4826 0)
			(end -0.2032 0)
			(stroke
				(width 0.2032)
				(type default)
			)
			(layer "F.SilkS")
		)
		(fp_line
			(start 0.2032 0)
			(end 0.4826 0)
			(stroke
				(width 0.2032)
				(type default)
			)
			(layer "F.SilkS")
		)
		(fp_rect
			(start -0.5842 1.3335)
			(end 0.5842 -1.3335)
			(stroke
				(width 0)
				(type default)
			)
			(fill no)
			(layer "F.CrtYd")
		)
		(fp_rect
			(start -0.5842 1.3335)
			(end 0.5842 -1.3335)
			(stroke
				(width 0)
				(type default)
			)
			(fill no)
			(layer "F.Fab")
		)
		(pad "1" smd custom
			(at 0 -0.762 270)
			(size 0.2159 0.2159)
			(layers "F.Cu" "F.Mask" "F.Paste")
			(net "P12V_SW_R")
			(options
				(clearance outline)
				(anchor circle)
			)
			(primitives
				(gr_poly
					(pts
						(arc
							(start -0.3302 -0.4318)
							(mid -0.402042 -0.402042)
							(end -0.4318 -0.3302)
						)
						(arc
							(start -0.4318 0.3302)
							(mid -0.402042 0.402042)
							(end -0.3302 0.4318)
						)
						(arc
							(start 0.3302 0.4318)
							(mid 0.402042 0.402042)
							(end 0.4318 0.3302)
						)
						(arc
							(start 0.4318 -0.3302)
							(mid 0.402042 -0.402042)
							(end 0.3302 -0.4318)
						)
					)
					(width 0)
					(fill yes)
				)
			)
		)
		(pad "2" smd custom
			(at 0 0.762 270)
			(size 0.2159 0.2159)
			(layers "F.Cu" "F.Mask" "F.Paste")
			(net "12V_PRE_0")
			(options
				(clearance outline)
				(anchor circle)
			)
			(primitives
				(gr_poly
					(pts
						(arc
							(start -0.3302 -0.4318)
							(mid -0.402042 -0.402042)
							(end -0.4318 -0.3302)
						)
						(arc
							(start -0.4318 0.3302)
							(mid -0.402042 0.402042)
							(end -0.3302 0.4318)
						)
						(arc
							(start 0.3302 0.4318)
							(mid 0.402042 0.402042)
							(end 0.4318 0.3302)
						)
						(arc
							(start 0.4318 -0.3302)
							(mid 0.402042 -0.402042)
							(end 0.3302 -0.4318)
						)
					)
					(width 0)
					(fill yes)
				)
			)
		)
	)
	(footprint ""
		(layer "F.Cu")
		(at 50.45202 -19.396456 90)
		(property "Reference" "C16"
			(at 0 0 90)
			(layer "F.SilkS")
			(hide yes)
			(effects
				(font
					(size 1.27 1.27)
				)
			)
		)
		(property "Value" "SC10U10V5KX-L1-GP"
			(at -0.0762 -6.1214 90)
			(unlocked yes)
			(layer "F.Fab")
			(hide yes)
			(effects
				(font
					(size 1.016 1.016)
					(thickness 0.1524)
				)
			)
		)
		(property "Device Type" "C805H58"
			(at -0.0762 -8.1534 90)
			(unlocked yes)
			(layer "F.Fab")
			(hide yes)
			(effects
				(font
					(size 1.016 1.016)
					(thickness 0.1524)
				)
			)
		)
		(duplicate_pad_numbers_are_jumpers no)
		(fp_line
			(start 0.635 0)
			(end -0.635 0)
			(stroke
				(width 0.508)
				(type default)
			)
			(layer "F.SilkS")
		)
		(fp_rect
			(start -0.9652 1.778)
			(end 0.9652 -1.778)
			(stroke
				(width 0)
				(type default)
			)
			(fill no)
			(layer "F.CrtYd")
		)
		(fp_poly
			(pts
				(xy -0.9652 -1.778) (xy 0.9652 -1.778) (xy 0.9652 1.778) (xy -0.9652 1.778)
			)
			(stroke
				(width 0)
				(type default)
			)
			(fill no)
			(layer "F.Fab")
		)
		(pad "1" smd rect
			(at 0 -0.9652 90)
			(size 1.397 1.143)
			(layers "F.Cu" "F.Mask" "F.Paste")
			(net "P5V_SW_L")
		)
		(pad "2" smd rect
			(at 0 0.9652 90)
			(size 1.397 1.143)
			(layers "F.Cu" "F.Mask" "F.Paste")
			(net "GND")
		)
	)
	(footprint ""
		(layer "F.Cu")
		(at 52.705 -19.431 180)
		(property "Reference" "C13"
			(at 0 0 180)
			(layer "F.SilkS")
			(hide yes)
			(effects
				(font
					(size 1.27 1.27)
				)
			)
		)
		(property "Value" "SCD01U50V2KX-1GP"
			(at 1.1811 -2.7051 180)
			(unlocked yes)
			(layer "F.Fab")
			(hide yes)
			(effects
				(font
					(size 1.016 1.016)
					(thickness 0.1524)
				)
			)
		)
		(property "Device Type" "C402H22"
			(at 1.1811 -4.2291 180)
			(unlocked yes)
			(layer "F.Fab")
			(hide yes)
			(effects
				(font
					(size 1.016 1.016)
					(thickness 0.1524)
				)
			)
		)
		(duplicate_pad_numbers_are_jumpers no)
		(fp_rect
			(start -0.4318 0.9525)
			(end 0.4318 -0.9525)
			(stroke
				(width 0)
				(type default)
			)
			(fill no)
			(layer "F.CrtYd")
		)
		(fp_rect
			(start -0.4318 0.9525)
			(end 0.4318 -0.9525)
			(stroke
				(width 0)
				(type default)
			)
			(fill no)
			(layer "F.Fab")
		)
		(pad "1" smd custom
			(at 0 -0.4445 180)
			(size 0.1524 0.1524)
			(layers "F.Cu" "F.Mask" "F.Paste")
			(net "HBA_PRSNT2_N")
			(options
				(clearance outline)
				(anchor circle)
			)
			(primitives
				(gr_poly
					(pts
						(arc
							(start 0.3048 -0.2032)
							(mid 0.275042 -0.275042)
							(end 0.2032 -0.3048)
						)
						(arc
							(start -0.2032 -0.3048)
							(mid -0.275042 -0.275042)
							(end -0.3048 -0.2032)
						)
						(arc
							(start -0.3048 0.2032)
							(mid -0.275042 0.275042)
							(end -0.2032 0.3048)
						)
						(arc
							(start 0.2032 0.3048)
							(mid 0.275042 0.275042)
							(end 0.3048 0.2032)
						)
					)
					(width 0)
					(fill yes)
				)
			)
		)
		(pad "2" smd custom
			(at 0 0.4445 180)
			(size 0.1524 0.1524)
			(layers "F.Cu" "F.Mask" "F.Paste")
			(net "GND")
			(options
				(clearance outline)
				(anchor circle)
			)
			(primitives
				(gr_poly
					(pts
						(arc
							(start 0.3048 -0.2032)
							(mid 0.275042 -0.275042)
							(end 0.2032 -0.3048)
						)
						(arc
							(start -0.2032 -0.3048)
							(mid -0.275042 -0.275042)
							(end -0.3048 -0.2032)
						)
						(arc
							(start -0.3048 0.2032)
							(mid -0.275042 0.275042)
							(end -0.2032 0.3048)
						)
						(arc
							(start 0.2032 0.3048)
							(mid 0.275042 0.275042)
							(end 0.3048 0.2032)
						)
					)
					(width 0)
					(fill yes)
				)
			)
		)
	)
	(footprint ""
		(layer "F.Cu")
		(at 107.145074 -36.319968 180)
		(property "Reference" "SATA2"
			(at 0 0 180)
			(layer "F.SilkS")
			(hide yes)
			(effects
				(font
					(size 1.27 1.27)
				)
			)
		)
		(property "Value" "FCI-CONN29-2R-GP-U"
			(at -35.2552 -14.1859 180)
			(unlocked yes)
			(layer "F.Fab")
			(hide yes)
			(effects
				(font
					(size 1.016 1.016)
					(thickness 0.1524)
				)
			)
		)
		(property "Device Type" "PREFIT-29P-458055-UH395"
			(at -35.2552 -15.7099 180)
			(unlocked yes)
			(layer "F.Fab")
			(hide yes)
			(effects
				(font
					(size 1.016 1.016)
					(thickness 0.1524)
				)
			)
		)
		(duplicate_pad_numbers_are_jumpers no)
		(fp_line
			(start 18.0467 3.0099)
			(end -28.2067 3.0099)
			(stroke
				(width 0.1524)
				(type default)
			)
			(layer "F.SilkS")
		)
		(fp_line
			(start 18.0467 -3.0099)
			(end 18.0467 3.0099)
			(stroke
				(width 0.1524)
				(type default)
			)
			(layer "F.SilkS")
		)
		(fp_line
			(start -28.2067 3.0099)
			(end -28.2067 -3.0099)
			(stroke
				(width 0.1524)
				(type default)
			)
			(layer "F.SilkS")
		)
		(fp_line
			(start -28.2067 -3.0099)
			(end 18.0467 -3.0099)
			(stroke
				(width 0.1524)
				(type default)
			)
			(layer "F.SilkS")
		)
		(fp_poly
			(pts
				(xy -28.2067 3.0099) (xy -28.2067 -3.0099) (xy -21.9202 -3.0099) (xy -21.9202 -1.4478) (xy -28.1305 -1.4478)
				(xy -28.1305 1.4478) (xy -10.6934 1.4478) (xy -10.6934 -0.381) (xy -3.0607 -0.381) (xy -3.0607 2.4384)
				(xy 3.1115 2.4384) (xy 3.1115 1.4478) (xy 17.9705 1.4478) (xy 17.9705 -1.4351) (xy 11.7602 -1.4351)
				(xy 11.7602 -2.2098) (xy -2.2606 -2.2098) (xy -2.2606 -3.0099) (xy 18.0467 -3.0099) (xy 18.0467 3.0099)
			)
			(stroke
				(width 0)
				(type default)
			)
			(fill yes)
			(layer "F.SilkS")
		)
		(fp_poly
			(pts
				(arc
					(start 2.2098 1.25095)
					(mid 2.0828 1.12395)
					(end 2.2098 0.99695)
				)
				(arc
					(start 2.5908 0.99695)
					(mid 2.7178 1.12395)
					(end 2.5908 1.25095)
				)
			)
			(stroke
				(width 0)
				(type default)
			)
			(fill yes)
			(layer "F.SilkS")
		)
		(fp_poly
			(pts
				(arc
					(start 1.4097 1.25095)
					(mid 1.2827 1.12395)
					(end 1.4097 0.99695)
				)
				(arc
					(start 1.7907 0.99695)
					(mid 1.9177 1.12395)
					(end 1.7907 1.25095)
				)
			)
			(stroke
				(width 0)
				(type default)
			)
			(fill yes)
			(layer "F.SilkS")
		)
		(fp_poly
			(pts
				(arc
					(start 0.6096 1.25095)
					(mid 0.4826 1.12395)
					(end 0.6096 0.99695)
				)
				(arc
					(start 0.9906 0.99695)
					(mid 1.1176 1.12395)
					(end 0.9906 1.25095)
				)
			)
			(stroke
				(width 0)
				(type default)
			)
			(fill yes)
			(layer "F.SilkS")
		)
		(fp_poly
			(pts
				(arc
					(start -0.1905 1.25095)
					(mid -0.3175 1.12395)
					(end -0.1905 0.99695)
				)
				(arc
					(start 0.1905 0.99695)
					(mid 0.3175 1.12395)
					(end 0.1905 1.25095)
				)
			)
			(stroke
				(width 0)
				(type default)
			)
			(fill yes)
			(layer "F.SilkS")
		)
		(fp_poly
			(pts
				(arc
					(start -0.9906 1.25095)
					(mid -1.1176 1.12395)
					(end -0.9906 0.99695)
				)
				(arc
					(start -0.6096 0.99695)
					(mid -0.4826 1.12395)
					(end -0.6096 1.25095)
				)
			)
			(stroke
				(width 0)
				(type default)
			)
			(fill yes)
			(layer "F.SilkS")
		)
		(fp_poly
			(pts
				(arc
					(start -1.7907 1.25095)
					(mid -1.9177 1.12395)
					(end -1.7907 0.99695)
				)
				(arc
					(start -1.4097 0.99695)
					(mid -1.2827 1.12395)
					(end -1.4097 1.25095)
				)
			)
			(stroke
				(width 0)
				(type default)
			)
			(fill yes)
			(layer "F.SilkS")
		)
		(fp_poly
			(pts
				(arc
					(start -2.5908 1.25095)
					(mid -2.7178 1.12395)
					(end -2.5908 0.99695)
				)
				(arc
					(start -2.2098 0.99695)
					(mid -2.0828 1.12395)
					(end -2.2098 1.25095)
				)
			)
			(stroke
				(width 0)
				(type default)
			)
			(fill yes)
			(layer "F.SilkS")
		)
		(fp_poly
			(pts
				(arc
					(start 10.4902 0.2032)
					(mid 10.287 0)
					(end 10.4902 -0.2032)
				)
				(arc
					(start 11.0998 -0.2032)
					(mid 11.303 0)
					(end 11.0998 0.2032)
				)
			)
			(stroke
				(width 0)
				(type default)
			)
			(fill yes)
			(layer "F.SilkS")
		)
		(fp_poly
			(pts
				(arc
					(start 9.2202 0.2032)
					(mid 9.017 0)
					(end 9.2202 -0.2032)
				)
				(arc
					(start 9.8298 -0.2032)
					(mid 10.033 0)
					(end 9.8298 0.2032)
				)
			)
			(stroke
				(width 0)
				(type default)
			)
			(fill yes)
			(layer "F.SilkS")
		)
		(fp_poly
			(pts
				(arc
					(start 7.9502 0.2032)
					(mid 7.747 0)
					(end 7.9502 -0.2032)
				)
				(arc
					(start 8.5598 -0.2032)
					(mid 8.763 0)
					(end 8.5598 0.2032)
				)
			)
			(stroke
				(width 0)
				(type default)
			)
			(fill yes)
			(layer "F.SilkS")
		)
		(fp_poly
			(pts
				(arc
					(start 6.6802 0.2032)
					(mid 6.477 0)
					(end 6.6802 -0.2032)
				)
				(arc
					(start 7.2898 -0.2032)
					(mid 7.493 0)
					(end 7.2898 0.2032)
				)
			)
			(stroke
				(width 0)
				(type default)
			)
			(fill yes)
			(layer "F.SilkS")
		)
		(fp_poly
			(pts
				(arc
					(start 5.4102 0.2032)
					(mid 5.207 0)
					(end 5.4102 -0.2032)
				)
				(arc
					(start 6.0198 -0.2032)
					(mid 6.223 0)
					(end 6.0198 0.2032)
				)
			)
			(stroke
				(width 0)
				(type default)
			)
			(fill yes)
			(layer "F.SilkS")
		)
		(fp_poly
			(pts
				(arc
					(start 4.1402 0.2032)
					(mid 3.937 0)
					(end 4.1402 -0.2032)
				)
				(arc
					(start 4.7498 -0.2032)
					(mid 4.953 0)
					(end 4.7498 0.2032)
				)
			)
			(stroke
				(width 0)
				(type default)
			)
			(fill yes)
			(layer "F.SilkS")
		)
		(fp_poly
			(pts
				(arc
					(start 2.8702 0.2032)
					(mid 2.667 0)
					(end 2.8702 -0.2032)
				)
				(arc
					(start 3.4798 -0.2032)
					(mid 3.683 0)
					(end 3.4798 0.2032)
				)
			)
			(stroke
				(width 0)
				(type default)
			)
			(fill yes)
			(layer "F.SilkS")
		)
		(fp_poly
			(pts
				(arc
					(start -3.4798 -2.4638)
					(mid -3.683 -2.667)
					(end -3.4798 -2.8702)
				)
				(arc
					(start -2.8702 -2.8702)
					(mid -2.667 -2.667)
					(end -2.8702 -2.4638)
				)
			)
			(stroke
				(width 0)
				(type default)
			)
			(fill yes)
			(layer "F.SilkS")
		)
		(fp_poly
			(pts
				(arc
					(start -4.7498 -2.4638)
					(mid -4.953 -2.667)
					(end -4.7498 -2.8702)
				)
				(arc
					(start -4.1402 -2.8702)
					(mid -3.937 -2.667)
					(end -4.1402 -2.4638)
				)
			)
			(stroke
				(width 0)
				(type default)
			)
			(fill yes)
			(layer "F.SilkS")
		)
		(fp_poly
			(pts
				(arc
					(start -6.0198 -2.4638)
					(mid -6.223 -2.667)
					(end -6.0198 -2.8702)
				)
				(arc
					(start -5.4102 -2.8702)
					(mid -5.207 -2.667)
					(end -5.4102 -2.4638)
				)
			)
			(stroke
				(width 0)
				(type default)
			)
			(fill yes)
			(layer "F.SilkS")
		)
		(fp_poly
			(pts
				(arc
					(start -7.2898 -2.4638)
					(mid -7.493 -2.667)
					(end -7.2898 -2.8702)
				)
				(arc
					(start -6.6802 -2.8702)
					(mid -6.477 -2.667)
					(end -6.6802 -2.4638)
				)
			)
			(stroke
				(width 0)
				(type default)
			)
			(fill yes)
			(layer "F.SilkS")
		)
		(fp_poly
			(pts
				(arc
					(start -8.5598 -2.4638)
					(mid -8.763 -2.667)
					(end -8.5598 -2.8702)
				)
				(arc
					(start -7.9502 -2.8702)
					(mid -7.747 -2.667)
					(end -7.9502 -2.4638)
				)
			)
			(stroke
				(width 0)
				(type default)
			)
			(fill yes)
			(layer "F.SilkS")
		)
		(fp_poly
			(pts
				(arc
					(start -9.8298 -2.4638)
					(mid -10.033 -2.667)
					(end -9.8298 -2.8702)
				)
				(arc
					(start -9.2202 -2.8702)
					(mid -9.017 -2.667)
					(end -9.2202 -2.4638)
				)
			)
			(stroke
				(width 0)
				(type default)
			)
			(fill yes)
			(layer "F.SilkS")
		)
		(fp_poly
			(pts
				(arc
					(start -11.0998 -2.4638)
					(mid -11.303 -2.667)
					(end -11.0998 -2.8702)
				)
				(arc
					(start -10.4902 -2.8702)
					(mid -10.287 -2.667)
					(end -10.4902 -2.4638)
				)
			)
			(stroke
				(width 0)
				(type default)
			)
			(fill yes)
			(layer "F.SilkS")
		)
		(fp_poly
			(pts
				(arc
					(start -12.3698 -2.4638)
					(mid -12.573 -2.667)
					(end -12.3698 -2.8702)
				)
				(arc
					(start -11.7602 -2.8702)
					(mid -11.557 -2.667)
					(end -11.7602 -2.4638)
				)
			)
			(stroke
				(width 0)
				(type default)
			)
			(fill yes)
			(layer "F.SilkS")
		)
		(fp_poly
			(pts
				(arc
					(start -13.6398 -2.4638)
					(mid -13.843 -2.667)
					(end -13.6398 -2.8702)
				)
				(arc
					(start -13.0302 -2.8702)
					(mid -12.827 -2.667)
					(end -13.0302 -2.4638)
				)
			)
			(stroke
				(width 0)
				(type default)
			)
			(fill yes)
			(layer "F.SilkS")
		)
		(fp_poly
			(pts
				(arc
					(start -14.9098 -2.4638)
					(mid -15.113 -2.667)
					(end -14.9098 -2.8702)
				)
				(arc
					(start -14.3002 -2.8702)
					(mid -14.097 -2.667)
					(end -14.3002 -2.4638)
				)
			)
			(stroke
				(width 0)
				(type default)
			)
			(fill yes)
			(layer "F.SilkS")
		)
		(fp_poly
			(pts
				(arc
					(start -16.1798 -2.4638)
					(mid -16.383 -2.667)
					(end -16.1798 -2.8702)
				)
				(arc
					(start -15.5702 -2.8702)
					(mid -15.367 -2.667)
					(end -15.5702 -2.4638)
				)
			)
			(stroke
				(width 0)
				(type default)
			)
			(fill yes)
			(layer "F.SilkS")
		)
		(fp_poly
			(pts
				(arc
					(start -17.4498 -2.4638)
					(mid -17.653 -2.667)
					(end -17.4498 -2.8702)
				)
				(arc
					(start -16.8402 -2.8702)
					(mid -16.637 -2.667)
					(end -16.8402 -2.4638)
				)
			)
			(stroke
				(width 0)
				(type default)
			)
			(fill yes)
			(layer "F.SilkS")
		)
		(fp_poly
			(pts
				(arc
					(start -18.7198 -2.4638)
					(mid -18.923 -2.667)
					(end -18.7198 -2.8702)
				)
				(arc
					(start -18.1102 -2.8702)
					(mid -17.907 -2.667)
					(end -18.1102 -2.4638)
				)
			)
			(stroke
				(width 0)
				(type default)
			)
			(fill yes)
			(layer "F.SilkS")
		)
		(fp_poly
			(pts
				(arc
					(start -19.9898 -2.4638)
					(mid -20.193 -2.667)
					(end -19.9898 -2.8702)
				)
				(arc
					(start -19.3802 -2.8702)
					(mid -19.177 -2.667)
					(end -19.3802 -2.4638)
				)
			)
			(stroke
				(width 0)
				(type default)
			)
			(fill yes)
			(layer "F.SilkS")
		)
		(fp_poly
			(pts
				(arc
					(start -21.2598 -2.4638)
					(mid -21.463 -2.667)
					(end -21.2598 -2.8702)
				)
				(arc
					(start -20.6502 -2.8702)
					(mid -20.447 -2.667)
					(end -20.6502 -2.4638)
				)
			)
			(stroke
				(width 0)
				(type default)
			)
			(fill yes)
			(layer "F.SilkS")
		)
		(fp_poly
			(pts
				(arc
					(start 17.87525 0.6096)
					(mid 17.57045 0.9144)
					(end 17.26565 0.6096)
				)
				(arc
					(start 17.26565 -0.6096)
					(mid 17.57045 -0.9144)
					(end 17.87525 -0.6096)
				)
			)
			(stroke
				(width 0)
				(type default)
			)
			(fill yes)
			(layer "F.SilkS")
		)
		(fp_poly
			(pts
				(arc
					(start -27.42565 0.6096)
					(mid -27.73045 0.9144)
					(end -28.03525 0.6096)
				)
				(arc
					(start -28.03525 -0.6096)
					(mid -27.73045 -0.9144)
					(end -27.42565 -0.6096)
				)
			)
			(stroke
				(width 0)
				(type default)
			)
			(fill yes)
			(layer "F.SilkS")
		)
		(fp_rect
			(start -32.2707 7.5438)
			(end 22.1107 -6.7056)
			(stroke
				(width 0)
				(type default)
			)
			(fill no)
			(layer "B.CrtYd")
		)
		(fp_rect
			(start -27.9527 2.7559)
			(end 17.7927 -2.7559)
			(stroke
				(width 0)
				(type default)
			)
			(fill no)
			(layer "F.CrtYd")
		)
		(fp_poly
			(pts
				(xy -28.4607 3.2639) (xy -28.4607 -3.2639) (xy 18.3007 -3.2639) (xy 18.3007 2.7051) (xy 17.7927 2.7051)
				(xy 17.7927 -2.7559) (xy -27.9527 -2.7559) (xy -27.9527 2.7559) (xy 17.7927 2.7559) (xy 17.7927 2.7178)
				(xy 18.3007 2.7178) (xy 18.3007 3.2639)
			)
			(stroke
				(width 0)
				(type default)
			)
			(fill no)
			(layer "F.CrtYd")
		)
		(fp_poly
			(pts
				(xy -32.9565 7.7597) (xy -32.9565 -7.7597) (xy 22.7965 -7.7597) (xy 22.7965 2.7051) (xy 18.3007 2.7051)
				(xy 18.3007 -3.2639) (xy -28.4607 -3.2639) (xy -28.4607 3.2639) (xy 18.3007 3.2639) (xy 18.3007 2.7178)
				(xy 22.7965 2.7178) (xy 22.7965 7.7597)
			)
			(stroke
				(width 0)
				(type default)
			)
			(fill no)
			(layer "F.CrtYd")
		)
		(fp_rect
			(start -32.2707 7.5438)
			(end 22.1107 -6.7056)
			(stroke
				(width 0)
				(type default)
			)
			(fill no)
			(layer "B.Fab")
		)
		(fp_rect
			(start -37.2745 12.5476)
			(end 27.1145 -11.7094)
			(stroke
				(width 0)
				(type default)
			)
			(fill no)
			(layer "B.Fab")
		)
		(fp_rect
			(start -28.4607 3.2639)
			(end 18.3007 -3.2639)
			(stroke
				(width 0)
				(type default)
			)
			(fill no)
			(layer "F.Fab")
		)
		(fp_rect
			(start -32.9565 7.7597)
			(end 22.7965 -7.7597)
			(stroke
				(width 0)
				(type default)
			)
			(fill no)
			(layer "F.Fab")
		)
		(fp_rect
			(start -37.9603 12.7635)
			(end 27.8003 -12.7635)
			(stroke
				(width 0)
				(type default)
			)
			(fill no)
			(layer "F.Fab")
		)
		(fp_text user "Press Fit"
			(at -21.3614 0.5715 180)
			(unlocked yes)
			(layer "F.SilkS")
			(effects
				(font
					(size 1.016 1.016)
					(thickness 0.1524)
				)
				(justify left)
			)
		)
		(fp_text user "Can not place BGA,CSP,Wave Solder Comonent."
			(at -28.9433 10.1219 180)
			(unlocked yes)
			(layer "B.Fab")
			(effects
				(font
					(size 1.016 1.016)
					(thickness 0.1524)
				)
				(justify left)
			)
		)
		(fp_text user "High Limit 2mm"
			(at -13.8811 6.6421 180)
			(unlocked yes)
			(layer "F.Fab")
			(effects
				(font
					(size 1.016 1.016)
					(thickness 0.1524)
				)
				(justify left)
			)
		)
		(fp_text user "Can not place BGA,CSP,Wave Solder Comonent."
			(at -28.9433 10.1219 180)
			(unlocked yes)
			(layer "F.Fab")
			(effects
				(font
					(size 1.016 1.016)
					(thickness 0.1524)
				)
				(justify left)
			)
		)
		(pad "" np_thru_hole circle
			(at -23.95474 0 180)
			(size 0.254 0.254)
			(drill 1.3462)
			(layers "*.Cu" "*.Mask")
			(clearance 0.9017)
			(thermal_gap 0.9017)
		)
		(pad "30" thru_hole circle
			(at -26.07945 0 180)
			(size 2.3622 2.3622)
			(drill 1.949958)
			(layers "*.Cu" "*.Mask")
			(remove_unused_layers no)
			(net "Net_73")
			(clearance 0.1524)
			(thermal_gap 0.1524)
		)
		(pad "31" thru_hole circle
			(at 15.91945 0 180)
			(size 2.3622 2.3622)
			(drill 1.949958)
			(layers "*.Cu" "*.Mask")
			(remove_unused_layers no)
			(net "Net_64")
			(clearance 0.1524)
			(thermal_gap 0.1524)
		)
		(pad "P1" thru_hole circle
			(at -3.175 -1.27 180)
			(size 0.8636 0.8636)
			(drill 0.499872)
			(layers "*.Cu" "*.Mask")
			(remove_unused_layers no)
			(net "Net_69")
			(clearance 0.1778)
			(thermal_gap 0.1778)
		)
		(pad "P2" thru_hole circle
			(at -4.445 -1.27 180)
			(size 0.8636 0.8636)
			(drill 0.499872)
			(layers "*.Cu" "*.Mask")
			(remove_unused_layers no)
			(net "Net_71")
			(clearance 0.1778)
			(thermal_gap 0.1778)
		)
		(pad "P3" thru_hole circle
			(at -5.715 -1.27 180)
			(size 0.8636 0.8636)
			(drill 0.499872)
			(layers "*.Cu" "*.Mask")
			(remove_unused_layers no)
			(net "Net_70")
			(clearance 0.1778)
			(thermal_gap 0.1778)
		)
		(pad "P4" thru_hole circle
			(at -6.985 -1.27 180)
			(size 0.8636 0.8636)
			(drill 0.499872)
			(layers "*.Cu" "*.Mask")
			(remove_unused_layers no)
			(net "GND")
			(clearance 0.1778)
			(thermal_gap 0.1778)
		)
		(pad "P5" thru_hole circle
			(at -8.255 -1.27 180)
			(size 0.8636 0.8636)
			(drill 0.499872)
			(layers "*.Cu" "*.Mask")
			(remove_unused_layers no)
			(net "GND")
			(clearance 0.1778)
			(thermal_gap 0.1778)
		)
		(pad "P6" thru_hole circle
			(at -9.525 -1.27 180)
			(size 0.8636 0.8636)
			(drill 0.499872)
			(layers "*.Cu" "*.Mask")
			(remove_unused_layers no)
			(net "GND")
			(clearance 0.1778)
			(thermal_gap 0.1778)
		)
		(pad "P7" thru_hole circle
			(at -10.795 -1.27 180)
			(size 0.8636 0.8636)
			(drill 0.499872)
			(layers "*.Cu" "*.Mask")
			(remove_unused_layers no)
			(net "5V_PRE_1")
			(clearance 0.1778)
			(thermal_gap 0.1778)
		)
		(pad "P8" thru_hole circle
			(at -12.065 -1.27 180)
			(size 0.8636 0.8636)
			(drill 0.499872)
			(layers "*.Cu" "*.Mask")
			(remove_unused_layers no)
			(net "P5V_SW_R")
			(clearance 0.1778)
			(thermal_gap 0.1778)
		)
		(pad "P9" thru_hole circle
			(at -13.335 -1.27 180)
			(size 0.8636 0.8636)
			(drill 0.499872)
			(layers "*.Cu" "*.Mask")
			(remove_unused_layers no)
			(net "P5V_SW_R")
			(clearance 0.1778)
			(thermal_gap 0.1778)
		)
		(pad "P10" thru_hole circle
			(at -14.605 -1.27 180)
			(size 0.8636 0.8636)
			(drill 0.499872)
			(layers "*.Cu" "*.Mask")
			(remove_unused_layers no)
			(net "HBA_PRSNT1_N")
			(clearance 0.1778)
			(thermal_gap 0.1778)
		)
		(pad "P11" thru_hole circle
			(at -15.875 -1.27 180)
			(size 0.8636 0.8636)
			(drill 0.499872)
			(layers "*.Cu" "*.Mask")
			(remove_unused_layers no)
			(net "HDD_ACT_LED1")
			(clearance 0.1778)
			(thermal_gap 0.1778)
		)
		(pad "P12" thru_hole circle
			(at -17.145 -1.27 180)
			(size 0.8636 0.8636)
			(drill 0.499872)
			(layers "*.Cu" "*.Mask")
			(remove_unused_layers no)
			(net "GND")
			(clearance 0.1778)
			(thermal_gap 0.1778)
		)
		(pad "P13" thru_hole circle
			(at -18.415 -1.27 180)
			(size 0.8636 0.8636)
			(drill 0.499872)
			(layers "*.Cu" "*.Mask")
			(remove_unused_layers no)
			(net "12V_PRE_1")
			(clearance 0.1778)
			(thermal_gap 0.1778)
		)
		(pad "P14" thru_hole circle
			(at -19.685 -1.27 180)
			(size 0.8636 0.8636)
			(drill 0.499872)
			(layers "*.Cu" "*.Mask")
			(remove_unused_layers no)
			(net "P12V_SW_R")
			(clearance 0.1778)
			(thermal_gap 0.1778)
		)
		(pad "P15" thru_hole circle
			(at -20.955 -1.27 180)
			(size 0.8636 0.8636)
			(drill 0.499872)
			(layers "*.Cu" "*.Mask")
			(remove_unused_layers no)
			(net "P12V_SW_R")
			(clearance 0.1778)
			(thermal_gap 0.1778)
		)
		(pad "S1" thru_hole circle
			(at 10.795 -1.27 180)
			(size 0.8636 0.8636)
			(drill 0.499872)
			(layers "*.Cu" "*.Mask")
			(remove_unused_layers no)
			(net "GND")
			(clearance 0.1778)
			(thermal_gap 0.1778)
		)
		(pad "S2" thru_hole circle
			(at 9.525 -1.27 180)
			(size 0.8636 0.8636)
			(drill 0.499872)
			(layers "*.Cu" "*.Mask")
			(remove_unused_layers no)
			(net "HBA_MB_TX_P1")
			(clearance 0.1778)
			(thermal_gap 0.1778)
		)
		(pad "S3" thru_hole circle
			(at 8.255 -1.27 180)
			(size 0.8636 0.8636)
			(drill 0.499872)
			(layers "*.Cu" "*.Mask")
			(remove_unused_layers no)
			(net "HBA_MB_TX_N1")
			(clearance 0.1778)
			(thermal_gap 0.1778)
		)
		(pad "S4" thru_hole circle
			(at 6.985 -1.27 180)
			(size 0.8636 0.8636)
			(drill 0.499872)
			(layers "*.Cu" "*.Mask")
			(remove_unused_layers no)
			(net "GND")
			(clearance 0.1778)
			(thermal_gap 0.1778)
		)
		(pad "S5" thru_hole circle
			(at 5.715 -1.27 180)
			(size 0.8636 0.8636)
			(drill 0.499872)
			(layers "*.Cu" "*.Mask")
			(remove_unused_layers no)
			(net "HBA_MB_RX_N1")
			(clearance 0.1778)
			(thermal_gap 0.1778)
		)
		(pad "S6" thru_hole circle
			(at 4.445 -1.27 180)
			(size 0.8636 0.8636)
			(drill 0.499872)
			(layers "*.Cu" "*.Mask")
			(remove_unused_layers no)
			(net "HBA_MB_RX_P1")
			(clearance 0.1778)
			(thermal_gap 0.1778)
		)
		(pad "S7" thru_hole circle
			(at 3.175 -1.27 180)
			(size 0.8636 0.8636)
			(drill 0.499872)
			(layers "*.Cu" "*.Mask")
			(remove_unused_layers no)
			(net "GND")
			(clearance 0.1778)
			(thermal_gap 0.1778)
		)
		(pad "S8" thru_hole oval
			(at 2.4003 2.13995 180)
			(size 0.6096 0.8128)
			(drill 0.399796)
			(layers "*.Cu" "*.Mask")
			(remove_unused_layers no)
			(net "GND")
			(clearance 0.254)
			(thermal_gap 0.254)
		)
		(pad "S9" thru_hole oval
			(at 1.6002 2.13995 180)
			(size 0.6096 0.8128)
			(drill 0.399796)
			(layers "*.Cu" "*.Mask")
			(remove_unused_layers no)
			(net "Net_68")
			(clearance 0.254)
			(thermal_gap 0.254)
		)
		(pad "S10" thru_hole oval
			(at 0.8001 2.13995 180)
			(size 0.6096 0.8128)
			(drill 0.399796)
			(layers "*.Cu" "*.Mask")
			(remove_unused_layers no)
			(net "Net_67")
			(clearance 0.254)
			(thermal_gap 0.254)
		)
		(pad "S11" thru_hole oval
			(at 0 2.13995 180)
			(size 0.6096 0.8128)
			(drill 0.399796)
			(layers "*.Cu" "*.Mask")
			(remove_unused_layers no)
			(net "Net_41")
			(clearance 0.254)
			(thermal_gap 0.254)
		)
		(pad "S12" thru_hole oval
			(at -0.8001 2.13995 180)
			(size 0.6096 0.8128)
			(drill 0.399796)
			(layers "*.Cu" "*.Mask")
			(remove_unused_layers no)
			(net "Net_66")
			(clearance 0.254)
			(thermal_gap 0.254)
		)
		(pad "S13" thru_hole oval
			(at -1.6002 2.13995 180)
			(size 0.6096 0.8128)
			(drill 0.399796)
			(layers "*.Cu" "*.Mask")
			(remove_unused_layers no)
			(net "Net_65")
			(clearance 0.254)
			(thermal_gap 0.254)
		)
		(pad "S14" thru_hole oval
			(at -2.4003 2.13995 180)
			(size 0.6096 0.8128)
			(drill 0.399796)
			(layers "*.Cu" "*.Mask")
			(remove_unused_layers no)
			(net "GND")
			(clearance 0.254)
			(thermal_gap 0.254)
		)
		(zone
			(layers "F.Cu" "B.Cu" "In1.Cu" "In2.Cu" "In3.Cu" "In4.Cu")
			(hatch none 0.5)
			(connect_pads
				(clearance 0)
			)
			(min_thickness 0.25)
			(keepout
				(tracks not_allowed)
				(vias allowed)
				(pads allowed)
				(copperpour not_allowed)
				(footprints allowed)
			)
			(placement
				(enabled no)
				(sheetname "")
			)
			(fill
				(thermal_gap 0.5)
				(thermal_bridge_width 0.5)
				(island_removal_mode 0)
			)
			(polygon
				(pts
					(arc
						(start 132.077714 -36.319968)
						(mid 130.121914 -36.319968)
						(end 132.077714 -36.319968)
					)
				)
			)
		)
	)
	(footprint ""
		(layer "F.Cu")
		(at 118.57609 -56.962802 -90)
		(property "Reference" "R4"
			(at 0 0 270)
			(layer "F.SilkS")
			(hide yes)
			(effects
				(font
					(size 1.27 1.27)
				)
			)
		)
		(property "Value" "10R3F-GP"
			(at -0.0254 -2.5146 270)
			(unlocked yes)
			(layer "F.Fab")
			(hide yes)
			(effects
				(font
					(size 1.016 1.016)
					(thickness 0.1524)
				)
			)
		)
		(property "Device Type" "R603H22"
			(at -0.0254 -4.0386 270)
			(unlocked yes)
			(layer "F.Fab")
			(hide yes)
			(effects
				(font
					(size 1.016 1.016)
					(thickness 0.1524)
				)
			)
		)
		(duplicate_pad_numbers_are_jumpers no)
		(fp_line
			(start -0.4826 0)
			(end -0.2032 0)
			(stroke
				(width 0.2032)
				(type default)
			)
			(layer "F.SilkS")
		)
		(fp_line
			(start 0.2032 0)
			(end 0.4826 0)
			(stroke
				(width 0.2032)
				(type default)
			)
			(layer "F.SilkS")
		)
		(fp_rect
			(start -0.5842 1.3335)
			(end 0.5842 -1.3335)
			(stroke
				(width 0)
				(type default)
			)
			(fill no)
			(layer "F.CrtYd")
		)
		(fp_rect
			(start -0.5842 1.3335)
			(end 0.5842 -1.3335)
			(stroke
				(width 0)
				(type default)
			)
			(fill no)
			(layer "F.Fab")
		)
		(pad "1" smd custom
			(at 0 -0.762 270)
			(size 0.2159 0.2159)
			(layers "F.Cu" "F.Mask" "F.Paste")
			(net "P5V_SW_R")
			(options
				(clearance outline)
				(anchor circle)
			)
			(primitives
				(gr_poly
					(pts
						(arc
							(start -0.3302 -0.4318)
							(mid -0.402042 -0.402042)
							(end -0.4318 -0.3302)
						)
						(arc
							(start -0.4318 0.3302)
							(mid -0.402042 0.402042)
							(end -0.3302 0.4318)
						)
						(arc
							(start 0.3302 0.4318)
							(mid 0.402042 0.402042)
							(end 0.4318 0.3302)
						)
						(arc
							(start 0.4318 -0.3302)
							(mid 0.402042 -0.402042)
							(end 0.3302 -0.4318)
						)
					)
					(width 0)
					(fill yes)
				)
			)
		)
		(pad "2" smd custom
			(at 0 0.762 270)
			(size 0.2159 0.2159)
			(layers "F.Cu" "F.Mask" "F.Paste")
			(net "5V_PRE_0")
			(options
				(clearance outline)
				(anchor circle)
			)
			(primitives
				(gr_poly
					(pts
						(arc
							(start -0.3302 -0.4318)
							(mid -0.402042 -0.402042)
							(end -0.4318 -0.3302)
						)
						(arc
							(start -0.4318 0.3302)
							(mid -0.402042 0.402042)
							(end -0.3302 0.4318)
						)
						(arc
							(start 0.3302 0.4318)
							(mid 0.402042 0.402042)
							(end 0.4318 0.3302)
						)
						(arc
							(start 0.4318 -0.3302)
							(mid 0.402042 -0.402042)
							(end 0.3302 -0.4318)
						)
					)
					(width 0)
					(fill yes)
				)
			)
		)
	)
	(footprint ""
		(layer "F.Cu")
		(at 139.999974 -61.699902)
		(property "Reference" "H2"
			(at 0 0 0)
			(layer "F.SilkS")
			(hide yes)
			(effects
				(font
					(size 1.27 1.27)
				)
			)
		)
		(property "Value" "HOLET217B237R166-GP"
			(at -5.08 -0.4572 0)
			(unlocked yes)
			(layer "F.Fab")
			(hide yes)
			(effects
				(font
					(size 1.016 1.016)
					(thickness 0.1524)
				)
			)
		)
		(property "Device Type" "HOLET217B237R166"
			(at -5.08 -1.9812 0)
			(unlocked yes)
			(layer "F.Fab")
			(hide yes)
			(effects
				(font
					(size 1.016 1.016)
					(thickness 0.1524)
				)
			)
		)
		(duplicate_pad_numbers_are_jumpers no)
		(fp_poly
			(pts
				(arc
					(start 3.3147 0)
					(mid -3.3147 0)
					(end 3.3147 0)
				)
			)
			(stroke
				(width 0)
				(type default)
			)
			(fill no)
			(layer "B.CrtYd")
		)
		(fp_poly
			(pts
				(arc
					(start 3.0607 0)
					(mid -3.0607 0)
					(end 3.0607 0)
				)
			)
			(stroke
				(width 0)
				(type default)
			)
			(fill no)
			(layer "F.CrtYd")
		)
		(fp_poly
			(pts
				(arc
					(start 3.3147 0)
					(mid -3.3147 0)
					(end 3.3147 0)
				)
			)
			(stroke
				(width 0)
				(type default)
			)
			(fill no)
			(layer "B.Fab")
		)
		(fp_poly
			(pts
				(arc
					(start 3.0607 0)
					(mid -3.0607 0)
					(end 3.0607 0)
				)
			)
			(stroke
				(width 0)
				(type default)
			)
			(fill no)
			(layer "F.Fab")
		)
		(pad "1" thru_hole circle
			(at 0 0)
			(size 5.5118 5.5118)
			(drill 4.2164)
			(layers "*.Cu" "*.Mask")
			(remove_unused_layers no)
			(net "GND")
			(clearance -0.1397)
			(thermal_gap 0.3048)
			(padstack
				(mode front_inner_back)
				(layer "Inner"
					(shape circle)
					(size 4.6228 4.6228)
					(clearance 0.3048)
				)
				(layer "B.Cu"
					(shape circle)
					(size 6.0198 6.0198)
					(clearance -0.3937)
				)
			)
		)
	)
	(footprint ""
		(layer "F.Cu")
		(at 91.059 -7.493 90)
		(property "Reference" "R149"
			(at 0 0 90)
			(layer "F.SilkS")
			(hide yes)
			(effects
				(font
					(size 1.27 1.27)
				)
			)
		)
		(property "Value" "200KR2F-L-GP"
			(at 0.064008 -3.993896 90)
			(unlocked yes)
			(layer "F.Fab")
			(hide yes)
			(effects
				(font
					(size 1.016 1.016)
					(thickness 0.1524)
				)
			)
		)
		(property "Device Type" "R402H16"
			(at 0.064008 -5.517896 90)
			(unlocked yes)
			(layer "F.Fab")
			(hide yes)
			(effects
				(font
					(size 1.016 1.016)
					(thickness 0.1524)
				)
			)
		)
		(duplicate_pad_numbers_are_jumpers no)
		(fp_line
			(start 0.508 -0.9398)
			(end -0.508 -0.9398)
			(stroke
				(width 0.1524)
				(type default)
			)
			(layer "F.SilkS")
		)
		(fp_line
			(start -0.508 -0.9398)
			(end -0.508 0.9398)
			(stroke
				(width 0.1524)
				(type default)
			)
			(layer "F.SilkS")
		)
		(fp_rect
			(start -0.508 0.9398)
			(end 0.508 -0.9398)
			(stroke
				(width 0)
				(type default)
			)
			(fill no)
			(layer "F.CrtYd")
		)
		(fp_rect
			(start -0.508 0.9398)
			(end 0.508 -0.9398)
			(stroke
				(width 0)
				(type default)
			)
			(fill no)
			(layer "F.Fab")
		)
		(pad "1" smd custom
			(at 0 -0.4445 90)
			(size 0.1397 0.1397)
			(layers "F.Cu" "F.Mask" "F.Paste")
			(net "SW_SW_L_0")
			(options
				(clearance outline)
				(anchor circle)
			)
			(primitives
				(gr_poly
					(pts
						(arc
							(start -0.1778 -0.2794)
							(mid -0.249642 -0.249642)
							(end -0.2794 -0.1778)
						)
						(arc
							(start -0.2794 0.1778)
							(mid -0.249642 0.249642)
							(end -0.1778 0.2794)
						)
						(arc
							(start 0.1778 0.2794)
							(mid 0.249642 0.249642)
							(end 0.2794 0.1778)
						)
						(arc
							(start 0.2794 -0.1778)
							(mid 0.249642 -0.249642)
							(end 0.1778 -0.2794)
						)
					)
					(width 0)
					(fill yes)
				)
			)
		)
		(pad "2" smd custom
			(at 0 0.4445 90)
			(size 0.1397 0.1397)
			(layers "F.Cu" "F.Mask" "F.Paste")
			(net "SW_SW_L_N_0")
			(options
				(clearance outline)
				(anchor circle)
			)
			(primitives
				(gr_poly
					(pts
						(arc
							(start -0.1778 -0.2794)
							(mid -0.249642 -0.249642)
							(end -0.2794 -0.1778)
						)
						(arc
							(start -0.2794 0.1778)
							(mid -0.249642 0.249642)
							(end -0.1778 0.2794)
						)
						(arc
							(start 0.1778 0.2794)
							(mid 0.249642 0.249642)
							(end 0.2794 0.1778)
						)
						(arc
							(start 0.2794 -0.1778)
							(mid 0.249642 -0.249642)
							(end 0.1778 -0.2794)
						)
					)
					(width 0)
					(fill yes)
				)
			)
		)
	)
	(footprint ""
		(layer "F.Cu")
		(at 128.744472 -40.966644)
		(property "Reference" "R1"
			(at 0 0 0)
			(layer "F.SilkS")
			(hide yes)
			(effects
				(font
					(size 1.27 1.27)
				)
			)
		)
		(property "Value" "10KR2J-3-GP"
			(at 0.064008 -3.993896 0)
			(unlocked yes)
			(layer "F.Fab")
			(hide yes)
			(effects
				(font
					(size 1.016 1.016)
					(thickness 0.1524)
				)
			)
		)
		(property "Device Type" "R402H16"
			(at 0.064008 -5.517896 0)
			(unlocked yes)
			(layer "F.Fab")
			(hide yes)
			(effects
				(font
					(size 1.016 1.016)
					(thickness 0.1524)
				)
			)
		)
		(duplicate_pad_numbers_are_jumpers no)
		(fp_line
			(start -0.508 -0.9398)
			(end -0.508 0.9398)
			(stroke
				(width 0.1524)
				(type default)
			)
			(layer "F.SilkS")
		)
		(fp_line
			(start 0.508 -0.9398)
			(end -0.508 -0.9398)
			(stroke
				(width 0.1524)
				(type default)
			)
			(layer "F.SilkS")
		)
		(fp_rect
			(start -0.508 0.9398)
			(end 0.508 -0.9398)
			(stroke
				(width 0)
				(type default)
			)
			(fill no)
			(layer "F.CrtYd")
		)
		(fp_rect
			(start -0.508 0.9398)
			(end 0.508 -0.9398)
			(stroke
				(width 0)
				(type default)
			)
			(fill no)
			(layer "F.Fab")
		)
		(pad "1" smd custom
			(at 0 -0.4445)
			(size 0.1397 0.1397)
			(layers "F.Cu" "F.Mask" "F.Paste")
			(net "P3V3")
			(options
				(clearance outline)
				(anchor circle)
			)
			(primitives
				(gr_poly
					(pts
						(arc
							(start -0.1778 -0.2794)
							(mid -0.249642 -0.249642)
							(end -0.2794 -0.1778)
						)
						(arc
							(start -0.2794 0.1778)
							(mid -0.249642 0.249642)
							(end -0.1778 0.2794)
						)
						(arc
							(start 0.1778 0.2794)
							(mid 0.249642 0.249642)
							(end 0.2794 0.1778)
						)
						(arc
							(start 0.2794 -0.1778)
							(mid 0.249642 -0.249642)
							(end 0.1778 -0.2794)
						)
					)
					(width 0)
					(fill yes)
				)
			)
		)
		(pad "2" smd custom
			(at 0 0.4445)
			(size 0.1397 0.1397)
			(layers "F.Cu" "F.Mask" "F.Paste")
			(net "HBA_PRSNT1_N")
			(options
				(clearance outline)
				(anchor circle)
			)
			(primitives
				(gr_poly
					(pts
						(arc
							(start -0.1778 -0.2794)
							(mid -0.249642 -0.249642)
							(end -0.2794 -0.1778)
						)
						(arc
							(start -0.2794 0.1778)
							(mid -0.249642 0.249642)
							(end -0.1778 0.2794)
						)
						(arc
							(start 0.1778 0.2794)
							(mid 0.249642 0.249642)
							(end 0.2794 0.1778)
						)
						(arc
							(start 0.2794 -0.1778)
							(mid 0.249642 -0.249642)
							(end 0.1778 -0.2794)
						)
					)
					(width 0)
					(fill yes)
				)
			)
		)
	)
	(footprint ""
		(layer "F.Cu")
		(at 11.811 -20.193 -90)
		(property "Reference" "C26"
			(at 0 0 270)
			(layer "F.SilkS")
			(hide yes)
			(effects
				(font
					(size 1.27 1.27)
				)
			)
		)
		(property "Value" "SCD1U25V2KX-GP"
			(at 1.1811 -2.7051 270)
			(unlocked yes)
			(layer "F.Fab")
			(hide yes)
			(effects
				(font
					(size 1.016 1.016)
					(thickness 0.1524)
				)
			)
		)
		(property "Device Type" "C402H22"
			(at 1.1811 -4.2291 270)
			(unlocked yes)
			(layer "F.Fab")
			(hide yes)
			(effects
				(font
					(size 1.016 1.016)
					(thickness 0.1524)
				)
			)
		)
		(duplicate_pad_numbers_are_jumpers no)
		(fp_rect
			(start -0.4318 0.9525)
			(end 0.4318 -0.9525)
			(stroke
				(width 0)
				(type default)
			)
			(fill no)
			(layer "F.CrtYd")
		)
		(fp_rect
			(start -0.4318 0.9525)
			(end 0.4318 -0.9525)
			(stroke
				(width 0)
				(type default)
			)
			(fill no)
			(layer "F.Fab")
		)
		(pad "1" smd custom
			(at 0 -0.4445 270)
			(size 0.1524 0.1524)
			(layers "F.Cu" "F.Mask" "F.Paste")
			(net "P5V")
			(options
				(clearance outline)
				(anchor circle)
			)
			(primitives
				(gr_poly
					(pts
						(arc
							(start 0.3048 -0.2032)
							(mid 0.275042 -0.275042)
							(end 0.2032 -0.3048)
						)
						(arc
							(start -0.2032 -0.3048)
							(mid -0.275042 -0.275042)
							(end -0.3048 -0.2032)
						)
						(arc
							(start -0.3048 0.2032)
							(mid -0.275042 0.275042)
							(end -0.2032 0.3048)
						)
						(arc
							(start 0.2032 0.3048)
							(mid 0.275042 0.275042)
							(end 0.3048 0.2032)
						)
					)
					(width 0)
					(fill yes)
				)
			)
		)
		(pad "2" smd custom
			(at 0 0.4445 270)
			(size 0.1524 0.1524)
			(layers "F.Cu" "F.Mask" "F.Paste")
			(net "GND")
			(options
				(clearance outline)
				(anchor circle)
			)
			(primitives
				(gr_poly
					(pts
						(arc
							(start 0.3048 -0.2032)
							(mid 0.275042 -0.275042)
							(end 0.2032 -0.3048)
						)
						(arc
							(start -0.2032 -0.3048)
							(mid -0.275042 -0.275042)
							(end -0.3048 -0.2032)
						)
						(arc
							(start -0.3048 0.2032)
							(mid -0.275042 0.275042)
							(end -0.2032 0.3048)
						)
						(arc
							(start 0.2032 0.3048)
							(mid 0.275042 0.275042)
							(end 0.3048 0.2032)
						)
					)
					(width 0)
					(fill yes)
				)
			)
		)
	)
	(footprint ""
		(layer "F.Cu")
		(at 77.978 -8.128 90)
		(property "Reference" "R153"
			(at 0 0 90)
			(layer "F.SilkS")
			(hide yes)
			(effects
				(font
					(size 1.27 1.27)
				)
			)
		)
		(property "Value" "33KR2J-3-GP"
			(at 0.064008 -3.993896 90)
			(unlocked yes)
			(layer "F.Fab")
			(hide yes)
			(effects
				(font
					(size 1.016 1.016)
					(thickness 0.1524)
				)
			)
		)
		(property "Device Type" "R402H16"
			(at 0.064008 -5.517896 90)
			(unlocked yes)
			(layer "F.Fab")
			(hide yes)
			(effects
				(font
					(size 1.016 1.016)
					(thickness 0.1524)
				)
			)
		)
		(duplicate_pad_numbers_are_jumpers no)
		(fp_line
			(start 0.508 -0.9398)
			(end -0.508 -0.9398)
			(stroke
				(width 0.1524)
				(type default)
			)
			(layer "F.SilkS")
		)
		(fp_line
			(start -0.508 -0.9398)
			(end -0.508 0.9398)
			(stroke
				(width 0.1524)
				(type default)
			)
			(layer "F.SilkS")
		)
		(fp_rect
			(start -0.508 0.9398)
			(end 0.508 -0.9398)
			(stroke
				(width 0)
				(type default)
			)
			(fill no)
			(layer "F.CrtYd")
		)
		(fp_rect
			(start -0.508 0.9398)
			(end 0.508 -0.9398)
			(stroke
				(width 0)
				(type default)
			)
			(fill no)
			(layer "F.Fab")
		)
		(pad "1" smd custom
			(at 0 -0.4445 90)
			(size 0.1397 0.1397)
			(layers "F.Cu" "F.Mask" "F.Paste")
			(net "PWR_EN_L")
			(options
				(clearance outline)
				(anchor circle)
			)
			(primitives
				(gr_poly
					(pts
						(arc
							(start -0.1778 -0.2794)
							(mid -0.249642 -0.249642)
							(end -0.2794 -0.1778)
						)
						(arc
							(start -0.2794 0.1778)
							(mid -0.249642 0.249642)
							(end -0.1778 0.2794)
						)
						(arc
							(start 0.1778 0.2794)
							(mid 0.249642 0.249642)
							(end 0.2794 0.1778)
						)
						(arc
							(start 0.2794 -0.1778)
							(mid 0.249642 -0.249642)
							(end 0.1778 -0.2794)
						)
					)
					(width 0)
					(fill yes)
				)
			)
		)
		(pad "2" smd custom
			(at 0 0.4445 90)
			(size 0.1397 0.1397)
			(layers "F.Cu" "F.Mask" "F.Paste")
			(net "VIN_P3")
			(options
				(clearance outline)
				(anchor circle)
			)
			(primitives
				(gr_poly
					(pts
						(arc
							(start -0.1778 -0.2794)
							(mid -0.249642 -0.249642)
							(end -0.2794 -0.1778)
						)
						(arc
							(start -0.2794 0.1778)
							(mid -0.249642 0.249642)
							(end -0.1778 0.2794)
						)
						(arc
							(start 0.1778 0.2794)
							(mid 0.249642 0.249642)
							(end 0.2794 0.1778)
						)
						(arc
							(start 0.2794 -0.1778)
							(mid 0.249642 -0.249642)
							(end 0.1778 -0.2794)
						)
					)
					(width 0)
					(fill yes)
				)
			)
		)
	)
	(footprint ""
		(layer "F.Cu")
		(at 83.096354 -38.56736 180)
		(property "Reference" "R139"
			(at 0 0 180)
			(layer "F.SilkS")
			(hide yes)
			(effects
				(font
					(size 1.27 1.27)
				)
			)
		)
		(property "Value" "300KR2F-GP"
			(at 0.064008 -3.993896 180)
			(unlocked yes)
			(layer "F.Fab")
			(hide yes)
			(effects
				(font
					(size 1.016 1.016)
					(thickness 0.1524)
				)
			)
		)
		(property "Device Type" "R402H16"
			(at 0.064008 -5.517896 180)
			(unlocked yes)
			(layer "F.Fab")
			(hide yes)
			(effects
				(font
					(size 1.016 1.016)
					(thickness 0.1524)
				)
			)
		)
		(duplicate_pad_numbers_are_jumpers no)
		(fp_line
			(start 0.508 -0.9398)
			(end -0.508 -0.9398)
			(stroke
				(width 0.1524)
				(type default)
			)
			(layer "F.SilkS")
		)
		(fp_line
			(start -0.508 -0.9398)
			(end -0.508 0.9398)
			(stroke
				(width 0.1524)
				(type default)
			)
			(layer "F.SilkS")
		)
		(fp_rect
			(start -0.508 0.9398)
			(end 0.508 -0.9398)
			(stroke
				(width 0)
				(type default)
			)
			(fill no)
			(layer "F.CrtYd")
		)
		(fp_rect
			(start -0.508 0.9398)
			(end 0.508 -0.9398)
			(stroke
				(width 0)
				(type default)
			)
			(fill no)
			(layer "F.Fab")
		)
		(pad "1" smd custom
			(at 0 -0.4445 180)
			(size 0.1397 0.1397)
			(layers "F.Cu" "F.Mask" "F.Paste")
			(net "SW_SW_R_N_0")
			(options
				(clearance outline)
				(anchor circle)
			)
			(primitives
				(gr_poly
					(pts
						(arc
							(start -0.1778 -0.2794)
							(mid -0.249642 -0.249642)
							(end -0.2794 -0.1778)
						)
						(arc
							(start -0.2794 0.1778)
							(mid -0.249642 0.249642)
							(end -0.1778 0.2794)
						)
						(arc
							(start 0.1778 0.2794)
							(mid 0.249642 0.249642)
							(end 0.2794 0.1778)
						)
						(arc
							(start 0.2794 -0.1778)
							(mid 0.249642 -0.249642)
							(end 0.1778 -0.2794)
						)
					)
					(width 0)
					(fill yes)
				)
			)
		)
		(pad "2" smd custom
			(at 0 0.4445 180)
			(size 0.1397 0.1397)
			(layers "F.Cu" "F.Mask" "F.Paste")
			(net "P12V")
			(options
				(clearance outline)
				(anchor circle)
			)
			(primitives
				(gr_poly
					(pts
						(arc
							(start -0.1778 -0.2794)
							(mid -0.249642 -0.249642)
							(end -0.2794 -0.1778)
						)
						(arc
							(start -0.2794 0.1778)
							(mid -0.249642 0.249642)
							(end -0.1778 0.2794)
						)
						(arc
							(start 0.1778 0.2794)
							(mid 0.249642 0.249642)
							(end 0.2794 0.1778)
						)
						(arc
							(start 0.2794 -0.1778)
							(mid 0.249642 -0.249642)
							(end 0.1778 -0.2794)
						)
					)
					(width 0)
					(fill yes)
				)
			)
		)
	)
	(footprint ""
		(layer "F.Cu")
		(at 59.46902 -19.523456 90)
		(property "Reference" "C19"
			(at 0 0 90)
			(layer "F.SilkS")
			(hide yes)
			(effects
				(font
					(size 1.27 1.27)
				)
			)
		)
		(property "Value" "SC10U25V6KX-1GP"
			(at -0.0762 -5.1308 90)
			(unlocked yes)
			(layer "F.Fab")
			(hide yes)
			(effects
				(font
					(size 1.016 1.016)
					(thickness 0.1524)
				)
			)
		)
		(property "Device Type" "C1206H71"
			(at -0.127 -6.6548 90)
			(unlocked yes)
			(layer "F.Fab")
			(hide yes)
			(effects
				(font
					(size 1.016 1.016)
					(thickness 0.1524)
				)
			)
		)
		(duplicate_pad_numbers_are_jumpers no)
		(fp_line
			(start 1.016 -2.2352)
			(end 1.016 -0.8382)
			(stroke
				(width 0.1524)
				(type default)
			)
			(layer "F.SilkS")
		)
		(fp_line
			(start -1.016 -2.2352)
			(end 1.016 -2.2352)
			(stroke
				(width 0.1524)
				(type default)
			)
			(layer "F.SilkS")
		)
		(fp_line
			(start -1.016 -0.8382)
			(end -1.016 -2.2352)
			(stroke
				(width 0.1524)
				(type default)
			)
			(layer "F.SilkS")
		)
		(fp_line
			(start 1.016 0.8382)
			(end 1.016 2.2352)
			(stroke
				(width 0.1524)
				(type default)
			)
			(layer "F.SilkS")
		)
		(fp_line
			(start 1.016 2.2352)
			(end -1.016 2.2352)
			(stroke
				(width 0.1524)
				(type default)
			)
			(layer "F.SilkS")
		)
		(fp_line
			(start -1.016 2.2352)
			(end -1.016 0.8382)
			(stroke
				(width 0.1524)
				(type default)
			)
			(layer "F.SilkS")
		)
		(fp_rect
			(start -1.0922 2.3114)
			(end 1.0922 -2.3114)
			(stroke
				(width 0)
				(type default)
			)
			(fill no)
			(layer "F.CrtYd")
		)
		(fp_poly
			(pts
				(xy 1.0922 -2.3114) (xy 1.0922 2.3114) (xy -1.0922 2.3114) (xy -1.0922 -2.3114)
			)
			(stroke
				(width 0)
				(type default)
			)
			(fill no)
			(layer "F.Fab")
		)
		(pad "1" smd rect
			(at 0 -1.397 90)
			(size 1.651 1.27)
			(layers "F.Cu" "F.Mask" "F.Paste")
			(net "P12V_SW_L")
		)
		(pad "2" smd rect
			(at 0 1.397 90)
			(size 1.651 1.27)
			(layers "F.Cu" "F.Mask" "F.Paste")
			(net "GND")
		)
	)
	(footprint ""
		(layer "F.Cu")
		(at 81.52511 -8.5852)
		(property "Reference" "R151"
			(at 0 0 0)
			(layer "F.SilkS")
			(hide yes)
			(effects
				(font
					(size 1.27 1.27)
				)
			)
		)
		(property "Value" "10KR2J-3-GP"
			(at 0.064008 -3.993896 0)
			(unlocked yes)
			(layer "F.Fab")
			(hide yes)
			(effects
				(font
					(size 1.016 1.016)
					(thickness 0.1524)
				)
			)
		)
		(property "Device Type" "R402H16"
			(at 0.064008 -5.517896 0)
			(unlocked yes)
			(layer "F.Fab")
			(hide yes)
			(effects
				(font
					(size 1.016 1.016)
					(thickness 0.1524)
				)
			)
		)
		(duplicate_pad_numbers_are_jumpers no)
		(fp_line
			(start -0.508 -0.9398)
			(end -0.508 0.9398)
			(stroke
				(width 0.1524)
				(type default)
			)
			(layer "F.SilkS")
		)
		(fp_line
			(start 0.508 -0.9398)
			(end -0.508 -0.9398)
			(stroke
				(width 0.1524)
				(type default)
			)
			(layer "F.SilkS")
		)
		(fp_rect
			(start -0.508 0.9398)
			(end 0.508 -0.9398)
			(stroke
				(width 0)
				(type default)
			)
			(fill no)
			(layer "F.CrtYd")
		)
		(fp_rect
			(start -0.508 0.9398)
			(end 0.508 -0.9398)
			(stroke
				(width 0)
				(type default)
			)
			(fill no)
			(layer "F.Fab")
		)
		(pad "1" smd custom
			(at 0 -0.4445)
			(size 0.1397 0.1397)
			(layers "F.Cu" "F.Mask" "F.Paste")
			(net "P3V3")
			(options
				(clearance outline)
				(anchor circle)
			)
			(primitives
				(gr_poly
					(pts
						(arc
							(start -0.1778 -0.2794)
							(mid -0.249642 -0.249642)
							(end -0.2794 -0.1778)
						)
						(arc
							(start -0.2794 0.1778)
							(mid -0.249642 0.249642)
							(end -0.1778 0.2794)
						)
						(arc
							(start 0.1778 0.2794)
							(mid 0.249642 0.249642)
							(end 0.2794 0.1778)
						)
						(arc
							(start 0.2794 -0.1778)
							(mid 0.249642 -0.249642)
							(end 0.1778 -0.2794)
						)
					)
					(width 0)
					(fill yes)
				)
			)
		)
		(pad "2" smd custom
			(at 0 0.4445)
			(size 0.1397 0.1397)
			(layers "F.Cu" "F.Mask" "F.Paste")
			(net "ENIN_P1")
			(options
				(clearance outline)
				(anchor circle)
			)
			(primitives
				(gr_poly
					(pts
						(arc
							(start -0.1778 -0.2794)
							(mid -0.249642 -0.249642)
							(end -0.2794 -0.1778)
						)
						(arc
							(start -0.2794 0.1778)
							(mid -0.249642 0.249642)
							(end -0.1778 0.2794)
						)
						(arc
							(start 0.1778 0.2794)
							(mid 0.249642 0.249642)
							(end 0.2794 0.1778)
						)
						(arc
							(start 0.2794 -0.1778)
							(mid 0.249642 -0.249642)
							(end 0.1778 -0.2794)
						)
					)
					(width 0)
					(fill yes)
				)
			)
		)
	)
	(footprint ""
		(layer "F.Cu")
		(at 77.724 -48.895 -90)
		(property "Reference" "C2"
			(at 0 0 270)
			(layer "F.SilkS")
			(hide yes)
			(effects
				(font
					(size 1.27 1.27)
				)
			)
		)
		(property "Value" "SC10U10V5KX-L1-GP"
			(at -0.0762 -6.1214 270)
			(unlocked yes)
			(layer "F.Fab")
			(hide yes)
			(effects
				(font
					(size 1.016 1.016)
					(thickness 0.1524)
				)
			)
		)
		(property "Device Type" "C805H58"
			(at -0.0762 -8.1534 270)
			(unlocked yes)
			(layer "F.Fab")
			(hide yes)
			(effects
				(font
					(size 1.016 1.016)
					(thickness 0.1524)
				)
			)
		)
		(duplicate_pad_numbers_are_jumpers no)
		(fp_line
			(start 0.635 0)
			(end -0.635 0)
			(stroke
				(width 0.508)
				(type default)
			)
			(layer "F.SilkS")
		)
		(fp_rect
			(start -0.9652 1.778)
			(end 0.9652 -1.778)
			(stroke
				(width 0)
				(type default)
			)
			(fill no)
			(layer "F.CrtYd")
		)
		(fp_poly
			(pts
				(xy -0.9652 -1.778) (xy 0.9652 -1.778) (xy 0.9652 1.778) (xy -0.9652 1.778)
			)
			(stroke
				(width 0)
				(type default)
			)
			(fill no)
			(layer "F.Fab")
		)
		(pad "1" smd rect
			(at 0 -0.9652 270)
			(size 1.397 1.143)
			(layers "F.Cu" "F.Mask" "F.Paste")
			(net "P5V_SW_R")
		)
		(pad "2" smd rect
			(at 0 0.9652 270)
			(size 1.397 1.143)
			(layers "F.Cu" "F.Mask" "F.Paste")
			(net "GND")
		)
	)
	(footprint ""
		(layer "F.Cu")
		(at 82.588608 -8.58393)
		(property "Reference" "R152"
			(at 0 0 0)
			(layer "F.SilkS")
			(hide yes)
			(effects
				(font
					(size 1.27 1.27)
				)
			)
		)
		(property "Value" "4K7R2J-2-GP"
			(at 0.064008 -3.993896 0)
			(unlocked yes)
			(layer "F.Fab")
			(hide yes)
			(effects
				(font
					(size 1.016 1.016)
					(thickness 0.1524)
				)
			)
		)
		(property "Device Type" "R402H16"
			(at 0.064008 -5.517896 0)
			(unlocked yes)
			(layer "F.Fab")
			(hide yes)
			(effects
				(font
					(size 1.016 1.016)
					(thickness 0.1524)
				)
			)
		)
		(duplicate_pad_numbers_are_jumpers no)
		(fp_line
			(start -0.508 -0.9398)
			(end -0.508 0.9398)
			(stroke
				(width 0.1524)
				(type default)
			)
			(layer "F.SilkS")
		)
		(fp_line
			(start 0.508 -0.9398)
			(end -0.508 -0.9398)
			(stroke
				(width 0.1524)
				(type default)
			)
			(layer "F.SilkS")
		)
		(fp_rect
			(start -0.508 0.9398)
			(end 0.508 -0.9398)
			(stroke
				(width 0)
				(type default)
			)
			(fill no)
			(layer "F.CrtYd")
		)
		(fp_rect
			(start -0.508 0.9398)
			(end 0.508 -0.9398)
			(stroke
				(width 0)
				(type default)
			)
			(fill no)
			(layer "F.Fab")
		)
		(pad "1" smd custom
			(at 0 -0.4445)
			(size 0.1397 0.1397)
			(layers "F.Cu" "F.Mask" "F.Paste")
			(net "P3V3")
			(options
				(clearance outline)
				(anchor circle)
			)
			(primitives
				(gr_poly
					(pts
						(arc
							(start -0.1778 -0.2794)
							(mid -0.249642 -0.249642)
							(end -0.2794 -0.1778)
						)
						(arc
							(start -0.2794 0.1778)
							(mid -0.249642 0.249642)
							(end -0.1778 0.2794)
						)
						(arc
							(start 0.1778 0.2794)
							(mid 0.249642 0.249642)
							(end 0.2794 0.1778)
						)
						(arc
							(start 0.2794 -0.1778)
							(mid 0.249642 -0.249642)
							(end 0.1778 -0.2794)
						)
					)
					(width 0)
					(fill yes)
				)
			)
		)
		(pad "2" smd custom
			(at 0 0.4445)
			(size 0.1397 0.1397)
			(layers "F.Cu" "F.Mask" "F.Paste")
			(net "PWR_EN_L_DELAY")
			(options
				(clearance outline)
				(anchor circle)
			)
			(primitives
				(gr_poly
					(pts
						(arc
							(start -0.1778 -0.2794)
							(mid -0.249642 -0.249642)
							(end -0.2794 -0.1778)
						)
						(arc
							(start -0.2794 0.1778)
							(mid -0.249642 0.249642)
							(end -0.1778 0.2794)
						)
						(arc
							(start 0.1778 0.2794)
							(mid 0.249642 0.249642)
							(end 0.2794 0.1778)
						)
						(arc
							(start 0.2794 -0.1778)
							(mid 0.249642 -0.249642)
							(end 0.1778 -0.2794)
						)
					)
					(width 0)
					(fill yes)
				)
			)
		)
	)
	(footprint ""
		(layer "F.Cu")
		(at 3.999992 -17.020032)
		(property "Reference" "H3"
			(at 0 0 0)
			(layer "F.SilkS")
			(hide yes)
			(effects
				(font
					(size 1.27 1.27)
				)
			)
		)
		(property "Value" "HOLET217B237R130-GP"
			(at -5.08 -0.4572 0)
			(unlocked yes)
			(layer "F.Fab")
			(hide yes)
			(effects
				(font
					(size 1.016 1.016)
					(thickness 0.1524)
				)
			)
		)
		(property "Device Type" "HOLET217B237R130"
			(at -5.08 -1.9812 0)
			(unlocked yes)
			(layer "F.Fab")
			(hide yes)
			(effects
				(font
					(size 1.016 1.016)
					(thickness 0.1524)
				)
			)
		)
		(duplicate_pad_numbers_are_jumpers no)
		(fp_poly
			(pts
				(arc
					(start 3.3147 0)
					(mid -3.3147 0)
					(end 3.3147 0)
				)
			)
			(stroke
				(width 0)
				(type default)
			)
			(fill no)
			(layer "B.CrtYd")
		)
		(fp_poly
			(pts
				(arc
					(start 3.0607 0)
					(mid -3.0607 0)
					(end 3.0607 0)
				)
			)
			(stroke
				(width 0)
				(type default)
			)
			(fill no)
			(layer "F.CrtYd")
		)
		(fp_poly
			(pts
				(arc
					(start 3.3147 0)
					(mid -3.3147 0)
					(end 3.3147 0)
				)
			)
			(stroke
				(width 0)
				(type default)
			)
			(fill no)
			(layer "B.Fab")
		)
		(fp_poly
			(pts
				(arc
					(start 3.0607 0)
					(mid -3.0607 0)
					(end 3.0607 0)
				)
			)
			(stroke
				(width 0)
				(type default)
			)
			(fill no)
			(layer "F.Fab")
		)
		(pad "1" thru_hole circle
			(at 0 0)
			(size 5.5118 5.5118)
			(drill 3.302)
			(layers "*.Cu" "*.Mask")
			(remove_unused_layers no)
			(net "GND")
			(clearance -0.5969)
			(thermal_gap 0.3048)
			(padstack
				(mode front_inner_back)
				(layer "Inner"
					(shape circle)
					(size 3.7084 3.7084)
					(clearance 0.3048)
				)
				(layer "B.Cu"
					(shape circle)
					(size 6.0198 6.0198)
					(clearance -0.8509)
				)
			)
		)
	)
	(footprint ""
		(layer "F.Cu")
		(at 50.45202 -20.793456 90)
		(property "Reference" "C17"
			(at 0 0 90)
			(layer "F.SilkS")
			(hide yes)
			(effects
				(font
					(size 1.27 1.27)
				)
			)
		)
		(property "Value" "SCD1U25V2KX-GP"
			(at 1.1811 -2.7051 90)
			(unlocked yes)
			(layer "F.Fab")
			(hide yes)
			(effects
				(font
					(size 1.016 1.016)
					(thickness 0.1524)
				)
			)
		)
		(property "Device Type" "C402H22"
			(at 1.1811 -4.2291 90)
			(unlocked yes)
			(layer "F.Fab")
			(hide yes)
			(effects
				(font
					(size 1.016 1.016)
					(thickness 0.1524)
				)
			)
		)
		(duplicate_pad_numbers_are_jumpers no)
		(fp_rect
			(start -0.4318 0.9525)
			(end 0.4318 -0.9525)
			(stroke
				(width 0)
				(type default)
			)
			(fill no)
			(layer "F.CrtYd")
		)
		(fp_rect
			(start -0.4318 0.9525)
			(end 0.4318 -0.9525)
			(stroke
				(width 0)
				(type default)
			)
			(fill no)
			(layer "F.Fab")
		)
		(pad "1" smd custom
			(at 0 -0.4445 90)
			(size 0.1524 0.1524)
			(layers "F.Cu" "F.Mask" "F.Paste")
			(net "P5V_SW_L")
			(options
				(clearance outline)
				(anchor circle)
			)
			(primitives
				(gr_poly
					(pts
						(arc
							(start 0.3048 -0.2032)
							(mid 0.275042 -0.275042)
							(end 0.2032 -0.3048)
						)
						(arc
							(start -0.2032 -0.3048)
							(mid -0.275042 -0.275042)
							(end -0.3048 -0.2032)
						)
						(arc
							(start -0.3048 0.2032)
							(mid -0.275042 0.275042)
							(end -0.2032 0.3048)
						)
						(arc
							(start 0.2032 0.3048)
							(mid 0.275042 0.275042)
							(end 0.3048 0.2032)
						)
					)
					(width 0)
					(fill yes)
				)
			)
		)
		(pad "2" smd custom
			(at 0 0.4445 90)
			(size 0.1524 0.1524)
			(layers "F.Cu" "F.Mask" "F.Paste")
			(net "GND")
			(options
				(clearance outline)
				(anchor circle)
			)
			(primitives
				(gr_poly
					(pts
						(arc
							(start 0.3048 -0.2032)
							(mid 0.275042 -0.275042)
							(end 0.2032 -0.3048)
						)
						(arc
							(start -0.2032 -0.3048)
							(mid -0.275042 -0.275042)
							(end -0.3048 -0.2032)
						)
						(arc
							(start -0.3048 0.2032)
							(mid -0.275042 0.275042)
							(end -0.2032 0.3048)
						)
						(arc
							(start 0.2032 0.3048)
							(mid 0.275042 0.275042)
							(end 0.3048 0.2032)
						)
					)
					(width 0)
					(fill yes)
				)
			)
		)
	)
	(footprint ""
		(layer "F.Cu")
		(at 82.998564 -50.779426 -90)
		(property "Reference" "R165"
			(at 0 0 270)
			(layer "F.SilkS")
			(hide yes)
			(effects
				(font
					(size 1.27 1.27)
				)
			)
		)
		(property "Value" "0R5J-5-GP"
			(at 0 -8.9535 270)
			(unlocked yes)
			(layer "F.Fab")
			(hide yes)
			(effects
				(font
					(size 1.27 1.016)
					(thickness 0.1524)
				)
			)
		)
		(property "Device Type" "R805H24"
			(at 0 -10.6299 270)
			(unlocked yes)
			(layer "F.Fab")
			(hide yes)
			(effects
				(font
					(size 1.27 1.016)
					(thickness 0.1524)
				)
			)
		)
		(duplicate_pad_numbers_are_jumpers no)
		(fp_line
			(start -0.889 1.7018)
			(end 0.889 1.7018)
			(stroke
				(width 0.1524)
				(type default)
			)
			(layer "F.SilkS")
		)
		(fp_line
			(start 0.889 1.7018)
			(end 0.889 -0.508)
			(stroke
				(width 0.1524)
				(type default)
			)
			(layer "F.SilkS")
		)
		(fp_line
			(start -0.889 0.0762)
			(end -0.889 1.7018)
			(stroke
				(width 0.1524)
				(type default)
			)
			(layer "F.SilkS")
		)
		(fp_line
			(start -0.889 -1.7018)
			(end -0.889 0.2794)
			(stroke
				(width 0.1524)
				(type default)
			)
			(layer "F.SilkS")
		)
		(fp_line
			(start 0.889 -1.7018)
			(end 0.889 -0.381)
			(stroke
				(width 0.1524)
				(type default)
			)
			(layer "F.SilkS")
		)
		(fp_line
			(start 0.889 -1.7018)
			(end -0.889 -1.7018)
			(stroke
				(width 0.1524)
				(type default)
			)
			(layer "F.SilkS")
		)
		(fp_poly
			(pts
				(xy 0.9652 -1.778) (xy 0.9652 1.778) (xy -0.9652 1.778) (xy -0.9652 -1.778)
			)
			(stroke
				(width 0)
				(type default)
			)
			(fill no)
			(layer "F.CrtYd")
		)
		(fp_rect
			(start -0.9652 1.778)
			(end 0.9652 -1.778)
			(stroke
				(width 0)
				(type default)
			)
			(fill no)
			(layer "F.Fab")
		)
		(pad "1" smd rect
			(at 0 -0.9652 270)
			(size 1.397 1.143)
			(layers "F.Cu" "F.Mask" "F.Paste")
			(net "P5V")
		)
		(pad "2" smd rect
			(at 0 0.9652 270)
			(size 1.397 1.143)
			(layers "F.Cu" "F.Mask" "F.Paste")
			(net "P5V_SW_R")
		)
	)
	(footprint ""
		(layer "F.Cu")
		(at 130.683 -40.259 -90)
		(property "Reference" "R5"
			(at 0 0 270)
			(layer "F.SilkS")
			(hide yes)
			(effects
				(font
					(size 1.27 1.27)
				)
			)
		)
		(property "Value" "10R3F-GP"
			(at -0.0254 -2.5146 270)
			(unlocked yes)
			(layer "F.Fab")
			(hide yes)
			(effects
				(font
					(size 1.016 1.016)
					(thickness 0.1524)
				)
			)
		)
		(property "Device Type" "R603H22"
			(at -0.0254 -4.0386 270)
			(unlocked yes)
			(layer "F.Fab")
			(hide yes)
			(effects
				(font
					(size 1.016 1.016)
					(thickness 0.1524)
				)
			)
		)
		(duplicate_pad_numbers_are_jumpers no)
		(fp_line
			(start -0.4826 0)
			(end -0.2032 0)
			(stroke
				(width 0.2032)
				(type default)
			)
			(layer "F.SilkS")
		)
		(fp_line
			(start 0.2032 0)
			(end 0.4826 0)
			(stroke
				(width 0.2032)
				(type default)
			)
			(layer "F.SilkS")
		)
		(fp_rect
			(start -0.5842 1.3335)
			(end 0.5842 -1.3335)
			(stroke
				(width 0)
				(type default)
			)
			(fill no)
			(layer "F.CrtYd")
		)
		(fp_rect
			(start -0.5842 1.3335)
			(end 0.5842 -1.3335)
			(stroke
				(width 0)
				(type default)
			)
			(fill no)
			(layer "F.Fab")
		)
		(pad "1" smd custom
			(at 0 -0.762 270)
			(size 0.2159 0.2159)
			(layers "F.Cu" "F.Mask" "F.Paste")
			(net "P12V_SW_R")
			(options
				(clearance outline)
				(anchor circle)
			)
			(primitives
				(gr_poly
					(pts
						(arc
							(start -0.3302 -0.4318)
							(mid -0.402042 -0.402042)
							(end -0.4318 -0.3302)
						)
						(arc
							(start -0.4318 0.3302)
							(mid -0.402042 0.402042)
							(end -0.3302 0.4318)
						)
						(arc
							(start 0.3302 0.4318)
							(mid 0.402042 0.402042)
							(end 0.4318 0.3302)
						)
						(arc
							(start 0.4318 -0.3302)
							(mid 0.402042 -0.402042)
							(end 0.3302 -0.4318)
						)
					)
					(width 0)
					(fill yes)
				)
			)
		)
		(pad "2" smd custom
			(at 0 0.762 270)
			(size 0.2159 0.2159)
			(layers "F.Cu" "F.Mask" "F.Paste")
			(net "12V_PRE_1")
			(options
				(clearance outline)
				(anchor circle)
			)
			(primitives
				(gr_poly
					(pts
						(arc
							(start -0.3302 -0.4318)
							(mid -0.402042 -0.402042)
							(end -0.4318 -0.3302)
						)
						(arc
							(start -0.4318 0.3302)
							(mid -0.402042 0.402042)
							(end -0.3302 0.4318)
						)
						(arc
							(start 0.3302 0.4318)
							(mid 0.402042 0.402042)
							(end 0.4318 0.3302)
						)
						(arc
							(start 0.4318 -0.3302)
							(mid 0.402042 -0.402042)
							(end 0.3302 -0.4318)
						)
					)
					(width 0)
					(fill yes)
				)
			)
		)
	)
	(footprint ""
		(layer "F.Cu")
		(at 84.112354 -38.56736)
		(property "Reference" "C29"
			(at 0 0 0)
			(layer "F.SilkS")
			(hide yes)
			(effects
				(font
					(size 1.27 1.27)
				)
			)
		)
		(property "Value" "SCD1U25V2KX-2-GP"
			(at 1.1811 -2.7051 0)
			(unlocked yes)
			(layer "F.Fab")
			(hide yes)
			(effects
				(font
					(size 1.016 1.016)
					(thickness 0.1524)
				)
			)
		)
		(property "Device Type" "C402H22"
			(at 1.1811 -4.2291 0)
			(unlocked yes)
			(layer "F.Fab")
			(hide yes)
			(effects
				(font
					(size 1.016 1.016)
					(thickness 0.1524)
				)
			)
		)
		(duplicate_pad_numbers_are_jumpers no)
		(fp_rect
			(start -0.4318 0.9525)
			(end 0.4318 -0.9525)
			(stroke
				(width 0)
				(type default)
			)
			(fill no)
			(layer "F.CrtYd")
		)
		(fp_rect
			(start -0.4318 0.9525)
			(end 0.4318 -0.9525)
			(stroke
				(width 0)
				(type default)
			)
			(fill no)
			(layer "F.Fab")
		)
		(pad "1" smd custom
			(at 0 -0.4445)
			(size 0.1524 0.1524)
			(layers "F.Cu" "F.Mask" "F.Paste")
			(net "P12V")
			(options
				(clearance outline)
				(anchor circle)
			)
			(primitives
				(gr_poly
					(pts
						(arc
							(start 0.3048 -0.2032)
							(mid 0.275042 -0.275042)
							(end 0.2032 -0.3048)
						)
						(arc
							(start -0.2032 -0.3048)
							(mid -0.275042 -0.275042)
							(end -0.3048 -0.2032)
						)
						(arc
							(start -0.3048 0.2032)
							(mid -0.275042 0.275042)
							(end -0.2032 0.3048)
						)
						(arc
							(start 0.2032 0.3048)
							(mid 0.275042 0.275042)
							(end 0.3048 0.2032)
						)
					)
					(width 0)
					(fill yes)
				)
			)
		)
		(pad "2" smd custom
			(at 0 0.4445)
			(size 0.1524 0.1524)
			(layers "F.Cu" "F.Mask" "F.Paste")
			(net "SW_SW_R_N_0")
			(options
				(clearance outline)
				(anchor circle)
			)
			(primitives
				(gr_poly
					(pts
						(arc
							(start 0.3048 -0.2032)
							(mid 0.275042 -0.275042)
							(end 0.2032 -0.3048)
						)
						(arc
							(start -0.2032 -0.3048)
							(mid -0.275042 -0.275042)
							(end -0.3048 -0.2032)
						)
						(arc
							(start -0.3048 0.2032)
							(mid -0.275042 0.275042)
							(end -0.2032 0.3048)
						)
						(arc
							(start 0.2032 0.3048)
							(mid 0.275042 0.275042)
							(end 0.3048 0.2032)
						)
					)
					(width 0)
					(fill yes)
				)
			)
		)
	)
	(footprint ""
		(layer "F.Cu")
		(at 82.403442 -11.334496 180)
		(property "Reference" "C32"
			(at 0 0 180)
			(layer "F.SilkS")
			(hide yes)
			(effects
				(font
					(size 1.27 1.27)
				)
			)
		)
		(property "Value" "SCD1U16V2JX-1-GP"
			(at 1.1811 -2.7051 180)
			(unlocked yes)
			(layer "F.Fab")
			(hide yes)
			(effects
				(font
					(size 1.016 1.016)
					(thickness 0.1524)
				)
			)
		)
		(property "Device Type" "C402H22"
			(at 1.1811 -4.2291 180)
			(unlocked yes)
			(layer "F.Fab")
			(hide yes)
			(effects
				(font
					(size 1.016 1.016)
					(thickness 0.1524)
				)
			)
		)
		(duplicate_pad_numbers_are_jumpers no)
		(fp_rect
			(start -0.4318 0.9525)
			(end 0.4318 -0.9525)
			(stroke
				(width 0)
				(type default)
			)
			(fill no)
			(layer "F.CrtYd")
		)
		(fp_rect
			(start -0.4318 0.9525)
			(end 0.4318 -0.9525)
			(stroke
				(width 0)
				(type default)
			)
			(fill no)
			(layer "F.Fab")
		)
		(pad "1" smd custom
			(at 0 -0.4445 180)
			(size 0.1524 0.1524)
			(layers "F.Cu" "F.Mask" "F.Paste")
			(net "P3V3")
			(options
				(clearance outline)
				(anchor circle)
			)
			(primitives
				(gr_poly
					(pts
						(arc
							(start 0.3048 -0.2032)
							(mid 0.275042 -0.275042)
							(end 0.2032 -0.3048)
						)
						(arc
							(start -0.2032 -0.3048)
							(mid -0.275042 -0.275042)
							(end -0.3048 -0.2032)
						)
						(arc
							(start -0.3048 0.2032)
							(mid -0.275042 0.275042)
							(end -0.2032 0.3048)
						)
						(arc
							(start 0.2032 0.3048)
							(mid 0.275042 0.275042)
							(end 0.3048 0.2032)
						)
					)
					(width 0)
					(fill yes)
				)
			)
		)
		(pad "2" smd custom
			(at 0 0.4445 180)
			(size 0.1524 0.1524)
			(layers "F.Cu" "F.Mask" "F.Paste")
			(net "GND")
			(options
				(clearance outline)
				(anchor circle)
			)
			(primitives
				(gr_poly
					(pts
						(arc
							(start 0.3048 -0.2032)
							(mid 0.275042 -0.275042)
							(end 0.2032 -0.3048)
						)
						(arc
							(start -0.2032 -0.3048)
							(mid -0.275042 -0.275042)
							(end -0.3048 -0.2032)
						)
						(arc
							(start -0.3048 0.2032)
							(mid -0.275042 0.275042)
							(end -0.2032 0.3048)
						)
						(arc
							(start 0.2032 0.3048)
							(mid 0.275042 0.275042)
							(end 0.3048 0.2032)
						)
					)
					(width 0)
					(fill yes)
				)
			)
		)
	)
	(footprint ""
		(layer "F.Cu")
		(at 77.724 -53.213 -90)
		(property "Reference" "C4"
			(at 0 0 270)
			(layer "F.SilkS")
			(hide yes)
			(effects
				(font
					(size 1.27 1.27)
				)
			)
		)
		(property "Value" "SCD1U25V2KX-GP"
			(at 1.1811 -2.7051 270)
			(unlocked yes)
			(layer "F.Fab")
			(hide yes)
			(effects
				(font
					(size 1.016 1.016)
					(thickness 0.1524)
				)
			)
		)
		(property "Device Type" "C402H22"
			(at 1.1811 -4.2291 270)
			(unlocked yes)
			(layer "F.Fab")
			(hide yes)
			(effects
				(font
					(size 1.016 1.016)
					(thickness 0.1524)
				)
			)
		)
		(duplicate_pad_numbers_are_jumpers no)
		(fp_rect
			(start -0.4318 0.9525)
			(end 0.4318 -0.9525)
			(stroke
				(width 0)
				(type default)
			)
			(fill no)
			(layer "F.CrtYd")
		)
		(fp_rect
			(start -0.4318 0.9525)
			(end 0.4318 -0.9525)
			(stroke
				(width 0)
				(type default)
			)
			(fill no)
			(layer "F.Fab")
		)
		(pad "1" smd custom
			(at 0 -0.4445 270)
			(size 0.1524 0.1524)
			(layers "F.Cu" "F.Mask" "F.Paste")
			(net "P5V_SW_R")
			(options
				(clearance outline)
				(anchor circle)
			)
			(primitives
				(gr_poly
					(pts
						(arc
							(start 0.3048 -0.2032)
							(mid 0.275042 -0.275042)
							(end 0.2032 -0.3048)
						)
						(arc
							(start -0.2032 -0.3048)
							(mid -0.275042 -0.275042)
							(end -0.3048 -0.2032)
						)
						(arc
							(start -0.3048 0.2032)
							(mid -0.275042 0.275042)
							(end -0.2032 0.3048)
						)
						(arc
							(start 0.2032 0.3048)
							(mid 0.275042 0.275042)
							(end 0.3048 0.2032)
						)
					)
					(width 0)
					(fill yes)
				)
			)
		)
		(pad "2" smd custom
			(at 0 0.4445 270)
			(size 0.1524 0.1524)
			(layers "F.Cu" "F.Mask" "F.Paste")
			(net "GND")
			(options
				(clearance outline)
				(anchor circle)
			)
			(primitives
				(gr_poly
					(pts
						(arc
							(start 0.3048 -0.2032)
							(mid 0.275042 -0.275042)
							(end 0.2032 -0.3048)
						)
						(arc
							(start -0.2032 -0.3048)
							(mid -0.275042 -0.275042)
							(end -0.3048 -0.2032)
						)
						(arc
							(start -0.3048 0.2032)
							(mid -0.275042 0.275042)
							(end -0.2032 0.3048)
						)
						(arc
							(start 0.2032 0.3048)
							(mid 0.275042 0.275042)
							(end 0.3048 0.2032)
						)
					)
					(width 0)
					(fill yes)
				)
			)
		)
	)
	(footprint ""
		(layer "F.Cu")
		(at 91.694 -10.033)
		(property "Reference" "C31"
			(at 0 0 0)
			(layer "F.SilkS")
			(hide yes)
			(effects
				(font
					(size 1.27 1.27)
				)
			)
		)
		(property "Value" "SCD1U25V2KX-2-GP"
			(at 1.1811 -2.7051 0)
			(unlocked yes)
			(layer "F.Fab")
			(hide yes)
			(effects
				(font
					(size 1.016 1.016)
					(thickness 0.1524)
				)
			)
		)
		(property "Device Type" "C402H22"
			(at 1.1811 -4.2291 0)
			(unlocked yes)
			(layer "F.Fab")
			(hide yes)
			(effects
				(font
					(size 1.016 1.016)
					(thickness 0.1524)
				)
			)
		)
		(duplicate_pad_numbers_are_jumpers no)
		(fp_rect
			(start -0.4318 0.9525)
			(end 0.4318 -0.9525)
			(stroke
				(width 0)
				(type default)
			)
			(fill no)
			(layer "F.CrtYd")
		)
		(fp_rect
			(start -0.4318 0.9525)
			(end 0.4318 -0.9525)
			(stroke
				(width 0)
				(type default)
			)
			(fill no)
			(layer "F.Fab")
		)
		(pad "1" smd custom
			(at 0 -0.4445)
			(size 0.1524 0.1524)
			(layers "F.Cu" "F.Mask" "F.Paste")
			(net "P12V")
			(options
				(clearance outline)
				(anchor circle)
			)
			(primitives
				(gr_poly
					(pts
						(arc
							(start 0.3048 -0.2032)
							(mid 0.275042 -0.275042)
							(end 0.2032 -0.3048)
						)
						(arc
							(start -0.2032 -0.3048)
							(mid -0.275042 -0.275042)
							(end -0.3048 -0.2032)
						)
						(arc
							(start -0.3048 0.2032)
							(mid -0.275042 0.275042)
							(end -0.2032 0.3048)
						)
						(arc
							(start 0.2032 0.3048)
							(mid 0.275042 0.275042)
							(end 0.3048 0.2032)
						)
					)
					(width 0)
					(fill yes)
				)
			)
		)
		(pad "2" smd custom
			(at 0 0.4445)
			(size 0.1524 0.1524)
			(layers "F.Cu" "F.Mask" "F.Paste")
			(net "SW_SW_L_N_0")
			(options
				(clearance outline)
				(anchor circle)
			)
			(primitives
				(gr_poly
					(pts
						(arc
							(start 0.3048 -0.2032)
							(mid 0.275042 -0.275042)
							(end 0.2032 -0.3048)
						)
						(arc
							(start -0.2032 -0.3048)
							(mid -0.275042 -0.275042)
							(end -0.3048 -0.2032)
						)
						(arc
							(start -0.3048 0.2032)
							(mid -0.275042 0.275042)
							(end -0.2032 0.3048)
						)
						(arc
							(start 0.2032 0.3048)
							(mid 0.275042 0.275042)
							(end 0.3048 0.2032)
						)
					)
					(width 0)
					(fill yes)
				)
			)
		)
	)
	(footprint ""
		(layer "F.Cu")
		(at 83.435444 -41.18102 -90)
		(property "Reference" "R161"
			(at 0 0 270)
			(layer "F.SilkS")
			(hide yes)
			(effects
				(font
					(size 1.27 1.27)
				)
			)
		)
		(property "Value" "0R5J-5-GP"
			(at 0 -8.9535 270)
			(unlocked yes)
			(layer "F.Fab")
			(hide yes)
			(effects
				(font
					(size 1.27 1.016)
					(thickness 0.1524)
				)
			)
		)
		(property "Device Type" "R805H24"
			(at 0 -10.6299 270)
			(unlocked yes)
			(layer "F.Fab")
			(hide yes)
			(effects
				(font
					(size 1.27 1.016)
					(thickness 0.1524)
				)
			)
		)
		(duplicate_pad_numbers_are_jumpers no)
		(fp_line
			(start -0.889 1.7018)
			(end 0.889 1.7018)
			(stroke
				(width 0.1524)
				(type default)
			)
			(layer "F.SilkS")
		)
		(fp_line
			(start 0.889 1.7018)
			(end 0.889 -0.508)
			(stroke
				(width 0.1524)
				(type default)
			)
			(layer "F.SilkS")
		)
		(fp_line
			(start -0.889 0.0762)
			(end -0.889 1.7018)
			(stroke
				(width 0.1524)
				(type default)
			)
			(layer "F.SilkS")
		)
		(fp_line
			(start -0.889 -1.7018)
			(end -0.889 0.2794)
			(stroke
				(width 0.1524)
				(type default)
			)
			(layer "F.SilkS")
		)
		(fp_line
			(start 0.889 -1.7018)
			(end 0.889 -0.381)
			(stroke
				(width 0.1524)
				(type default)
			)
			(layer "F.SilkS")
		)
		(fp_line
			(start 0.889 -1.7018)
			(end -0.889 -1.7018)
			(stroke
				(width 0.1524)
				(type default)
			)
			(layer "F.SilkS")
		)
		(fp_poly
			(pts
				(xy 0.9652 -1.778) (xy 0.9652 1.778) (xy -0.9652 1.778) (xy -0.9652 -1.778)
			)
			(stroke
				(width 0)
				(type default)
			)
			(fill no)
			(layer "F.CrtYd")
		)
		(fp_rect
			(start -0.9652 1.778)
			(end 0.9652 -1.778)
			(stroke
				(width 0)
				(type default)
			)
			(fill no)
			(layer "F.Fab")
		)
		(pad "1" smd rect
			(at 0 -0.9652 270)
			(size 1.397 1.143)
			(layers "F.Cu" "F.Mask" "F.Paste")
			(net "P12V")
		)
		(pad "2" smd rect
			(at 0 0.9652 270)
			(size 1.397 1.143)
			(layers "F.Cu" "F.Mask" "F.Paste")
			(net "P12V_SW_R")
		)
	)
	(footprint ""
		(layer "F.Cu")
		(at 74.9046 -41.8592 -90)
		(property "Reference" "C10"
			(at 0 0 270)
			(layer "F.SilkS")
			(hide yes)
			(effects
				(font
					(size 1.27 1.27)
				)
			)
		)
		(property "Value" "SCD1U25V2KX-GP"
			(at 1.1811 -2.7051 270)
			(unlocked yes)
			(layer "F.Fab")
			(hide yes)
			(effects
				(font
					(size 1.016 1.016)
					(thickness 0.1524)
				)
			)
		)
		(property "Device Type" "C402H22"
			(at 1.1811 -4.2291 270)
			(unlocked yes)
			(layer "F.Fab")
			(hide yes)
			(effects
				(font
					(size 1.016 1.016)
					(thickness 0.1524)
				)
			)
		)
		(duplicate_pad_numbers_are_jumpers no)
		(fp_rect
			(start -0.4318 0.9525)
			(end 0.4318 -0.9525)
			(stroke
				(width 0)
				(type default)
			)
			(fill no)
			(layer "F.CrtYd")
		)
		(fp_rect
			(start -0.4318 0.9525)
			(end 0.4318 -0.9525)
			(stroke
				(width 0)
				(type default)
			)
			(fill no)
			(layer "F.Fab")
		)
		(pad "1" smd custom
			(at 0 -0.4445 270)
			(size 0.1524 0.1524)
			(layers "F.Cu" "F.Mask" "F.Paste")
			(net "P12V_SW_R")
			(options
				(clearance outline)
				(anchor circle)
			)
			(primitives
				(gr_poly
					(pts
						(arc
							(start 0.3048 -0.2032)
							(mid 0.275042 -0.275042)
							(end 0.2032 -0.3048)
						)
						(arc
							(start -0.2032 -0.3048)
							(mid -0.275042 -0.275042)
							(end -0.3048 -0.2032)
						)
						(arc
							(start -0.3048 0.2032)
							(mid -0.275042 0.275042)
							(end -0.2032 0.3048)
						)
						(arc
							(start 0.2032 0.3048)
							(mid 0.275042 0.275042)
							(end 0.3048 0.2032)
						)
					)
					(width 0)
					(fill yes)
				)
			)
		)
		(pad "2" smd custom
			(at 0 0.4445 270)
			(size 0.1524 0.1524)
			(layers "F.Cu" "F.Mask" "F.Paste")
			(net "GND")
			(options
				(clearance outline)
				(anchor circle)
			)
			(primitives
				(gr_poly
					(pts
						(arc
							(start 0.3048 -0.2032)
							(mid 0.275042 -0.275042)
							(end 0.2032 -0.3048)
						)
						(arc
							(start -0.2032 -0.3048)
							(mid -0.275042 -0.275042)
							(end -0.3048 -0.2032)
						)
						(arc
							(start -0.3048 0.2032)
							(mid -0.275042 0.275042)
							(end -0.2032 0.3048)
						)
						(arc
							(start 0.2032 0.3048)
							(mid 0.275042 0.275042)
							(end 0.3048 0.2032)
						)
					)
					(width 0)
					(fill yes)
				)
			)
		)
	)
	(footprint ""
		(layer "F.Cu")
		(at 139.999974 -3.50012)
		(property "Reference" "H6"
			(at 0 0 0)
			(layer "F.SilkS")
			(hide yes)
			(effects
				(font
					(size 1.27 1.27)
				)
			)
		)
		(property "Value" "HOLET217B237R130-GP"
			(at -5.08 -0.4572 0)
			(unlocked yes)
			(layer "F.Fab")
			(hide yes)
			(effects
				(font
					(size 1.016 1.016)
					(thickness 0.1524)
				)
			)
		)
		(property "Device Type" "HOLET217B237R130"
			(at -5.08 -1.9812 0)
			(unlocked yes)
			(layer "F.Fab")
			(hide yes)
			(effects
				(font
					(size 1.016 1.016)
					(thickness 0.1524)
				)
			)
		)
		(duplicate_pad_numbers_are_jumpers no)
		(fp_poly
			(pts
				(arc
					(start 3.3147 0)
					(mid -3.3147 0)
					(end 3.3147 0)
				)
			)
			(stroke
				(width 0)
				(type default)
			)
			(fill no)
			(layer "B.CrtYd")
		)
		(fp_poly
			(pts
				(arc
					(start 3.0607 0)
					(mid -3.0607 0)
					(end 3.0607 0)
				)
			)
			(stroke
				(width 0)
				(type default)
			)
			(fill no)
			(layer "F.CrtYd")
		)
		(fp_poly
			(pts
				(arc
					(start 3.3147 0)
					(mid -3.3147 0)
					(end 3.3147 0)
				)
			)
			(stroke
				(width 0)
				(type default)
			)
			(fill no)
			(layer "B.Fab")
		)
		(fp_poly
			(pts
				(arc
					(start 3.0607 0)
					(mid -3.0607 0)
					(end 3.0607 0)
				)
			)
			(stroke
				(width 0)
				(type default)
			)
			(fill no)
			(layer "F.Fab")
		)
		(pad "1" thru_hole circle
			(at 0 0)
			(size 5.5118 5.5118)
			(drill 3.302)
			(layers "*.Cu" "*.Mask")
			(remove_unused_layers no)
			(net "GND")
			(clearance -0.5969)
			(thermal_gap 0.3048)
			(padstack
				(mode front_inner_back)
				(layer "Inner"
					(shape circle)
					(size 3.7084 3.7084)
					(clearance 0.3048)
				)
				(layer "B.Cu"
					(shape circle)
					(size 6.0198 6.0198)
					(clearance -0.8509)
				)
			)
		)
	)
	(footprint ""
		(layer "F.Cu")
		(at 60.694824 -8.457946 90)
		(property "Reference" "C22"
			(at 0 0 90)
			(layer "F.SilkS")
			(hide yes)
			(effects
				(font
					(size 1.27 1.27)
				)
			)
		)
		(property "Value" "SC10U25V6KX-1GP"
			(at -0.0762 -5.1308 90)
			(unlocked yes)
			(layer "F.Fab")
			(hide yes)
			(effects
				(font
					(size 1.016 1.016)
					(thickness 0.1524)
				)
			)
		)
		(property "Device Type" "C1206H71"
			(at -0.127 -6.6548 90)
			(unlocked yes)
			(layer "F.Fab")
			(hide yes)
			(effects
				(font
					(size 1.016 1.016)
					(thickness 0.1524)
				)
			)
		)
		(duplicate_pad_numbers_are_jumpers no)
		(fp_line
			(start 1.016 -2.2352)
			(end 1.016 -0.8382)
			(stroke
				(width 0.1524)
				(type default)
			)
			(layer "F.SilkS")
		)
		(fp_line
			(start -1.016 -2.2352)
			(end 1.016 -2.2352)
			(stroke
				(width 0.1524)
				(type default)
			)
			(layer "F.SilkS")
		)
		(fp_line
			(start -1.016 -0.8382)
			(end -1.016 -2.2352)
			(stroke
				(width 0.1524)
				(type default)
			)
			(layer "F.SilkS")
		)
		(fp_line
			(start 1.016 0.8382)
			(end 1.016 2.2352)
			(stroke
				(width 0.1524)
				(type default)
			)
			(layer "F.SilkS")
		)
		(fp_line
			(start 1.016 2.2352)
			(end -1.016 2.2352)
			(stroke
				(width 0.1524)
				(type default)
			)
			(layer "F.SilkS")
		)
		(fp_line
			(start -1.016 2.2352)
			(end -1.016 0.8382)
			(stroke
				(width 0.1524)
				(type default)
			)
			(layer "F.SilkS")
		)
		(fp_rect
			(start -1.0922 2.3114)
			(end 1.0922 -2.3114)
			(stroke
				(width 0)
				(type default)
			)
			(fill no)
			(layer "F.CrtYd")
		)
		(fp_poly
			(pts
				(xy 1.0922 -2.3114) (xy 1.0922 2.3114) (xy -1.0922 2.3114) (xy -1.0922 -2.3114)
			)
			(stroke
				(width 0)
				(type default)
			)
			(fill no)
			(layer "F.Fab")
		)
		(pad "1" smd rect
			(at 0 -1.397 90)
			(size 1.651 1.27)
			(layers "F.Cu" "F.Mask" "F.Paste")
			(net "P12V_SW_L")
		)
		(pad "2" smd rect
			(at 0 1.397 90)
			(size 1.651 1.27)
			(layers "F.Cu" "F.Mask" "F.Paste")
			(net "GND")
		)
	)
	(footprint ""
		(layer "F.Cu")
		(at 107.145074 -53.01996 180)
		(property "Reference" "SATA1"
			(at 0 0 180)
			(layer "F.SilkS")
			(hide yes)
			(effects
				(font
					(size 1.27 1.27)
				)
			)
		)
		(property "Value" "FCI-CONN29-2R-GP-U"
			(at -35.2552 -14.1859 180)
			(unlocked yes)
			(layer "F.Fab")
			(hide yes)
			(effects
				(font
					(size 1.016 1.016)
					(thickness 0.1524)
				)
			)
		)
		(property "Device Type" "PREFIT-29P-458055-UH395"
			(at -35.2552 -15.7099 180)
			(unlocked yes)
			(layer "F.Fab")
			(hide yes)
			(effects
				(font
					(size 1.016 1.016)
					(thickness 0.1524)
				)
			)
		)
		(duplicate_pad_numbers_are_jumpers no)
		(fp_line
			(start 18.0467 3.0099)
			(end -28.2067 3.0099)
			(stroke
				(width 0.1524)
				(type default)
			)
			(layer "F.SilkS")
		)
		(fp_line
			(start 18.0467 -3.0099)
			(end 18.0467 3.0099)
			(stroke
				(width 0.1524)
				(type default)
			)
			(layer "F.SilkS")
		)
		(fp_line
			(start -28.2067 3.0099)
			(end -28.2067 -3.0099)
			(stroke
				(width 0.1524)
				(type default)
			)
			(layer "F.SilkS")
		)
		(fp_line
			(start -28.2067 -3.0099)
			(end 18.0467 -3.0099)
			(stroke
				(width 0.1524)
				(type default)
			)
			(layer "F.SilkS")
		)
		(fp_poly
			(pts
				(xy -28.2067 3.0099) (xy -28.2067 -3.0099) (xy -21.9202 -3.0099) (xy -21.9202 -1.4478) (xy -28.1305 -1.4478)
				(xy -28.1305 1.4478) (xy -10.6934 1.4478) (xy -10.6934 -0.381) (xy -3.0607 -0.381) (xy -3.0607 2.4384)
				(xy 3.1115 2.4384) (xy 3.1115 1.4478) (xy 17.9705 1.4478) (xy 17.9705 -1.4351) (xy 11.7602 -1.4351)
				(xy 11.7602 -2.2098) (xy -2.2606 -2.2098) (xy -2.2606 -3.0099) (xy 18.0467 -3.0099) (xy 18.0467 3.0099)
			)
			(stroke
				(width 0)
				(type default)
			)
			(fill yes)
			(layer "F.SilkS")
		)
		(fp_poly
			(pts
				(arc
					(start 2.2098 1.25095)
					(mid 2.0828 1.12395)
					(end 2.2098 0.99695)
				)
				(arc
					(start 2.5908 0.99695)
					(mid 2.7178 1.12395)
					(end 2.5908 1.25095)
				)
			)
			(stroke
				(width 0)
				(type default)
			)
			(fill yes)
			(layer "F.SilkS")
		)
		(fp_poly
			(pts
				(arc
					(start 1.4097 1.25095)
					(mid 1.2827 1.12395)
					(end 1.4097 0.99695)
				)
				(arc
					(start 1.7907 0.99695)
					(mid 1.9177 1.12395)
					(end 1.7907 1.25095)
				)
			)
			(stroke
				(width 0)
				(type default)
			)
			(fill yes)
			(layer "F.SilkS")
		)
		(fp_poly
			(pts
				(arc
					(start 0.6096 1.25095)
					(mid 0.4826 1.12395)
					(end 0.6096 0.99695)
				)
				(arc
					(start 0.9906 0.99695)
					(mid 1.1176 1.12395)
					(end 0.9906 1.25095)
				)
			)
			(stroke
				(width 0)
				(type default)
			)
			(fill yes)
			(layer "F.SilkS")
		)
		(fp_poly
			(pts
				(arc
					(start -0.1905 1.25095)
					(mid -0.3175 1.12395)
					(end -0.1905 0.99695)
				)
				(arc
					(start 0.1905 0.99695)
					(mid 0.3175 1.12395)
					(end 0.1905 1.25095)
				)
			)
			(stroke
				(width 0)
				(type default)
			)
			(fill yes)
			(layer "F.SilkS")
		)
		(fp_poly
			(pts
				(arc
					(start -0.9906 1.25095)
					(mid -1.1176 1.12395)
					(end -0.9906 0.99695)
				)
				(arc
					(start -0.6096 0.99695)
					(mid -0.4826 1.12395)
					(end -0.6096 1.25095)
				)
			)
			(stroke
				(width 0)
				(type default)
			)
			(fill yes)
			(layer "F.SilkS")
		)
		(fp_poly
			(pts
				(arc
					(start -1.7907 1.25095)
					(mid -1.9177 1.12395)
					(end -1.7907 0.99695)
				)
				(arc
					(start -1.4097 0.99695)
					(mid -1.2827 1.12395)
					(end -1.4097 1.25095)
				)
			)
			(stroke
				(width 0)
				(type default)
			)
			(fill yes)
			(layer "F.SilkS")
		)
		(fp_poly
			(pts
				(arc
					(start -2.5908 1.25095)
					(mid -2.7178 1.12395)
					(end -2.5908 0.99695)
				)
				(arc
					(start -2.2098 0.99695)
					(mid -2.0828 1.12395)
					(end -2.2098 1.25095)
				)
			)
			(stroke
				(width 0)
				(type default)
			)
			(fill yes)
			(layer "F.SilkS")
		)
		(fp_poly
			(pts
				(arc
					(start 10.4902 0.2032)
					(mid 10.287 0)
					(end 10.4902 -0.2032)
				)
				(arc
					(start 11.0998 -0.2032)
					(mid 11.303 0)
					(end 11.0998 0.2032)
				)
			)
			(stroke
				(width 0)
				(type default)
			)
			(fill yes)
			(layer "F.SilkS")
		)
		(fp_poly
			(pts
				(arc
					(start 9.2202 0.2032)
					(mid 9.017 0)
					(end 9.2202 -0.2032)
				)
				(arc
					(start 9.8298 -0.2032)
					(mid 10.033 0)
					(end 9.8298 0.2032)
				)
			)
			(stroke
				(width 0)
				(type default)
			)
			(fill yes)
			(layer "F.SilkS")
		)
		(fp_poly
			(pts
				(arc
					(start 7.9502 0.2032)
					(mid 7.747 0)
					(end 7.9502 -0.2032)
				)
				(arc
					(start 8.5598 -0.2032)
					(mid 8.763 0)
					(end 8.5598 0.2032)
				)
			)
			(stroke
				(width 0)
				(type default)
			)
			(fill yes)
			(layer "F.SilkS")
		)
		(fp_poly
			(pts
				(arc
					(start 6.6802 0.2032)
					(mid 6.477 0)
					(end 6.6802 -0.2032)
				)
				(arc
					(start 7.2898 -0.2032)
					(mid 7.493 0)
					(end 7.2898 0.2032)
				)
			)
			(stroke
				(width 0)
				(type default)
			)
			(fill yes)
			(layer "F.SilkS")
		)
		(fp_poly
			(pts
				(arc
					(start 5.4102 0.2032)
					(mid 5.207 0)
					(end 5.4102 -0.2032)
				)
				(arc
					(start 6.0198 -0.2032)
					(mid 6.223 0)
					(end 6.0198 0.2032)
				)
			)
			(stroke
				(width 0)
				(type default)
			)
			(fill yes)
			(layer "F.SilkS")
		)
		(fp_poly
			(pts
				(arc
					(start 4.1402 0.2032)
					(mid 3.937 0)
					(end 4.1402 -0.2032)
				)
				(arc
					(start 4.7498 -0.2032)
					(mid 4.953 0)
					(end 4.7498 0.2032)
				)
			)
			(stroke
				(width 0)
				(type default)
			)
			(fill yes)
			(layer "F.SilkS")
		)
		(fp_poly
			(pts
				(arc
					(start 2.8702 0.2032)
					(mid 2.667 0)
					(end 2.8702 -0.2032)
				)
				(arc
					(start 3.4798 -0.2032)
					(mid 3.683 0)
					(end 3.4798 0.2032)
				)
			)
			(stroke
				(width 0)
				(type default)
			)
			(fill yes)
			(layer "F.SilkS")
		)
		(fp_poly
			(pts
				(arc
					(start -3.4798 -2.4638)
					(mid -3.683 -2.667)
					(end -3.4798 -2.8702)
				)
				(arc
					(start -2.8702 -2.8702)
					(mid -2.667 -2.667)
					(end -2.8702 -2.4638)
				)
			)
			(stroke
				(width 0)
				(type default)
			)
			(fill yes)
			(layer "F.SilkS")
		)
		(fp_poly
			(pts
				(arc
					(start -4.7498 -2.4638)
					(mid -4.953 -2.667)
					(end -4.7498 -2.8702)
				)
				(arc
					(start -4.1402 -2.8702)
					(mid -3.937 -2.667)
					(end -4.1402 -2.4638)
				)
			)
			(stroke
				(width 0)
				(type default)
			)
			(fill yes)
			(layer "F.SilkS")
		)
		(fp_poly
			(pts
				(arc
					(start -6.0198 -2.4638)
					(mid -6.223 -2.667)
					(end -6.0198 -2.8702)
				)
				(arc
					(start -5.4102 -2.8702)
					(mid -5.207 -2.667)
					(end -5.4102 -2.4638)
				)
			)
			(stroke
				(width 0)
				(type default)
			)
			(fill yes)
			(layer "F.SilkS")
		)
		(fp_poly
			(pts
				(arc
					(start -7.2898 -2.4638)
					(mid -7.493 -2.667)
					(end -7.2898 -2.8702)
				)
				(arc
					(start -6.6802 -2.8702)
					(mid -6.477 -2.667)
					(end -6.6802 -2.4638)
				)
			)
			(stroke
				(width 0)
				(type default)
			)
			(fill yes)
			(layer "F.SilkS")
		)
		(fp_poly
			(pts
				(arc
					(start -8.5598 -2.4638)
					(mid -8.763 -2.667)
					(end -8.5598 -2.8702)
				)
				(arc
					(start -7.9502 -2.8702)
					(mid -7.747 -2.667)
					(end -7.9502 -2.4638)
				)
			)
			(stroke
				(width 0)
				(type default)
			)
			(fill yes)
			(layer "F.SilkS")
		)
		(fp_poly
			(pts
				(arc
					(start -9.8298 -2.4638)
					(mid -10.033 -2.667)
					(end -9.8298 -2.8702)
				)
				(arc
					(start -9.2202 -2.8702)
					(mid -9.017 -2.667)
					(end -9.2202 -2.4638)
				)
			)
			(stroke
				(width 0)
				(type default)
			)
			(fill yes)
			(layer "F.SilkS")
		)
		(fp_poly
			(pts
				(arc
					(start -11.0998 -2.4638)
					(mid -11.303 -2.667)
					(end -11.0998 -2.8702)
				)
				(arc
					(start -10.4902 -2.8702)
					(mid -10.287 -2.667)
					(end -10.4902 -2.4638)
				)
			)
			(stroke
				(width 0)
				(type default)
			)
			(fill yes)
			(layer "F.SilkS")
		)
		(fp_poly
			(pts
				(arc
					(start -12.3698 -2.4638)
					(mid -12.573 -2.667)
					(end -12.3698 -2.8702)
				)
				(arc
					(start -11.7602 -2.8702)
					(mid -11.557 -2.667)
					(end -11.7602 -2.4638)
				)
			)
			(stroke
				(width 0)
				(type default)
			)
			(fill yes)
			(layer "F.SilkS")
		)
		(fp_poly
			(pts
				(arc
					(start -13.6398 -2.4638)
					(mid -13.843 -2.667)
					(end -13.6398 -2.8702)
				)
				(arc
					(start -13.0302 -2.8702)
					(mid -12.827 -2.667)
					(end -13.0302 -2.4638)
				)
			)
			(stroke
				(width 0)
				(type default)
			)
			(fill yes)
			(layer "F.SilkS")
		)
		(fp_poly
			(pts
				(arc
					(start -14.9098 -2.4638)
					(mid -15.113 -2.667)
					(end -14.9098 -2.8702)
				)
				(arc
					(start -14.3002 -2.8702)
					(mid -14.097 -2.667)
					(end -14.3002 -2.4638)
				)
			)
			(stroke
				(width 0)
				(type default)
			)
			(fill yes)
			(layer "F.SilkS")
		)
		(fp_poly
			(pts
				(arc
					(start -16.1798 -2.4638)
					(mid -16.383 -2.667)
					(end -16.1798 -2.8702)
				)
				(arc
					(start -15.5702 -2.8702)
					(mid -15.367 -2.667)
					(end -15.5702 -2.4638)
				)
			)
			(stroke
				(width 0)
				(type default)
			)
			(fill yes)
			(layer "F.SilkS")
		)
		(fp_poly
			(pts
				(arc
					(start -17.4498 -2.4638)
					(mid -17.653 -2.667)
					(end -17.4498 -2.8702)
				)
				(arc
					(start -16.8402 -2.8702)
					(mid -16.637 -2.667)
					(end -16.8402 -2.4638)
				)
			)
			(stroke
				(width 0)
				(type default)
			)
			(fill yes)
			(layer "F.SilkS")
		)
		(fp_poly
			(pts
				(arc
					(start -18.7198 -2.4638)
					(mid -18.923 -2.667)
					(end -18.7198 -2.8702)
				)
				(arc
					(start -18.1102 -2.8702)
					(mid -17.907 -2.667)
					(end -18.1102 -2.4638)
				)
			)
			(stroke
				(width 0)
				(type default)
			)
			(fill yes)
			(layer "F.SilkS")
		)
		(fp_poly
			(pts
				(arc
					(start -19.9898 -2.4638)
					(mid -20.193 -2.667)
					(end -19.9898 -2.8702)
				)
				(arc
					(start -19.3802 -2.8702)
					(mid -19.177 -2.667)
					(end -19.3802 -2.4638)
				)
			)
			(stroke
				(width 0)
				(type default)
			)
			(fill yes)
			(layer "F.SilkS")
		)
		(fp_poly
			(pts
				(arc
					(start -21.2598 -2.4638)
					(mid -21.463 -2.667)
					(end -21.2598 -2.8702)
				)
				(arc
					(start -20.6502 -2.8702)
					(mid -20.447 -2.667)
					(end -20.6502 -2.4638)
				)
			)
			(stroke
				(width 0)
				(type default)
			)
			(fill yes)
			(layer "F.SilkS")
		)
		(fp_poly
			(pts
				(arc
					(start 17.87525 0.6096)
					(mid 17.57045 0.9144)
					(end 17.26565 0.6096)
				)
				(arc
					(start 17.26565 -0.6096)
					(mid 17.57045 -0.9144)
					(end 17.87525 -0.6096)
				)
			)
			(stroke
				(width 0)
				(type default)
			)
			(fill yes)
			(layer "F.SilkS")
		)
		(fp_poly
			(pts
				(arc
					(start -27.42565 0.6096)
					(mid -27.73045 0.9144)
					(end -28.03525 0.6096)
				)
				(arc
					(start -28.03525 -0.6096)
					(mid -27.73045 -0.9144)
					(end -27.42565 -0.6096)
				)
			)
			(stroke
				(width 0)
				(type default)
			)
			(fill yes)
			(layer "F.SilkS")
		)
		(fp_rect
			(start -32.2707 7.5438)
			(end 22.1107 -6.7056)
			(stroke
				(width 0)
				(type default)
			)
			(fill no)
			(layer "B.CrtYd")
		)
		(fp_rect
			(start -27.9527 2.7559)
			(end 17.7927 -2.7559)
			(stroke
				(width 0)
				(type default)
			)
			(fill no)
			(layer "F.CrtYd")
		)
		(fp_poly
			(pts
				(xy -28.4607 3.2639) (xy -28.4607 -3.2639) (xy 18.3007 -3.2639) (xy 18.3007 2.7051) (xy 17.7927 2.7051)
				(xy 17.7927 -2.7559) (xy -27.9527 -2.7559) (xy -27.9527 2.7559) (xy 17.7927 2.7559) (xy 17.7927 2.7178)
				(xy 18.3007 2.7178) (xy 18.3007 3.2639)
			)
			(stroke
				(width 0)
				(type default)
			)
			(fill no)
			(layer "F.CrtYd")
		)
		(fp_poly
			(pts
				(xy -32.9565 7.7597) (xy -32.9565 -7.7597) (xy 22.7965 -7.7597) (xy 22.7965 2.7051) (xy 18.3007 2.7051)
				(xy 18.3007 -3.2639) (xy -28.4607 -3.2639) (xy -28.4607 3.2639) (xy 18.3007 3.2639) (xy 18.3007 2.7178)
				(xy 22.7965 2.7178) (xy 22.7965 7.7597)
			)
			(stroke
				(width 0)
				(type default)
			)
			(fill no)
			(layer "F.CrtYd")
		)
		(fp_rect
			(start -32.2707 7.5438)
			(end 22.1107 -6.7056)
			(stroke
				(width 0)
				(type default)
			)
			(fill no)
			(layer "B.Fab")
		)
		(fp_rect
			(start -37.2745 12.5476)
			(end 27.1145 -11.7094)
			(stroke
				(width 0)
				(type default)
			)
			(fill no)
			(layer "B.Fab")
		)
		(fp_rect
			(start -28.4607 3.2639)
			(end 18.3007 -3.2639)
			(stroke
				(width 0)
				(type default)
			)
			(fill no)
			(layer "F.Fab")
		)
		(fp_rect
			(start -32.9565 7.7597)
			(end 22.7965 -7.7597)
			(stroke
				(width 0)
				(type default)
			)
			(fill no)
			(layer "F.Fab")
		)
		(fp_rect
			(start -37.9603 12.7635)
			(end 27.8003 -12.7635)
			(stroke
				(width 0)
				(type default)
			)
			(fill no)
			(layer "F.Fab")
		)
		(fp_text user "Press Fit"
			(at -21.3614 0.5715 180)
			(unlocked yes)
			(layer "F.SilkS")
			(effects
				(font
					(size 1.016 1.016)
					(thickness 0.1524)
				)
				(justify left)
			)
		)
		(fp_text user "Can not place BGA,CSP,Wave Solder Comonent."
			(at -28.9433 10.1219 180)
			(unlocked yes)
			(layer "B.Fab")
			(effects
				(font
					(size 1.016 1.016)
					(thickness 0.1524)
				)
				(justify left)
			)
		)
		(fp_text user "High Limit 2mm"
			(at -13.8811 6.6421 180)
			(unlocked yes)
			(layer "F.Fab")
			(effects
				(font
					(size 1.016 1.016)
					(thickness 0.1524)
				)
				(justify left)
			)
		)
		(fp_text user "Can not place BGA,CSP,Wave Solder Comonent."
			(at -28.9433 10.1219 180)
			(unlocked yes)
			(layer "F.Fab")
			(effects
				(font
					(size 1.016 1.016)
					(thickness 0.1524)
				)
				(justify left)
			)
		)
		(pad "" np_thru_hole circle
			(at -23.95474 0 180)
			(size 0.254 0.254)
			(drill 1.3462)
			(layers "*.Cu" "*.Mask")
			(clearance 0.9017)
			(thermal_gap 0.9017)
		)
		(pad "30" thru_hole circle
			(at -26.07945 0 180)
			(size 2.3622 2.3622)
			(drill 1.949958)
			(layers "*.Cu" "*.Mask")
			(remove_unused_layers no)
			(net "Net_83")
			(clearance 0.1524)
			(thermal_gap 0.1524)
		)
		(pad "31" thru_hole circle
			(at 15.91945 0 180)
			(size 2.3622 2.3622)
			(drill 1.949958)
			(layers "*.Cu" "*.Mask")
			(remove_unused_layers no)
			(net "Net_74")
			(clearance 0.1524)
			(thermal_gap 0.1524)
		)
		(pad "P1" thru_hole circle
			(at -3.175 -1.27 180)
			(size 0.8636 0.8636)
			(drill 0.499872)
			(layers "*.Cu" "*.Mask")
			(remove_unused_layers no)
			(net "Net_79")
			(clearance 0.1778)
			(thermal_gap 0.1778)
		)
		(pad "P2" thru_hole circle
			(at -4.445 -1.27 180)
			(size 0.8636 0.8636)
			(drill 0.499872)
			(layers "*.Cu" "*.Mask")
			(remove_unused_layers no)
			(net "Net_81")
			(clearance 0.1778)
			(thermal_gap 0.1778)
		)
		(pad "P3" thru_hole circle
			(at -5.715 -1.27 180)
			(size 0.8636 0.8636)
			(drill 0.499872)
			(layers "*.Cu" "*.Mask")
			(remove_unused_layers no)
			(net "Net_80")
			(clearance 0.1778)
			(thermal_gap 0.1778)
		)
		(pad "P4" thru_hole circle
			(at -6.985 -1.27 180)
			(size 0.8636 0.8636)
			(drill 0.499872)
			(layers "*.Cu" "*.Mask")
			(remove_unused_layers no)
			(net "GND")
			(clearance 0.1778)
			(thermal_gap 0.1778)
		)
		(pad "P5" thru_hole circle
			(at -8.255 -1.27 180)
			(size 0.8636 0.8636)
			(drill 0.499872)
			(layers "*.Cu" "*.Mask")
			(remove_unused_layers no)
			(net "GND")
			(clearance 0.1778)
			(thermal_gap 0.1778)
		)
		(pad "P6" thru_hole circle
			(at -9.525 -1.27 180)
			(size 0.8636 0.8636)
			(drill 0.499872)
			(layers "*.Cu" "*.Mask")
			(remove_unused_layers no)
			(net "GND")
			(clearance 0.1778)
			(thermal_gap 0.1778)
		)
		(pad "P7" thru_hole circle
			(at -10.795 -1.27 180)
			(size 0.8636 0.8636)
			(drill 0.499872)
			(layers "*.Cu" "*.Mask")
			(remove_unused_layers no)
			(net "5V_PRE_0")
			(clearance 0.1778)
			(thermal_gap 0.1778)
		)
		(pad "P8" thru_hole circle
			(at -12.065 -1.27 180)
			(size 0.8636 0.8636)
			(drill 0.499872)
			(layers "*.Cu" "*.Mask")
			(remove_unused_layers no)
			(net "P5V_SW_R")
			(clearance 0.1778)
			(thermal_gap 0.1778)
		)
		(pad "P9" thru_hole circle
			(at -13.335 -1.27 180)
			(size 0.8636 0.8636)
			(drill 0.499872)
			(layers "*.Cu" "*.Mask")
			(remove_unused_layers no)
			(net "P5V_SW_R")
			(clearance 0.1778)
			(thermal_gap 0.1778)
		)
		(pad "P10" thru_hole circle
			(at -14.605 -1.27 180)
			(size 0.8636 0.8636)
			(drill 0.499872)
			(layers "*.Cu" "*.Mask")
			(remove_unused_layers no)
			(net "HBA_PRSNT0_N")
			(clearance 0.1778)
			(thermal_gap 0.1778)
		)
		(pad "P11" thru_hole circle
			(at -15.875 -1.27 180)
			(size 0.8636 0.8636)
			(drill 0.499872)
			(layers "*.Cu" "*.Mask")
			(remove_unused_layers no)
			(net "HDD_ACT_LED0")
			(clearance 0.1778)
			(thermal_gap 0.1778)
		)
		(pad "P12" thru_hole circle
			(at -17.145 -1.27 180)
			(size 0.8636 0.8636)
			(drill 0.499872)
			(layers "*.Cu" "*.Mask")
			(remove_unused_layers no)
			(net "GND")
			(clearance 0.1778)
			(thermal_gap 0.1778)
		)
		(pad "P13" thru_hole circle
			(at -18.415 -1.27 180)
			(size 0.8636 0.8636)
			(drill 0.499872)
			(layers "*.Cu" "*.Mask")
			(remove_unused_layers no)
			(net "12V_PRE_0")
			(clearance 0.1778)
			(thermal_gap 0.1778)
		)
		(pad "P14" thru_hole circle
			(at -19.685 -1.27 180)
			(size 0.8636 0.8636)
			(drill 0.499872)
			(layers "*.Cu" "*.Mask")
			(remove_unused_layers no)
			(net "P12V_SW_R")
			(clearance 0.1778)
			(thermal_gap 0.1778)
		)
		(pad "P15" thru_hole circle
			(at -20.955 -1.27 180)
			(size 0.8636 0.8636)
			(drill 0.499872)
			(layers "*.Cu" "*.Mask")
			(remove_unused_layers no)
			(net "P12V_SW_R")
			(clearance 0.1778)
			(thermal_gap 0.1778)
		)
		(pad "S1" thru_hole circle
			(at 10.795 -1.27 180)
			(size 0.8636 0.8636)
			(drill 0.499872)
			(layers "*.Cu" "*.Mask")
			(remove_unused_layers no)
			(net "GND")
			(clearance 0.1778)
			(thermal_gap 0.1778)
		)
		(pad "S2" thru_hole circle
			(at 9.525 -1.27 180)
			(size 0.8636 0.8636)
			(drill 0.499872)
			(layers "*.Cu" "*.Mask")
			(remove_unused_layers no)
			(net "HBA_MB_TX_P0")
			(clearance 0.1778)
			(thermal_gap 0.1778)
		)
		(pad "S3" thru_hole circle
			(at 8.255 -1.27 180)
			(size 0.8636 0.8636)
			(drill 0.499872)
			(layers "*.Cu" "*.Mask")
			(remove_unused_layers no)
			(net "HBA_MB_TX_N0")
			(clearance 0.1778)
			(thermal_gap 0.1778)
		)
		(pad "S4" thru_hole circle
			(at 6.985 -1.27 180)
			(size 0.8636 0.8636)
			(drill 0.499872)
			(layers "*.Cu" "*.Mask")
			(remove_unused_layers no)
			(net "GND")
			(clearance 0.1778)
			(thermal_gap 0.1778)
		)
		(pad "S5" thru_hole circle
			(at 5.715 -1.27 180)
			(size 0.8636 0.8636)
			(drill 0.499872)
			(layers "*.Cu" "*.Mask")
			(remove_unused_layers no)
			(net "HBA_MB_RX_N0")
			(clearance 0.1778)
			(thermal_gap 0.1778)
		)
		(pad "S6" thru_hole circle
			(at 4.445 -1.27 180)
			(size 0.8636 0.8636)
			(drill 0.499872)
			(layers "*.Cu" "*.Mask")
			(remove_unused_layers no)
			(net "HBA_MB_RX_P0")
			(clearance 0.1778)
			(thermal_gap 0.1778)
		)
		(pad "S7" thru_hole circle
			(at 3.175 -1.27 180)
			(size 0.8636 0.8636)
			(drill 0.499872)
			(layers "*.Cu" "*.Mask")
			(remove_unused_layers no)
			(net "GND")
			(clearance 0.1778)
			(thermal_gap 0.1778)
		)
		(pad "S8" thru_hole oval
			(at 2.4003 2.13995 180)
			(size 0.6096 0.8128)
			(drill 0.399796)
			(layers "*.Cu" "*.Mask")
			(remove_unused_layers no)
			(net "GND")
			(clearance 0.254)
			(thermal_gap 0.254)
		)
		(pad "S9" thru_hole oval
			(at 1.6002 2.13995 180)
			(size 0.6096 0.8128)
			(drill 0.399796)
			(layers "*.Cu" "*.Mask")
			(remove_unused_layers no)
			(net "Net_78")
			(clearance 0.254)
			(thermal_gap 0.254)
		)
		(pad "S10" thru_hole oval
			(at 0.8001 2.13995 180)
			(size 0.6096 0.8128)
			(drill 0.399796)
			(layers "*.Cu" "*.Mask")
			(remove_unused_layers no)
			(net "Net_77")
			(clearance 0.254)
			(thermal_gap 0.254)
		)
		(pad "S11" thru_hole oval
			(at 0 2.13995 180)
			(size 0.6096 0.8128)
			(drill 0.399796)
			(layers "*.Cu" "*.Mask")
			(remove_unused_layers no)
			(net "Net_40")
			(clearance 0.254)
			(thermal_gap 0.254)
		)
		(pad "S12" thru_hole oval
			(at -0.8001 2.13995 180)
			(size 0.6096 0.8128)
			(drill 0.399796)
			(layers "*.Cu" "*.Mask")
			(remove_unused_layers no)
			(net "Net_76")
			(clearance 0.254)
			(thermal_gap 0.254)
		)
		(pad "S13" thru_hole oval
			(at -1.6002 2.13995 180)
			(size 0.6096 0.8128)
			(drill 0.399796)
			(layers "*.Cu" "*.Mask")
			(remove_unused_layers no)
			(net "Net_75")
			(clearance 0.254)
			(thermal_gap 0.254)
		)
		(pad "S14" thru_hole oval
			(at -2.4003 2.13995 180)
			(size 0.6096 0.8128)
			(drill 0.399796)
			(layers "*.Cu" "*.Mask")
			(remove_unused_layers no)
			(net "GND")
			(clearance 0.254)
			(thermal_gap 0.254)
		)
		(zone
			(layers "F.Cu" "B.Cu" "In1.Cu" "In2.Cu" "In3.Cu" "In4.Cu")
			(hatch none 0.5)
			(connect_pads
				(clearance 0)
			)
			(min_thickness 0.25)
			(keepout
				(tracks not_allowed)
				(vias allowed)
				(pads allowed)
				(copperpour not_allowed)
				(footprints allowed)
			)
			(placement
				(enabled no)
				(sheetname "")
			)
			(fill
				(thermal_gap 0.5)
				(thermal_bridge_width 0.5)
				(island_removal_mode 0)
			)
			(polygon
				(pts
					(arc
						(start 132.077714 -53.01996)
						(mid 130.121914 -53.01996)
						(end 132.077714 -53.01996)
					)
				)
			)
		)
	)
	(footprint ""
		(layer "F.Cu")
		(at 77.0001 -3.50012)
		(property "Reference" "H5"
			(at 0 0 0)
			(layer "F.SilkS")
			(hide yes)
			(effects
				(font
					(size 1.27 1.27)
				)
			)
		)
		(property "Value" "HOLET217B237R130-GP"
			(at -5.08 -0.4572 0)
			(unlocked yes)
			(layer "F.Fab")
			(hide yes)
			(effects
				(font
					(size 1.016 1.016)
					(thickness 0.1524)
				)
			)
		)
		(property "Device Type" "HOLET217B237R130"
			(at -5.08 -1.9812 0)
			(unlocked yes)
			(layer "F.Fab")
			(hide yes)
			(effects
				(font
					(size 1.016 1.016)
					(thickness 0.1524)
				)
			)
		)
		(duplicate_pad_numbers_are_jumpers no)
		(fp_poly
			(pts
				(arc
					(start 3.3147 0)
					(mid -3.3147 0)
					(end 3.3147 0)
				)
			)
			(stroke
				(width 0)
				(type default)
			)
			(fill no)
			(layer "B.CrtYd")
		)
		(fp_poly
			(pts
				(arc
					(start 3.0607 0)
					(mid -3.0607 0)
					(end 3.0607 0)
				)
			)
			(stroke
				(width 0)
				(type default)
			)
			(fill no)
			(layer "F.CrtYd")
		)
		(fp_poly
			(pts
				(arc
					(start 3.3147 0)
					(mid -3.3147 0)
					(end 3.3147 0)
				)
			)
			(stroke
				(width 0)
				(type default)
			)
			(fill no)
			(layer "B.Fab")
		)
		(fp_poly
			(pts
				(arc
					(start 3.0607 0)
					(mid -3.0607 0)
					(end 3.0607 0)
				)
			)
			(stroke
				(width 0)
				(type default)
			)
			(fill no)
			(layer "F.Fab")
		)
		(pad "1" thru_hole circle
			(at 0 0)
			(size 5.5118 5.5118)
			(drill 3.302)
			(layers "*.Cu" "*.Mask")
			(remove_unused_layers no)
			(net "GND")
			(clearance -0.5969)
			(thermal_gap 0.3048)
			(padstack
				(mode front_inner_back)
				(layer "Inner"
					(shape circle)
					(size 3.7084 3.7084)
					(clearance 0.3048)
				)
				(layer "B.Cu"
					(shape circle)
					(size 6.0198 6.0198)
					(clearance -0.8509)
				)
			)
		)
	)
	(footprint ""
		(layer "F.Cu")
		(at 55.78602 -20.158456 -90)
		(property "Reference" "C21"
			(at 0 0 270)
			(layer "F.SilkS")
			(hide yes)
			(effects
				(font
					(size 1.27 1.27)
				)
			)
		)
		(property "Value" "SCD1U25V2KX-GP"
			(at 1.1811 -2.7051 270)
			(unlocked yes)
			(layer "F.Fab")
			(hide yes)
			(effects
				(font
					(size 1.016 1.016)
					(thickness 0.1524)
				)
			)
		)
		(property "Device Type" "C402H22"
			(at 1.1811 -4.2291 270)
			(unlocked yes)
			(layer "F.Fab")
			(hide yes)
			(effects
				(font
					(size 1.016 1.016)
					(thickness 0.1524)
				)
			)
		)
		(duplicate_pad_numbers_are_jumpers no)
		(fp_rect
			(start -0.4318 0.9525)
			(end 0.4318 -0.9525)
			(stroke
				(width 0)
				(type default)
			)
			(fill no)
			(layer "F.CrtYd")
		)
		(fp_rect
			(start -0.4318 0.9525)
			(end 0.4318 -0.9525)
			(stroke
				(width 0)
				(type default)
			)
			(fill no)
			(layer "F.Fab")
		)
		(pad "1" smd custom
			(at 0 -0.4445 270)
			(size 0.1524 0.1524)
			(layers "F.Cu" "F.Mask" "F.Paste")
			(net "P12V_SW_L")
			(options
				(clearance outline)
				(anchor circle)
			)
			(primitives
				(gr_poly
					(pts
						(arc
							(start 0.3048 -0.2032)
							(mid 0.275042 -0.275042)
							(end 0.2032 -0.3048)
						)
						(arc
							(start -0.2032 -0.3048)
							(mid -0.275042 -0.275042)
							(end -0.3048 -0.2032)
						)
						(arc
							(start -0.3048 0.2032)
							(mid -0.275042 0.275042)
							(end -0.2032 0.3048)
						)
						(arc
							(start 0.2032 0.3048)
							(mid 0.275042 0.275042)
							(end 0.3048 0.2032)
						)
					)
					(width 0)
					(fill yes)
				)
			)
		)
		(pad "2" smd custom
			(at 0 0.4445 270)
			(size 0.1524 0.1524)
			(layers "F.Cu" "F.Mask" "F.Paste")
			(net "GND")
			(options
				(clearance outline)
				(anchor circle)
			)
			(primitives
				(gr_poly
					(pts
						(arc
							(start 0.3048 -0.2032)
							(mid 0.275042 -0.275042)
							(end 0.2032 -0.3048)
						)
						(arc
							(start -0.2032 -0.3048)
							(mid -0.275042 -0.275042)
							(end -0.3048 -0.2032)
						)
						(arc
							(start -0.3048 0.2032)
							(mid -0.275042 0.275042)
							(end -0.2032 0.3048)
						)
						(arc
							(start 0.2032 0.3048)
							(mid 0.275042 0.275042)
							(end 0.3048 0.2032)
						)
					)
					(width 0)
					(fill yes)
				)
			)
		)
	)
	(footprint ""
		(layer "F.Cu")
		(at 85.852 -5.08 90)
		(property "Reference" "R147"
			(at 0 0 90)
			(layer "F.SilkS")
			(hide yes)
			(effects
				(font
					(size 1.27 1.27)
				)
			)
		)
		(property "Value" "4K7R2J-2-GP"
			(at 0.064008 -3.993896 90)
			(unlocked yes)
			(layer "F.Fab")
			(hide yes)
			(effects
				(font
					(size 1.016 1.016)
					(thickness 0.1524)
				)
			)
		)
		(property "Device Type" "R402H16"
			(at 0.064008 -5.517896 90)
			(unlocked yes)
			(layer "F.Fab")
			(hide yes)
			(effects
				(font
					(size 1.016 1.016)
					(thickness 0.1524)
				)
			)
		)
		(duplicate_pad_numbers_are_jumpers no)
		(fp_line
			(start 0.508 -0.9398)
			(end -0.508 -0.9398)
			(stroke
				(width 0.1524)
				(type default)
			)
			(layer "F.SilkS")
		)
		(fp_line
			(start -0.508 -0.9398)
			(end -0.508 0.9398)
			(stroke
				(width 0.1524)
				(type default)
			)
			(layer "F.SilkS")
		)
		(fp_rect
			(start -0.508 0.9398)
			(end 0.508 -0.9398)
			(stroke
				(width 0)
				(type default)
			)
			(fill no)
			(layer "F.CrtYd")
		)
		(fp_rect
			(start -0.508 0.9398)
			(end 0.508 -0.9398)
			(stroke
				(width 0)
				(type default)
			)
			(fill no)
			(layer "F.Fab")
		)
		(pad "1" smd custom
			(at 0 -0.4445 90)
			(size 0.1397 0.1397)
			(layers "F.Cu" "F.Mask" "F.Paste")
			(net "P3V3")
			(options
				(clearance outline)
				(anchor circle)
			)
			(primitives
				(gr_poly
					(pts
						(arc
							(start -0.1778 -0.2794)
							(mid -0.249642 -0.249642)
							(end -0.2794 -0.1778)
						)
						(arc
							(start -0.2794 0.1778)
							(mid -0.249642 0.249642)
							(end -0.1778 0.2794)
						)
						(arc
							(start 0.1778 0.2794)
							(mid 0.249642 0.249642)
							(end 0.2794 0.1778)
						)
						(arc
							(start 0.2794 -0.1778)
							(mid 0.249642 -0.249642)
							(end 0.1778 -0.2794)
						)
					)
					(width 0)
					(fill yes)
				)
			)
		)
		(pad "2" smd custom
			(at 0 0.4445 90)
			(size 0.1397 0.1397)
			(layers "F.Cu" "F.Mask" "F.Paste")
			(net "PWR_EN_D_2")
			(options
				(clearance outline)
				(anchor circle)
			)
			(primitives
				(gr_poly
					(pts
						(arc
							(start -0.1778 -0.2794)
							(mid -0.249642 -0.249642)
							(end -0.2794 -0.1778)
						)
						(arc
							(start -0.2794 0.1778)
							(mid -0.249642 0.249642)
							(end -0.1778 0.2794)
						)
						(arc
							(start 0.1778 0.2794)
							(mid 0.249642 0.249642)
							(end 0.2794 0.1778)
						)
						(arc
							(start 0.2794 -0.1778)
							(mid 0.249642 -0.249642)
							(end 0.1778 -0.2794)
						)
					)
					(width 0)
					(fill yes)
				)
			)
		)
	)
	(footprint ""
		(layer "F.Cu")
		(at 81.520284 -11.335766 180)
		(property "Reference" "PC2"
			(at 0 0 180)
			(layer "F.SilkS")
			(hide yes)
			(effects
				(font
					(size 1.27 1.27)
				)
			)
		)
		(property "Value" "SCD1U25V2KX-GP"
			(at 1.1811 -2.7051 180)
			(unlocked yes)
			(layer "F.Fab")
			(hide yes)
			(effects
				(font
					(size 1.016 1.016)
					(thickness 0.1524)
				)
			)
		)
		(property "Device Type" "C402H22"
			(at 1.1811 -4.2291 180)
			(unlocked yes)
			(layer "F.Fab")
			(hide yes)
			(effects
				(font
					(size 1.016 1.016)
					(thickness 0.1524)
				)
			)
		)
		(duplicate_pad_numbers_are_jumpers no)
		(fp_rect
			(start -0.4318 0.9525)
			(end 0.4318 -0.9525)
			(stroke
				(width 0)
				(type default)
			)
			(fill no)
			(layer "F.CrtYd")
		)
		(fp_rect
			(start -0.4318 0.9525)
			(end 0.4318 -0.9525)
			(stroke
				(width 0)
				(type default)
			)
			(fill no)
			(layer "F.Fab")
		)
		(pad "1" smd custom
			(at 0 -0.4445 180)
			(size 0.1524 0.1524)
			(layers "F.Cu" "F.Mask" "F.Paste")
			(net "P3V3")
			(options
				(clearance outline)
				(anchor circle)
			)
			(primitives
				(gr_poly
					(pts
						(arc
							(start 0.3048 -0.2032)
							(mid 0.275042 -0.275042)
							(end 0.2032 -0.3048)
						)
						(arc
							(start -0.2032 -0.3048)
							(mid -0.275042 -0.275042)
							(end -0.3048 -0.2032)
						)
						(arc
							(start -0.3048 0.2032)
							(mid -0.275042 0.275042)
							(end -0.2032 0.3048)
						)
						(arc
							(start 0.2032 0.3048)
							(mid 0.275042 0.275042)
							(end 0.3048 0.2032)
						)
					)
					(width 0)
					(fill yes)
				)
			)
		)
		(pad "2" smd custom
			(at 0 0.4445 180)
			(size 0.1524 0.1524)
			(layers "F.Cu" "F.Mask" "F.Paste")
			(net "GND")
			(options
				(clearance outline)
				(anchor circle)
			)
			(primitives
				(gr_poly
					(pts
						(arc
							(start 0.3048 -0.2032)
							(mid 0.275042 -0.275042)
							(end 0.2032 -0.3048)
						)
						(arc
							(start -0.2032 -0.3048)
							(mid -0.275042 -0.275042)
							(end -0.3048 -0.2032)
						)
						(arc
							(start -0.3048 0.2032)
							(mid -0.275042 0.275042)
							(end -0.2032 0.3048)
						)
						(arc
							(start 0.2032 0.3048)
							(mid 0.275042 0.275042)
							(end 0.3048 0.2032)
						)
					)
					(width 0)
					(fill yes)
				)
			)
		)
	)
	(footprint ""
		(layer "F.Cu")
		(at 75.0062 -38.1 -90)
		(property "Reference" "C8"
			(at 0 0 270)
			(layer "F.SilkS")
			(hide yes)
			(effects
				(font
					(size 1.27 1.27)
				)
			)
		)
		(property "Value" "SC10U25V6KX-1GP"
			(at -0.0762 -5.1308 270)
			(unlocked yes)
			(layer "F.Fab")
			(hide yes)
			(effects
				(font
					(size 1.016 1.016)
					(thickness 0.1524)
				)
			)
		)
		(property "Device Type" "C1206H71"
			(at -0.127 -6.6548 270)
			(unlocked yes)
			(layer "F.Fab")
			(hide yes)
			(effects
				(font
					(size 1.016 1.016)
					(thickness 0.1524)
				)
			)
		)
		(duplicate_pad_numbers_are_jumpers no)
		(fp_line
			(start -1.016 2.2352)
			(end -1.016 0.8382)
			(stroke
				(width 0.1524)
				(type default)
			)
			(layer "F.SilkS")
		)
		(fp_line
			(start 1.016 2.2352)
			(end -1.016 2.2352)
			(stroke
				(width 0.1524)
				(type default)
			)
			(layer "F.SilkS")
		)
		(fp_line
			(start 1.016 0.8382)
			(end 1.016 2.2352)
			(stroke
				(width 0.1524)
				(type default)
			)
			(layer "F.SilkS")
		)
		(fp_line
			(start -1.016 -0.8382)
			(end -1.016 -2.2352)
			(stroke
				(width 0.1524)
				(type default)
			)
			(layer "F.SilkS")
		)
		(fp_line
			(start -1.016 -2.2352)
			(end 1.016 -2.2352)
			(stroke
				(width 0.1524)
				(type default)
			)
			(layer "F.SilkS")
		)
		(fp_line
			(start 1.016 -2.2352)
			(end 1.016 -0.8382)
			(stroke
				(width 0.1524)
				(type default)
			)
			(layer "F.SilkS")
		)
		(fp_rect
			(start -1.0922 2.3114)
			(end 1.0922 -2.3114)
			(stroke
				(width 0)
				(type default)
			)
			(fill no)
			(layer "F.CrtYd")
		)
		(fp_poly
			(pts
				(xy 1.0922 -2.3114) (xy 1.0922 2.3114) (xy -1.0922 2.3114) (xy -1.0922 -2.3114)
			)
			(stroke
				(width 0)
				(type default)
			)
			(fill no)
			(layer "F.Fab")
		)
		(pad "1" smd rect
			(at 0 -1.397 270)
			(size 1.651 1.27)
			(layers "F.Cu" "F.Mask" "F.Paste")
			(net "P12V_SW_R")
		)
		(pad "2" smd rect
			(at 0 1.397 270)
			(size 1.651 1.27)
			(layers "F.Cu" "F.Mask" "F.Paste")
			(net "GND")
		)
	)
	(footprint ""
		(layer "F.Cu")
		(at 33.219898 -3.819906 180)
		(property "Reference" "SATA4"
			(at 0 0 180)
			(layer "F.SilkS")
			(hide yes)
			(effects
				(font
					(size 1.27 1.27)
				)
			)
		)
		(property "Value" "FCI-CONN29-2R-GP-U"
			(at -35.2552 -14.1859 180)
			(unlocked yes)
			(layer "F.Fab")
			(hide yes)
			(effects
				(font
					(size 1.016 1.016)
					(thickness 0.1524)
				)
			)
		)
		(property "Device Type" "PREFIT-29P-458055-UH395"
			(at -35.2552 -15.7099 180)
			(unlocked yes)
			(layer "F.Fab")
			(hide yes)
			(effects
				(font
					(size 1.016 1.016)
					(thickness 0.1524)
				)
			)
		)
		(duplicate_pad_numbers_are_jumpers no)
		(fp_line
			(start 18.0467 3.0099)
			(end -28.2067 3.0099)
			(stroke
				(width 0.1524)
				(type default)
			)
			(layer "F.SilkS")
		)
		(fp_line
			(start 18.0467 -3.0099)
			(end 18.0467 3.0099)
			(stroke
				(width 0.1524)
				(type default)
			)
			(layer "F.SilkS")
		)
		(fp_line
			(start -28.2067 3.0099)
			(end -28.2067 -3.0099)
			(stroke
				(width 0.1524)
				(type default)
			)
			(layer "F.SilkS")
		)
		(fp_line
			(start -28.2067 -3.0099)
			(end 18.0467 -3.0099)
			(stroke
				(width 0.1524)
				(type default)
			)
			(layer "F.SilkS")
		)
		(fp_poly
			(pts
				(xy -28.2067 3.0099) (xy -28.2067 -3.0099) (xy -21.9202 -3.0099) (xy -21.9202 -1.4478) (xy -28.1305 -1.4478)
				(xy -28.1305 1.4478) (xy -10.6934 1.4478) (xy -10.6934 -0.381) (xy -3.0607 -0.381) (xy -3.0607 2.4384)
				(xy 3.1115 2.4384) (xy 3.1115 1.4478) (xy 17.9705 1.4478) (xy 17.9705 -1.4351) (xy 11.7602 -1.4351)
				(xy 11.7602 -2.2098) (xy -2.2606 -2.2098) (xy -2.2606 -3.0099) (xy 18.0467 -3.0099) (xy 18.0467 3.0099)
			)
			(stroke
				(width 0)
				(type default)
			)
			(fill yes)
			(layer "F.SilkS")
		)
		(fp_poly
			(pts
				(arc
					(start 2.2098 1.25095)
					(mid 2.0828 1.12395)
					(end 2.2098 0.99695)
				)
				(arc
					(start 2.5908 0.99695)
					(mid 2.7178 1.12395)
					(end 2.5908 1.25095)
				)
			)
			(stroke
				(width 0)
				(type default)
			)
			(fill yes)
			(layer "F.SilkS")
		)
		(fp_poly
			(pts
				(arc
					(start 1.4097 1.25095)
					(mid 1.2827 1.12395)
					(end 1.4097 0.99695)
				)
				(arc
					(start 1.7907 0.99695)
					(mid 1.9177 1.12395)
					(end 1.7907 1.25095)
				)
			)
			(stroke
				(width 0)
				(type default)
			)
			(fill yes)
			(layer "F.SilkS")
		)
		(fp_poly
			(pts
				(arc
					(start 0.6096 1.25095)
					(mid 0.4826 1.12395)
					(end 0.6096 0.99695)
				)
				(arc
					(start 0.9906 0.99695)
					(mid 1.1176 1.12395)
					(end 0.9906 1.25095)
				)
			)
			(stroke
				(width 0)
				(type default)
			)
			(fill yes)
			(layer "F.SilkS")
		)
		(fp_poly
			(pts
				(arc
					(start -0.1905 1.25095)
					(mid -0.3175 1.12395)
					(end -0.1905 0.99695)
				)
				(arc
					(start 0.1905 0.99695)
					(mid 0.3175 1.12395)
					(end 0.1905 1.25095)
				)
			)
			(stroke
				(width 0)
				(type default)
			)
			(fill yes)
			(layer "F.SilkS")
		)
		(fp_poly
			(pts
				(arc
					(start -0.9906 1.25095)
					(mid -1.1176 1.12395)
					(end -0.9906 0.99695)
				)
				(arc
					(start -0.6096 0.99695)
					(mid -0.4826 1.12395)
					(end -0.6096 1.25095)
				)
			)
			(stroke
				(width 0)
				(type default)
			)
			(fill yes)
			(layer "F.SilkS")
		)
		(fp_poly
			(pts
				(arc
					(start -1.7907 1.25095)
					(mid -1.9177 1.12395)
					(end -1.7907 0.99695)
				)
				(arc
					(start -1.4097 0.99695)
					(mid -1.2827 1.12395)
					(end -1.4097 1.25095)
				)
			)
			(stroke
				(width 0)
				(type default)
			)
			(fill yes)
			(layer "F.SilkS")
		)
		(fp_poly
			(pts
				(arc
					(start -2.5908 1.25095)
					(mid -2.7178 1.12395)
					(end -2.5908 0.99695)
				)
				(arc
					(start -2.2098 0.99695)
					(mid -2.0828 1.12395)
					(end -2.2098 1.25095)
				)
			)
			(stroke
				(width 0)
				(type default)
			)
			(fill yes)
			(layer "F.SilkS")
		)
		(fp_poly
			(pts
				(arc
					(start 10.4902 0.2032)
					(mid 10.287 0)
					(end 10.4902 -0.2032)
				)
				(arc
					(start 11.0998 -0.2032)
					(mid 11.303 0)
					(end 11.0998 0.2032)
				)
			)
			(stroke
				(width 0)
				(type default)
			)
			(fill yes)
			(layer "F.SilkS")
		)
		(fp_poly
			(pts
				(arc
					(start 9.2202 0.2032)
					(mid 9.017 0)
					(end 9.2202 -0.2032)
				)
				(arc
					(start 9.8298 -0.2032)
					(mid 10.033 0)
					(end 9.8298 0.2032)
				)
			)
			(stroke
				(width 0)
				(type default)
			)
			(fill yes)
			(layer "F.SilkS")
		)
		(fp_poly
			(pts
				(arc
					(start 7.9502 0.2032)
					(mid 7.747 0)
					(end 7.9502 -0.2032)
				)
				(arc
					(start 8.5598 -0.2032)
					(mid 8.763 0)
					(end 8.5598 0.2032)
				)
			)
			(stroke
				(width 0)
				(type default)
			)
			(fill yes)
			(layer "F.SilkS")
		)
		(fp_poly
			(pts
				(arc
					(start 6.6802 0.2032)
					(mid 6.477 0)
					(end 6.6802 -0.2032)
				)
				(arc
					(start 7.2898 -0.2032)
					(mid 7.493 0)
					(end 7.2898 0.2032)
				)
			)
			(stroke
				(width 0)
				(type default)
			)
			(fill yes)
			(layer "F.SilkS")
		)
		(fp_poly
			(pts
				(arc
					(start 5.4102 0.2032)
					(mid 5.207 0)
					(end 5.4102 -0.2032)
				)
				(arc
					(start 6.0198 -0.2032)
					(mid 6.223 0)
					(end 6.0198 0.2032)
				)
			)
			(stroke
				(width 0)
				(type default)
			)
			(fill yes)
			(layer "F.SilkS")
		)
		(fp_poly
			(pts
				(arc
					(start 4.1402 0.2032)
					(mid 3.937 0)
					(end 4.1402 -0.2032)
				)
				(arc
					(start 4.7498 -0.2032)
					(mid 4.953 0)
					(end 4.7498 0.2032)
				)
			)
			(stroke
				(width 0)
				(type default)
			)
			(fill yes)
			(layer "F.SilkS")
		)
		(fp_poly
			(pts
				(arc
					(start 2.8702 0.2032)
					(mid 2.667 0)
					(end 2.8702 -0.2032)
				)
				(arc
					(start 3.4798 -0.2032)
					(mid 3.683 0)
					(end 3.4798 0.2032)
				)
			)
			(stroke
				(width 0)
				(type default)
			)
			(fill yes)
			(layer "F.SilkS")
		)
		(fp_poly
			(pts
				(arc
					(start -3.4798 -2.4638)
					(mid -3.683 -2.667)
					(end -3.4798 -2.8702)
				)
				(arc
					(start -2.8702 -2.8702)
					(mid -2.667 -2.667)
					(end -2.8702 -2.4638)
				)
			)
			(stroke
				(width 0)
				(type default)
			)
			(fill yes)
			(layer "F.SilkS")
		)
		(fp_poly
			(pts
				(arc
					(start -4.7498 -2.4638)
					(mid -4.953 -2.667)
					(end -4.7498 -2.8702)
				)
				(arc
					(start -4.1402 -2.8702)
					(mid -3.937 -2.667)
					(end -4.1402 -2.4638)
				)
			)
			(stroke
				(width 0)
				(type default)
			)
			(fill yes)
			(layer "F.SilkS")
		)
		(fp_poly
			(pts
				(arc
					(start -6.0198 -2.4638)
					(mid -6.223 -2.667)
					(end -6.0198 -2.8702)
				)
				(arc
					(start -5.4102 -2.8702)
					(mid -5.207 -2.667)
					(end -5.4102 -2.4638)
				)
			)
			(stroke
				(width 0)
				(type default)
			)
			(fill yes)
			(layer "F.SilkS")
		)
		(fp_poly
			(pts
				(arc
					(start -7.2898 -2.4638)
					(mid -7.493 -2.667)
					(end -7.2898 -2.8702)
				)
				(arc
					(start -6.6802 -2.8702)
					(mid -6.477 -2.667)
					(end -6.6802 -2.4638)
				)
			)
			(stroke
				(width 0)
				(type default)
			)
			(fill yes)
			(layer "F.SilkS")
		)
		(fp_poly
			(pts
				(arc
					(start -8.5598 -2.4638)
					(mid -8.763 -2.667)
					(end -8.5598 -2.8702)
				)
				(arc
					(start -7.9502 -2.8702)
					(mid -7.747 -2.667)
					(end -7.9502 -2.4638)
				)
			)
			(stroke
				(width 0)
				(type default)
			)
			(fill yes)
			(layer "F.SilkS")
		)
		(fp_poly
			(pts
				(arc
					(start -9.8298 -2.4638)
					(mid -10.033 -2.667)
					(end -9.8298 -2.8702)
				)
				(arc
					(start -9.2202 -2.8702)
					(mid -9.017 -2.667)
					(end -9.2202 -2.4638)
				)
			)
			(stroke
				(width 0)
				(type default)
			)
			(fill yes)
			(layer "F.SilkS")
		)
		(fp_poly
			(pts
				(arc
					(start -11.0998 -2.4638)
					(mid -11.303 -2.667)
					(end -11.0998 -2.8702)
				)
				(arc
					(start -10.4902 -2.8702)
					(mid -10.287 -2.667)
					(end -10.4902 -2.4638)
				)
			)
			(stroke
				(width 0)
				(type default)
			)
			(fill yes)
			(layer "F.SilkS")
		)
		(fp_poly
			(pts
				(arc
					(start -12.3698 -2.4638)
					(mid -12.573 -2.667)
					(end -12.3698 -2.8702)
				)
				(arc
					(start -11.7602 -2.8702)
					(mid -11.557 -2.667)
					(end -11.7602 -2.4638)
				)
			)
			(stroke
				(width 0)
				(type default)
			)
			(fill yes)
			(layer "F.SilkS")
		)
		(fp_poly
			(pts
				(arc
					(start -13.6398 -2.4638)
					(mid -13.843 -2.667)
					(end -13.6398 -2.8702)
				)
				(arc
					(start -13.0302 -2.8702)
					(mid -12.827 -2.667)
					(end -13.0302 -2.4638)
				)
			)
			(stroke
				(width 0)
				(type default)
			)
			(fill yes)
			(layer "F.SilkS")
		)
		(fp_poly
			(pts
				(arc
					(start -14.9098 -2.4638)
					(mid -15.113 -2.667)
					(end -14.9098 -2.8702)
				)
				(arc
					(start -14.3002 -2.8702)
					(mid -14.097 -2.667)
					(end -14.3002 -2.4638)
				)
			)
			(stroke
				(width 0)
				(type default)
			)
			(fill yes)
			(layer "F.SilkS")
		)
		(fp_poly
			(pts
				(arc
					(start -16.1798 -2.4638)
					(mid -16.383 -2.667)
					(end -16.1798 -2.8702)
				)
				(arc
					(start -15.5702 -2.8702)
					(mid -15.367 -2.667)
					(end -15.5702 -2.4638)
				)
			)
			(stroke
				(width 0)
				(type default)
			)
			(fill yes)
			(layer "F.SilkS")
		)
		(fp_poly
			(pts
				(arc
					(start -17.4498 -2.4638)
					(mid -17.653 -2.667)
					(end -17.4498 -2.8702)
				)
				(arc
					(start -16.8402 -2.8702)
					(mid -16.637 -2.667)
					(end -16.8402 -2.4638)
				)
			)
			(stroke
				(width 0)
				(type default)
			)
			(fill yes)
			(layer "F.SilkS")
		)
		(fp_poly
			(pts
				(arc
					(start -18.7198 -2.4638)
					(mid -18.923 -2.667)
					(end -18.7198 -2.8702)
				)
				(arc
					(start -18.1102 -2.8702)
					(mid -17.907 -2.667)
					(end -18.1102 -2.4638)
				)
			)
			(stroke
				(width 0)
				(type default)
			)
			(fill yes)
			(layer "F.SilkS")
		)
		(fp_poly
			(pts
				(arc
					(start -19.9898 -2.4638)
					(mid -20.193 -2.667)
					(end -19.9898 -2.8702)
				)
				(arc
					(start -19.3802 -2.8702)
					(mid -19.177 -2.667)
					(end -19.3802 -2.4638)
				)
			)
			(stroke
				(width 0)
				(type default)
			)
			(fill yes)
			(layer "F.SilkS")
		)
		(fp_poly
			(pts
				(arc
					(start -21.2598 -2.4638)
					(mid -21.463 -2.667)
					(end -21.2598 -2.8702)
				)
				(arc
					(start -20.6502 -2.8702)
					(mid -20.447 -2.667)
					(end -20.6502 -2.4638)
				)
			)
			(stroke
				(width 0)
				(type default)
			)
			(fill yes)
			(layer "F.SilkS")
		)
		(fp_poly
			(pts
				(arc
					(start 17.87525 0.6096)
					(mid 17.57045 0.9144)
					(end 17.26565 0.6096)
				)
				(arc
					(start 17.26565 -0.6096)
					(mid 17.57045 -0.9144)
					(end 17.87525 -0.6096)
				)
			)
			(stroke
				(width 0)
				(type default)
			)
			(fill yes)
			(layer "F.SilkS")
		)
		(fp_poly
			(pts
				(arc
					(start -27.42565 0.6096)
					(mid -27.73045 0.9144)
					(end -28.03525 0.6096)
				)
				(arc
					(start -28.03525 -0.6096)
					(mid -27.73045 -0.9144)
					(end -27.42565 -0.6096)
				)
			)
			(stroke
				(width 0)
				(type default)
			)
			(fill yes)
			(layer "F.SilkS")
		)
		(fp_rect
			(start -32.2707 7.5438)
			(end 22.1107 -6.7056)
			(stroke
				(width 0)
				(type default)
			)
			(fill no)
			(layer "B.CrtYd")
		)
		(fp_rect
			(start -27.9527 2.7559)
			(end 17.7927 -2.7559)
			(stroke
				(width 0)
				(type default)
			)
			(fill no)
			(layer "F.CrtYd")
		)
		(fp_poly
			(pts
				(xy -28.4607 3.2639) (xy -28.4607 -3.2639) (xy 18.3007 -3.2639) (xy 18.3007 2.7051) (xy 17.7927 2.7051)
				(xy 17.7927 -2.7559) (xy -27.9527 -2.7559) (xy -27.9527 2.7559) (xy 17.7927 2.7559) (xy 17.7927 2.7178)
				(xy 18.3007 2.7178) (xy 18.3007 3.2639)
			)
			(stroke
				(width 0)
				(type default)
			)
			(fill no)
			(layer "F.CrtYd")
		)
		(fp_poly
			(pts
				(xy -32.9565 7.7597) (xy -32.9565 -7.7597) (xy 22.7965 -7.7597) (xy 22.7965 2.7051) (xy 18.3007 2.7051)
				(xy 18.3007 -3.2639) (xy -28.4607 -3.2639) (xy -28.4607 3.2639) (xy 18.3007 3.2639) (xy 18.3007 2.7178)
				(xy 22.7965 2.7178) (xy 22.7965 7.7597)
			)
			(stroke
				(width 0)
				(type default)
			)
			(fill no)
			(layer "F.CrtYd")
		)
		(fp_rect
			(start -32.2707 7.5438)
			(end 22.1107 -6.7056)
			(stroke
				(width 0)
				(type default)
			)
			(fill no)
			(layer "B.Fab")
		)
		(fp_rect
			(start -37.2745 12.5476)
			(end 27.1145 -11.7094)
			(stroke
				(width 0)
				(type default)
			)
			(fill no)
			(layer "B.Fab")
		)
		(fp_rect
			(start -28.4607 3.2639)
			(end 18.3007 -3.2639)
			(stroke
				(width 0)
				(type default)
			)
			(fill no)
			(layer "F.Fab")
		)
		(fp_rect
			(start -32.9565 7.7597)
			(end 22.7965 -7.7597)
			(stroke
				(width 0)
				(type default)
			)
			(fill no)
			(layer "F.Fab")
		)
		(fp_rect
			(start -37.9603 12.7635)
			(end 27.8003 -12.7635)
			(stroke
				(width 0)
				(type default)
			)
			(fill no)
			(layer "F.Fab")
		)
		(fp_text user "Press Fit"
			(at -21.3614 0.5715 180)
			(unlocked yes)
			(layer "F.SilkS")
			(effects
				(font
					(size 1.016 1.016)
					(thickness 0.1524)
				)
				(justify left)
			)
		)
		(fp_text user "Can not place BGA,CSP,Wave Solder Comonent."
			(at -28.9433 10.1219 180)
			(unlocked yes)
			(layer "B.Fab")
			(effects
				(font
					(size 1.016 1.016)
					(thickness 0.1524)
				)
				(justify left)
			)
		)
		(fp_text user "High Limit 2mm"
			(at -13.8811 6.6421 180)
			(unlocked yes)
			(layer "F.Fab")
			(effects
				(font
					(size 1.016 1.016)
					(thickness 0.1524)
				)
				(justify left)
			)
		)
		(fp_text user "Can not place BGA,CSP,Wave Solder Comonent."
			(at -28.9433 10.1219 180)
			(unlocked yes)
			(layer "F.Fab")
			(effects
				(font
					(size 1.016 1.016)
					(thickness 0.1524)
				)
				(justify left)
			)
		)
		(pad "" np_thru_hole circle
			(at -23.95474 0 180)
			(size 0.254 0.254)
			(drill 1.3462)
			(layers "*.Cu" "*.Mask")
			(clearance 0.9017)
			(thermal_gap 0.9017)
		)
		(pad "30" thru_hole circle
			(at -26.07945 0 180)
			(size 2.3622 2.3622)
			(drill 1.949958)
			(layers "*.Cu" "*.Mask")
			(remove_unused_layers no)
			(net "Net_53")
			(clearance 0.1524)
			(thermal_gap 0.1524)
		)
		(pad "31" thru_hole circle
			(at 15.91945 0 180)
			(size 2.3622 2.3622)
			(drill 1.949958)
			(layers "*.Cu" "*.Mask")
			(remove_unused_layers no)
			(net "Net_44")
			(clearance 0.1524)
			(thermal_gap 0.1524)
		)
		(pad "P1" thru_hole circle
			(at -3.175 -1.27 180)
			(size 0.8636 0.8636)
			(drill 0.499872)
			(layers "*.Cu" "*.Mask")
			(remove_unused_layers no)
			(net "Net_49")
			(clearance 0.1778)
			(thermal_gap 0.1778)
		)
		(pad "P2" thru_hole circle
			(at -4.445 -1.27 180)
			(size 0.8636 0.8636)
			(drill 0.499872)
			(layers "*.Cu" "*.Mask")
			(remove_unused_layers no)
			(net "Net_51")
			(clearance 0.1778)
			(thermal_gap 0.1778)
		)
		(pad "P3" thru_hole circle
			(at -5.715 -1.27 180)
			(size 0.8636 0.8636)
			(drill 0.499872)
			(layers "*.Cu" "*.Mask")
			(remove_unused_layers no)
			(net "Net_50")
			(clearance 0.1778)
			(thermal_gap 0.1778)
		)
		(pad "P4" thru_hole circle
			(at -6.985 -1.27 180)
			(size 0.8636 0.8636)
			(drill 0.499872)
			(layers "*.Cu" "*.Mask")
			(remove_unused_layers no)
			(net "GND")
			(clearance 0.1778)
			(thermal_gap 0.1778)
		)
		(pad "P5" thru_hole circle
			(at -8.255 -1.27 180)
			(size 0.8636 0.8636)
			(drill 0.499872)
			(layers "*.Cu" "*.Mask")
			(remove_unused_layers no)
			(net "GND")
			(clearance 0.1778)
			(thermal_gap 0.1778)
		)
		(pad "P6" thru_hole circle
			(at -9.525 -1.27 180)
			(size 0.8636 0.8636)
			(drill 0.499872)
			(layers "*.Cu" "*.Mask")
			(remove_unused_layers no)
			(net "GND")
			(clearance 0.1778)
			(thermal_gap 0.1778)
		)
		(pad "P7" thru_hole circle
			(at -10.795 -1.27 180)
			(size 0.8636 0.8636)
			(drill 0.499872)
			(layers "*.Cu" "*.Mask")
			(remove_unused_layers no)
			(net "5V_PRE_3")
			(clearance 0.1778)
			(thermal_gap 0.1778)
		)
		(pad "P8" thru_hole circle
			(at -12.065 -1.27 180)
			(size 0.8636 0.8636)
			(drill 0.499872)
			(layers "*.Cu" "*.Mask")
			(remove_unused_layers no)
			(net "P5V_SW_L")
			(clearance 0.1778)
			(thermal_gap 0.1778)
		)
		(pad "P9" thru_hole circle
			(at -13.335 -1.27 180)
			(size 0.8636 0.8636)
			(drill 0.499872)
			(layers "*.Cu" "*.Mask")
			(remove_unused_layers no)
			(net "P5V_SW_L")
			(clearance 0.1778)
			(thermal_gap 0.1778)
		)
		(pad "P10" thru_hole circle
			(at -14.605 -1.27 180)
			(size 0.8636 0.8636)
			(drill 0.499872)
			(layers "*.Cu" "*.Mask")
			(remove_unused_layers no)
			(net "HBA_PRSNT3_N")
			(clearance 0.1778)
			(thermal_gap 0.1778)
		)
		(pad "P11" thru_hole circle
			(at -15.875 -1.27 180)
			(size 0.8636 0.8636)
			(drill 0.499872)
			(layers "*.Cu" "*.Mask")
			(remove_unused_layers no)
			(net "HDD_ACT_LED3")
			(clearance 0.1778)
			(thermal_gap 0.1778)
		)
		(pad "P12" thru_hole circle
			(at -17.145 -1.27 180)
			(size 0.8636 0.8636)
			(drill 0.499872)
			(layers "*.Cu" "*.Mask")
			(remove_unused_layers no)
			(net "GND")
			(clearance 0.1778)
			(thermal_gap 0.1778)
		)
		(pad "P13" thru_hole circle
			(at -18.415 -1.27 180)
			(size 0.8636 0.8636)
			(drill 0.499872)
			(layers "*.Cu" "*.Mask")
			(remove_unused_layers no)
			(net "12V_PRE_3")
			(clearance 0.1778)
			(thermal_gap 0.1778)
		)
		(pad "P14" thru_hole circle
			(at -19.685 -1.27 180)
			(size 0.8636 0.8636)
			(drill 0.499872)
			(layers "*.Cu" "*.Mask")
			(remove_unused_layers no)
			(net "P12V_SW_L")
			(clearance 0.1778)
			(thermal_gap 0.1778)
		)
		(pad "P15" thru_hole circle
			(at -20.955 -1.27 180)
			(size 0.8636 0.8636)
			(drill 0.499872)
			(layers "*.Cu" "*.Mask")
			(remove_unused_layers no)
			(net "P12V_SW_L")
			(clearance 0.1778)
			(thermal_gap 0.1778)
		)
		(pad "S1" thru_hole circle
			(at 10.795 -1.27 180)
			(size 0.8636 0.8636)
			(drill 0.499872)
			(layers "*.Cu" "*.Mask")
			(remove_unused_layers no)
			(net "GND")
			(clearance 0.1778)
			(thermal_gap 0.1778)
		)
		(pad "S2" thru_hole circle
			(at 9.525 -1.27 180)
			(size 0.8636 0.8636)
			(drill 0.499872)
			(layers "*.Cu" "*.Mask")
			(remove_unused_layers no)
			(net "HBA_MB_TX_P3")
			(clearance 0.1778)
			(thermal_gap 0.1778)
		)
		(pad "S3" thru_hole circle
			(at 8.255 -1.27 180)
			(size 0.8636 0.8636)
			(drill 0.499872)
			(layers "*.Cu" "*.Mask")
			(remove_unused_layers no)
			(net "HBA_MB_TX_N3")
			(clearance 0.1778)
			(thermal_gap 0.1778)
		)
		(pad "S4" thru_hole circle
			(at 6.985 -1.27 180)
			(size 0.8636 0.8636)
			(drill 0.499872)
			(layers "*.Cu" "*.Mask")
			(remove_unused_layers no)
			(net "GND")
			(clearance 0.1778)
			(thermal_gap 0.1778)
		)
		(pad "S5" thru_hole circle
			(at 5.715 -1.27 180)
			(size 0.8636 0.8636)
			(drill 0.499872)
			(layers "*.Cu" "*.Mask")
			(remove_unused_layers no)
			(net "HBA_MB_RX_N3")
			(clearance 0.1778)
			(thermal_gap 0.1778)
		)
		(pad "S6" thru_hole circle
			(at 4.445 -1.27 180)
			(size 0.8636 0.8636)
			(drill 0.499872)
			(layers "*.Cu" "*.Mask")
			(remove_unused_layers no)
			(net "HBA_MB_RX_P3")
			(clearance 0.1778)
			(thermal_gap 0.1778)
		)
		(pad "S7" thru_hole circle
			(at 3.175 -1.27 180)
			(size 0.8636 0.8636)
			(drill 0.499872)
			(layers "*.Cu" "*.Mask")
			(remove_unused_layers no)
			(net "GND")
			(clearance 0.1778)
			(thermal_gap 0.1778)
		)
		(pad "S8" thru_hole oval
			(at 2.4003 2.13995 180)
			(size 0.6096 0.8128)
			(drill 0.399796)
			(layers "*.Cu" "*.Mask")
			(remove_unused_layers no)
			(net "GND")
			(clearance 0.254)
			(thermal_gap 0.254)
		)
		(pad "S9" thru_hole oval
			(at 1.6002 2.13995 180)
			(size 0.6096 0.8128)
			(drill 0.399796)
			(layers "*.Cu" "*.Mask")
			(remove_unused_layers no)
			(net "Net_48")
			(clearance 0.254)
			(thermal_gap 0.254)
		)
		(pad "S10" thru_hole oval
			(at 0.8001 2.13995 180)
			(size 0.6096 0.8128)
			(drill 0.399796)
			(layers "*.Cu" "*.Mask")
			(remove_unused_layers no)
			(net "Net_47")
			(clearance 0.254)
			(thermal_gap 0.254)
		)
		(pad "S11" thru_hole oval
			(at 0 2.13995 180)
			(size 0.6096 0.8128)
			(drill 0.399796)
			(layers "*.Cu" "*.Mask")
			(remove_unused_layers no)
			(net "Net_43")
			(clearance 0.254)
			(thermal_gap 0.254)
		)
		(pad "S12" thru_hole oval
			(at -0.8001 2.13995 180)
			(size 0.6096 0.8128)
			(drill 0.399796)
			(layers "*.Cu" "*.Mask")
			(remove_unused_layers no)
			(net "Net_46")
			(clearance 0.254)
			(thermal_gap 0.254)
		)
		(pad "S13" thru_hole oval
			(at -1.6002 2.13995 180)
			(size 0.6096 0.8128)
			(drill 0.399796)
			(layers "*.Cu" "*.Mask")
			(remove_unused_layers no)
			(net "Net_45")
			(clearance 0.254)
			(thermal_gap 0.254)
		)
		(pad "S14" thru_hole oval
			(at -2.4003 2.13995 180)
			(size 0.6096 0.8128)
			(drill 0.399796)
			(layers "*.Cu" "*.Mask")
			(remove_unused_layers no)
			(net "GND")
			(clearance 0.254)
			(thermal_gap 0.254)
		)
		(zone
			(layers "F.Cu" "B.Cu" "In1.Cu" "In2.Cu" "In3.Cu" "In4.Cu")
			(hatch none 0.5)
			(connect_pads
				(clearance 0)
			)
			(min_thickness 0.25)
			(keepout
				(tracks not_allowed)
				(vias allowed)
				(pads allowed)
				(copperpour not_allowed)
				(footprints allowed)
			)
			(placement
				(enabled no)
				(sheetname "")
			)
			(fill
				(thermal_gap 0.5)
				(thermal_bridge_width 0.5)
				(island_removal_mode 0)
			)
			(polygon
				(pts
					(arc
						(start 58.152538 -3.819906)
						(mid 56.196738 -3.819906)
						(end 58.152538 -3.819906)
					)
				)
			)
		)
	)
	(footprint ""
		(layer "F.Cu")
		(at 86.566248 -11.259058 -90)
		(property "Reference" "R163"
			(at 0 0 270)
			(layer "F.SilkS")
			(hide yes)
			(effects
				(font
					(size 1.27 1.27)
				)
			)
		)
		(property "Value" "0R5J-5-GP"
			(at 0 -8.9535 270)
			(unlocked yes)
			(layer "F.Fab")
			(hide yes)
			(effects
				(font
					(size 1.27 1.016)
					(thickness 0.1524)
				)
			)
		)
		(property "Device Type" "R805H24"
			(at 0 -10.6299 270)
			(unlocked yes)
			(layer "F.Fab")
			(hide yes)
			(effects
				(font
					(size 1.27 1.016)
					(thickness 0.1524)
				)
			)
		)
		(duplicate_pad_numbers_are_jumpers no)
		(fp_line
			(start -0.889 1.7018)
			(end 0.889 1.7018)
			(stroke
				(width 0.1524)
				(type default)
			)
			(layer "F.SilkS")
		)
		(fp_line
			(start 0.889 1.7018)
			(end 0.889 -0.508)
			(stroke
				(width 0.1524)
				(type default)
			)
			(layer "F.SilkS")
		)
		(fp_line
			(start -0.889 0.0762)
			(end -0.889 1.7018)
			(stroke
				(width 0.1524)
				(type default)
			)
			(layer "F.SilkS")
		)
		(fp_line
			(start -0.889 -1.7018)
			(end -0.889 0.2794)
			(stroke
				(width 0.1524)
				(type default)
			)
			(layer "F.SilkS")
		)
		(fp_line
			(start 0.889 -1.7018)
			(end 0.889 -0.381)
			(stroke
				(width 0.1524)
				(type default)
			)
			(layer "F.SilkS")
		)
		(fp_line
			(start 0.889 -1.7018)
			(end -0.889 -1.7018)
			(stroke
				(width 0.1524)
				(type default)
			)
			(layer "F.SilkS")
		)
		(fp_poly
			(pts
				(xy 0.9652 -1.778) (xy 0.9652 1.778) (xy -0.9652 1.778) (xy -0.9652 -1.778)
			)
			(stroke
				(width 0)
				(type default)
			)
			(fill no)
			(layer "F.CrtYd")
		)
		(fp_rect
			(start -0.9652 1.778)
			(end 0.9652 -1.778)
			(stroke
				(width 0)
				(type default)
			)
			(fill no)
			(layer "F.Fab")
		)
		(pad "1" smd rect
			(at 0 -0.9652 270)
			(size 1.397 1.143)
			(layers "F.Cu" "F.Mask" "F.Paste")
			(net "P12V")
		)
		(pad "2" smd rect
			(at 0 0.9652 270)
			(size 1.397 1.143)
			(layers "F.Cu" "F.Mask" "F.Paste")
			(net "P12V_SW_L")
		)
	)
	(footprint ""
		(layer "F.Cu")
		(at 77.724 -52.324 -90)
		(property "Reference" "C6"
			(at 0 0 270)
			(layer "F.SilkS")
			(hide yes)
			(effects
				(font
					(size 1.27 1.27)
				)
			)
		)
		(property "Value" "SCD1U25V2KX-GP"
			(at 1.1811 -2.7051 270)
			(unlocked yes)
			(layer "F.Fab")
			(hide yes)
			(effects
				(font
					(size 1.016 1.016)
					(thickness 0.1524)
				)
			)
		)
		(property "Device Type" "C402H22"
			(at 1.1811 -4.2291 270)
			(unlocked yes)
			(layer "F.Fab")
			(hide yes)
			(effects
				(font
					(size 1.016 1.016)
					(thickness 0.1524)
				)
			)
		)
		(duplicate_pad_numbers_are_jumpers no)
		(fp_rect
			(start -0.4318 0.9525)
			(end 0.4318 -0.9525)
			(stroke
				(width 0)
				(type default)
			)
			(fill no)
			(layer "F.CrtYd")
		)
		(fp_rect
			(start -0.4318 0.9525)
			(end 0.4318 -0.9525)
			(stroke
				(width 0)
				(type default)
			)
			(fill no)
			(layer "F.Fab")
		)
		(pad "1" smd custom
			(at 0 -0.4445 270)
			(size 0.1524 0.1524)
			(layers "F.Cu" "F.Mask" "F.Paste")
			(net "P5V_SW_R")
			(options
				(clearance outline)
				(anchor circle)
			)
			(primitives
				(gr_poly
					(pts
						(arc
							(start 0.3048 -0.2032)
							(mid 0.275042 -0.275042)
							(end 0.2032 -0.3048)
						)
						(arc
							(start -0.2032 -0.3048)
							(mid -0.275042 -0.275042)
							(end -0.3048 -0.2032)
						)
						(arc
							(start -0.3048 0.2032)
							(mid -0.275042 0.275042)
							(end -0.2032 0.3048)
						)
						(arc
							(start 0.2032 0.3048)
							(mid 0.275042 0.275042)
							(end 0.3048 0.2032)
						)
					)
					(width 0)
					(fill yes)
				)
			)
		)
		(pad "2" smd custom
			(at 0 0.4445 270)
			(size 0.1524 0.1524)
			(layers "F.Cu" "F.Mask" "F.Paste")
			(net "GND")
			(options
				(clearance outline)
				(anchor circle)
			)
			(primitives
				(gr_poly
					(pts
						(arc
							(start 0.3048 -0.2032)
							(mid 0.275042 -0.275042)
							(end 0.2032 -0.3048)
						)
						(arc
							(start -0.2032 -0.3048)
							(mid -0.275042 -0.275042)
							(end -0.3048 -0.2032)
						)
						(arc
							(start -0.3048 0.2032)
							(mid -0.275042 0.275042)
							(end -0.2032 0.3048)
						)
						(arc
							(start 0.2032 0.3048)
							(mid 0.275042 0.275042)
							(end 0.3048 0.2032)
						)
					)
					(width 0)
					(fill yes)
				)
			)
		)
	)
	(footprint ""
		(layer "F.Cu")
		(at 127.728472 -40.966644 180)
		(property "Reference" "C1"
			(at 0 0 180)
			(layer "F.SilkS")
			(hide yes)
			(effects
				(font
					(size 1.27 1.27)
				)
			)
		)
		(property "Value" "SCD01U50V2KX-1GP"
			(at 1.1811 -2.7051 180)
			(unlocked yes)
			(layer "F.Fab")
			(hide yes)
			(effects
				(font
					(size 1.016 1.016)
					(thickness 0.1524)
				)
			)
		)
		(property "Device Type" "C402H22"
			(at 1.1811 -4.2291 180)
			(unlocked yes)
			(layer "F.Fab")
			(hide yes)
			(effects
				(font
					(size 1.016 1.016)
					(thickness 0.1524)
				)
			)
		)
		(duplicate_pad_numbers_are_jumpers no)
		(fp_rect
			(start -0.4318 0.9525)
			(end 0.4318 -0.9525)
			(stroke
				(width 0)
				(type default)
			)
			(fill no)
			(layer "F.CrtYd")
		)
		(fp_rect
			(start -0.4318 0.9525)
			(end 0.4318 -0.9525)
			(stroke
				(width 0)
				(type default)
			)
			(fill no)
			(layer "F.Fab")
		)
		(pad "1" smd custom
			(at 0 -0.4445 180)
			(size 0.1524 0.1524)
			(layers "F.Cu" "F.Mask" "F.Paste")
			(net "HBA_PRSNT1_N")
			(options
				(clearance outline)
				(anchor circle)
			)
			(primitives
				(gr_poly
					(pts
						(arc
							(start 0.3048 -0.2032)
							(mid 0.275042 -0.275042)
							(end 0.2032 -0.3048)
						)
						(arc
							(start -0.2032 -0.3048)
							(mid -0.275042 -0.275042)
							(end -0.3048 -0.2032)
						)
						(arc
							(start -0.3048 0.2032)
							(mid -0.275042 0.275042)
							(end -0.2032 0.3048)
						)
						(arc
							(start 0.2032 0.3048)
							(mid 0.275042 0.275042)
							(end 0.3048 0.2032)
						)
					)
					(width 0)
					(fill yes)
				)
			)
		)
		(pad "2" smd custom
			(at 0 0.4445 180)
			(size 0.1524 0.1524)
			(layers "F.Cu" "F.Mask" "F.Paste")
			(net "GND")
			(options
				(clearance outline)
				(anchor circle)
			)
			(primitives
				(gr_poly
					(pts
						(arc
							(start 0.3048 -0.2032)
							(mid 0.275042 -0.275042)
							(end 0.2032 -0.3048)
						)
						(arc
							(start -0.2032 -0.3048)
							(mid -0.275042 -0.275042)
							(end -0.3048 -0.2032)
						)
						(arc
							(start -0.3048 0.2032)
							(mid -0.275042 0.275042)
							(end -0.2032 0.3048)
						)
						(arc
							(start 0.2032 0.3048)
							(mid 0.275042 0.275042)
							(end 0.3048 0.2032)
						)
					)
					(width 0)
					(fill yes)
				)
			)
		)
	)
	(footprint ""
		(layer "F.Cu")
		(at 81.153 -36.068 90)
		(property "Reference" "R137"
			(at 0 0 90)
			(layer "F.SilkS")
			(hide yes)
			(effects
				(font
					(size 1.27 1.27)
				)
			)
		)
		(property "Value" "4K7R2J-2-GP"
			(at 0.064008 -3.993896 90)
			(unlocked yes)
			(layer "F.Fab")
			(hide yes)
			(effects
				(font
					(size 1.016 1.016)
					(thickness 0.1524)
				)
			)
		)
		(property "Device Type" "R402H16"
			(at 0.064008 -5.517896 90)
			(unlocked yes)
			(layer "F.Fab")
			(hide yes)
			(effects
				(font
					(size 1.016 1.016)
					(thickness 0.1524)
				)
			)
		)
		(duplicate_pad_numbers_are_jumpers no)
		(fp_line
			(start 0.508 -0.9398)
			(end -0.508 -0.9398)
			(stroke
				(width 0.1524)
				(type default)
			)
			(layer "F.SilkS")
		)
		(fp_line
			(start -0.508 -0.9398)
			(end -0.508 0.9398)
			(stroke
				(width 0.1524)
				(type default)
			)
			(layer "F.SilkS")
		)
		(fp_rect
			(start -0.508 0.9398)
			(end 0.508 -0.9398)
			(stroke
				(width 0)
				(type default)
			)
			(fill no)
			(layer "F.CrtYd")
		)
		(fp_rect
			(start -0.508 0.9398)
			(end 0.508 -0.9398)
			(stroke
				(width 0)
				(type default)
			)
			(fill no)
			(layer "F.Fab")
		)
		(pad "1" smd custom
			(at 0 -0.4445 90)
			(size 0.1397 0.1397)
			(layers "F.Cu" "F.Mask" "F.Paste")
			(net "P12V")
			(options
				(clearance outline)
				(anchor circle)
			)
			(primitives
				(gr_poly
					(pts
						(arc
							(start -0.1778 -0.2794)
							(mid -0.249642 -0.249642)
							(end -0.2794 -0.1778)
						)
						(arc
							(start -0.2794 0.1778)
							(mid -0.249642 0.249642)
							(end -0.1778 0.2794)
						)
						(arc
							(start 0.1778 0.2794)
							(mid 0.249642 0.249642)
							(end 0.2794 0.1778)
						)
						(arc
							(start 0.2794 -0.1778)
							(mid 0.249642 -0.249642)
							(end 0.1778 -0.2794)
						)
					)
					(width 0)
					(fill yes)
				)
			)
		)
		(pad "2" smd custom
			(at 0 0.4445 90)
			(size 0.1397 0.1397)
			(layers "F.Cu" "F.Mask" "F.Paste")
			(net "SW_SW_R_0")
			(options
				(clearance outline)
				(anchor circle)
			)
			(primitives
				(gr_poly
					(pts
						(arc
							(start -0.1778 -0.2794)
							(mid -0.249642 -0.249642)
							(end -0.2794 -0.1778)
						)
						(arc
							(start -0.2794 0.1778)
							(mid -0.249642 0.249642)
							(end -0.1778 0.2794)
						)
						(arc
							(start 0.1778 0.2794)
							(mid 0.249642 0.249642)
							(end 0.2794 0.1778)
						)
						(arc
							(start 0.2794 -0.1778)
							(mid 0.249642 -0.249642)
							(end 0.1778 -0.2794)
						)
					)
					(width 0)
					(fill yes)
				)
			)
		)
	)
	(footprint ""
		(layer "F.Cu")
		(at 53.6194 -8.5852 180)
		(property "Reference" "C14"
			(at 0 0 180)
			(layer "F.SilkS")
			(hide yes)
			(effects
				(font
					(size 1.27 1.27)
				)
			)
		)
		(property "Value" "SCD01U50V2KX-1GP"
			(at 1.1811 -2.7051 180)
			(unlocked yes)
			(layer "F.Fab")
			(hide yes)
			(effects
				(font
					(size 1.016 1.016)
					(thickness 0.1524)
				)
			)
		)
		(property "Device Type" "C402H22"
			(at 1.1811 -4.2291 180)
			(unlocked yes)
			(layer "F.Fab")
			(hide yes)
			(effects
				(font
					(size 1.016 1.016)
					(thickness 0.1524)
				)
			)
		)
		(duplicate_pad_numbers_are_jumpers no)
		(fp_rect
			(start -0.4318 0.9525)
			(end 0.4318 -0.9525)
			(stroke
				(width 0)
				(type default)
			)
			(fill no)
			(layer "F.CrtYd")
		)
		(fp_rect
			(start -0.4318 0.9525)
			(end 0.4318 -0.9525)
			(stroke
				(width 0)
				(type default)
			)
			(fill no)
			(layer "F.Fab")
		)
		(pad "1" smd custom
			(at 0 -0.4445 180)
			(size 0.1524 0.1524)
			(layers "F.Cu" "F.Mask" "F.Paste")
			(net "HBA_PRSNT3_N")
			(options
				(clearance outline)
				(anchor circle)
			)
			(primitives
				(gr_poly
					(pts
						(arc
							(start 0.3048 -0.2032)
							(mid 0.275042 -0.275042)
							(end 0.2032 -0.3048)
						)
						(arc
							(start -0.2032 -0.3048)
							(mid -0.275042 -0.275042)
							(end -0.3048 -0.2032)
						)
						(arc
							(start -0.3048 0.2032)
							(mid -0.275042 0.275042)
							(end -0.2032 0.3048)
						)
						(arc
							(start 0.2032 0.3048)
							(mid 0.275042 0.275042)
							(end 0.3048 0.2032)
						)
					)
					(width 0)
					(fill yes)
				)
			)
		)
		(pad "2" smd custom
			(at 0 0.4445 180)
			(size 0.1524 0.1524)
			(layers "F.Cu" "F.Mask" "F.Paste")
			(net "GND")
			(options
				(clearance outline)
				(anchor circle)
			)
			(primitives
				(gr_poly
					(pts
						(arc
							(start 0.3048 -0.2032)
							(mid 0.275042 -0.275042)
							(end 0.2032 -0.3048)
						)
						(arc
							(start -0.2032 -0.3048)
							(mid -0.275042 -0.275042)
							(end -0.3048 -0.2032)
						)
						(arc
							(start -0.3048 0.2032)
							(mid -0.275042 0.275042)
							(end -0.2032 0.3048)
						)
						(arc
							(start 0.2032 0.3048)
							(mid 0.275042 0.275042)
							(end 0.3048 0.2032)
						)
					)
					(width 0)
					(fill yes)
				)
			)
		)
	)
	(footprint ""
		(layer "F.Cu")
		(at 90.678 -10.033 180)
		(property "Reference" "R148"
			(at 0 0 180)
			(layer "F.SilkS")
			(hide yes)
			(effects
				(font
					(size 1.27 1.27)
				)
			)
		)
		(property "Value" "300KR2F-GP"
			(at 0.064008 -3.993896 180)
			(unlocked yes)
			(layer "F.Fab")
			(hide yes)
			(effects
				(font
					(size 1.016 1.016)
					(thickness 0.1524)
				)
			)
		)
		(property "Device Type" "R402H16"
			(at 0.064008 -5.517896 180)
			(unlocked yes)
			(layer "F.Fab")
			(hide yes)
			(effects
				(font
					(size 1.016 1.016)
					(thickness 0.1524)
				)
			)
		)
		(duplicate_pad_numbers_are_jumpers no)
		(fp_line
			(start 0.508 -0.9398)
			(end -0.508 -0.9398)
			(stroke
				(width 0.1524)
				(type default)
			)
			(layer "F.SilkS")
		)
		(fp_line
			(start -0.508 -0.9398)
			(end -0.508 0.9398)
			(stroke
				(width 0.1524)
				(type default)
			)
			(layer "F.SilkS")
		)
		(fp_rect
			(start -0.508 0.9398)
			(end 0.508 -0.9398)
			(stroke
				(width 0)
				(type default)
			)
			(fill no)
			(layer "F.CrtYd")
		)
		(fp_rect
			(start -0.508 0.9398)
			(end 0.508 -0.9398)
			(stroke
				(width 0)
				(type default)
			)
			(fill no)
			(layer "F.Fab")
		)
		(pad "1" smd custom
			(at 0 -0.4445 180)
			(size 0.1397 0.1397)
			(layers "F.Cu" "F.Mask" "F.Paste")
			(net "SW_SW_L_N_0")
			(options
				(clearance outline)
				(anchor circle)
			)
			(primitives
				(gr_poly
					(pts
						(arc
							(start -0.1778 -0.2794)
							(mid -0.249642 -0.249642)
							(end -0.2794 -0.1778)
						)
						(arc
							(start -0.2794 0.1778)
							(mid -0.249642 0.249642)
							(end -0.1778 0.2794)
						)
						(arc
							(start 0.1778 0.2794)
							(mid 0.249642 0.249642)
							(end 0.2794 0.1778)
						)
						(arc
							(start 0.2794 -0.1778)
							(mid 0.249642 -0.249642)
							(end 0.1778 -0.2794)
						)
					)
					(width 0)
					(fill yes)
				)
			)
		)
		(pad "2" smd custom
			(at 0 0.4445 180)
			(size 0.1397 0.1397)
			(layers "F.Cu" "F.Mask" "F.Paste")
			(net "P12V")
			(options
				(clearance outline)
				(anchor circle)
			)
			(primitives
				(gr_poly
					(pts
						(arc
							(start -0.1778 -0.2794)
							(mid -0.249642 -0.249642)
							(end -0.2794 -0.1778)
						)
						(arc
							(start -0.2794 0.1778)
							(mid -0.249642 0.249642)
							(end -0.1778 0.2794)
						)
						(arc
							(start 0.1778 0.2794)
							(mid 0.249642 0.249642)
							(end 0.2794 0.1778)
						)
						(arc
							(start 0.2794 -0.1778)
							(mid 0.249642 -0.249642)
							(end 0.1778 -0.2794)
						)
					)
					(width 0)
					(fill yes)
				)
			)
		)
	)
	(footprint ""
		(layer "F.Cu")
		(at 56.82488 -8.609838 -90)
		(property "Reference" "R11"
			(at 0 0 270)
			(layer "F.SilkS")
			(hide yes)
			(effects
				(font
					(size 1.27 1.27)
				)
			)
		)
		(property "Value" "10R3F-GP"
			(at -0.0254 -2.5146 270)
			(unlocked yes)
			(layer "F.Fab")
			(hide yes)
			(effects
				(font
					(size 1.016 1.016)
					(thickness 0.1524)
				)
			)
		)
		(property "Device Type" "R603H22"
			(at -0.0254 -4.0386 270)
			(unlocked yes)
			(layer "F.Fab")
			(hide yes)
			(effects
				(font
					(size 1.016 1.016)
					(thickness 0.1524)
				)
			)
		)
		(duplicate_pad_numbers_are_jumpers no)
		(fp_line
			(start -0.4826 0)
			(end -0.2032 0)
			(stroke
				(width 0.2032)
				(type default)
			)
			(layer "F.SilkS")
		)
		(fp_line
			(start 0.2032 0)
			(end 0.4826 0)
			(stroke
				(width 0.2032)
				(type default)
			)
			(layer "F.SilkS")
		)
		(fp_rect
			(start -0.5842 1.3335)
			(end 0.5842 -1.3335)
			(stroke
				(width 0)
				(type default)
			)
			(fill no)
			(layer "F.CrtYd")
		)
		(fp_rect
			(start -0.5842 1.3335)
			(end 0.5842 -1.3335)
			(stroke
				(width 0)
				(type default)
			)
			(fill no)
			(layer "F.Fab")
		)
		(pad "1" smd custom
			(at 0 -0.762 270)
			(size 0.2159 0.2159)
			(layers "F.Cu" "F.Mask" "F.Paste")
			(net "P12V_SW_L")
			(options
				(clearance outline)
				(anchor circle)
			)
			(primitives
				(gr_poly
					(pts
						(arc
							(start -0.3302 -0.4318)
							(mid -0.402042 -0.402042)
							(end -0.4318 -0.3302)
						)
						(arc
							(start -0.4318 0.3302)
							(mid -0.402042 0.402042)
							(end -0.3302 0.4318)
						)
						(arc
							(start 0.3302 0.4318)
							(mid 0.402042 0.402042)
							(end 0.4318 0.3302)
						)
						(arc
							(start 0.4318 -0.3302)
							(mid 0.402042 -0.402042)
							(end 0.3302 -0.4318)
						)
					)
					(width 0)
					(fill yes)
				)
			)
		)
		(pad "2" smd custom
			(at 0 0.762 270)
			(size 0.2159 0.2159)
			(layers "F.Cu" "F.Mask" "F.Paste")
			(net "12V_PRE_3")
			(options
				(clearance outline)
				(anchor circle)
			)
			(primitives
				(gr_poly
					(pts
						(arc
							(start -0.3302 -0.4318)
							(mid -0.402042 -0.402042)
							(end -0.4318 -0.3302)
						)
						(arc
							(start -0.4318 0.3302)
							(mid -0.402042 0.402042)
							(end -0.3302 0.4318)
						)
						(arc
							(start 0.3302 0.4318)
							(mid 0.402042 0.402042)
							(end 0.4318 0.3302)
						)
						(arc
							(start 0.4318 -0.3302)
							(mid 0.402042 -0.402042)
							(end 0.3302 -0.4318)
						)
					)
					(width 0)
					(fill yes)
				)
			)
		)
	)
	(footprint ""
		(layer "F.Cu")
		(at 68.603368 -12.333986 -90)
		(property "Reference" "R166"
			(at 0 0 270)
			(layer "F.SilkS")
			(hide yes)
			(effects
				(font
					(size 1.27 1.27)
				)
			)
		)
		(property "Value" "0R5J-5-GP"
			(at 0 -8.9535 270)
			(unlocked yes)
			(layer "F.Fab")
			(hide yes)
			(effects
				(font
					(size 1.27 1.016)
					(thickness 0.1524)
				)
			)
		)
		(property "Device Type" "R805H24"
			(at 0 -10.6299 270)
			(unlocked yes)
			(layer "F.Fab")
			(hide yes)
			(effects
				(font
					(size 1.27 1.016)
					(thickness 0.1524)
				)
			)
		)
		(duplicate_pad_numbers_are_jumpers no)
		(fp_line
			(start -0.889 1.7018)
			(end 0.889 1.7018)
			(stroke
				(width 0.1524)
				(type default)
			)
			(layer "F.SilkS")
		)
		(fp_line
			(start 0.889 1.7018)
			(end 0.889 -0.508)
			(stroke
				(width 0.1524)
				(type default)
			)
			(layer "F.SilkS")
		)
		(fp_line
			(start -0.889 0.0762)
			(end -0.889 1.7018)
			(stroke
				(width 0.1524)
				(type default)
			)
			(layer "F.SilkS")
		)
		(fp_line
			(start -0.889 -1.7018)
			(end -0.889 0.2794)
			(stroke
				(width 0.1524)
				(type default)
			)
			(layer "F.SilkS")
		)
		(fp_line
			(start 0.889 -1.7018)
			(end 0.889 -0.381)
			(stroke
				(width 0.1524)
				(type default)
			)
			(layer "F.SilkS")
		)
		(fp_line
			(start 0.889 -1.7018)
			(end -0.889 -1.7018)
			(stroke
				(width 0.1524)
				(type default)
			)
			(layer "F.SilkS")
		)
		(fp_poly
			(pts
				(xy 0.9652 -1.778) (xy 0.9652 1.778) (xy -0.9652 1.778) (xy -0.9652 -1.778)
			)
			(stroke
				(width 0)
				(type default)
			)
			(fill no)
			(layer "F.CrtYd")
		)
		(fp_rect
			(start -0.9652 1.778)
			(end 0.9652 -1.778)
			(stroke
				(width 0)
				(type default)
			)
			(fill no)
			(layer "F.Fab")
		)
		(pad "1" smd rect
			(at 0 -0.9652 270)
			(size 1.397 1.143)
			(layers "F.Cu" "F.Mask" "F.Paste")
			(net "P5V")
		)
		(pad "2" smd rect
			(at 0 0.9652 270)
			(size 1.397 1.143)
			(layers "F.Cu" "F.Mask" "F.Paste")
			(net "P5V_SW_L")
		)
	)
	(footprint ""
		(layer "F.Cu")
		(at 55.726076 -19.040348 -90)
		(property "Reference" "R12"
			(at 0 0 270)
			(layer "F.SilkS")
			(hide yes)
			(effects
				(font
					(size 1.27 1.27)
				)
			)
		)
		(property "Value" "10R3F-GP"
			(at -0.0254 -2.5146 270)
			(unlocked yes)
			(layer "F.Fab")
			(hide yes)
			(effects
				(font
					(size 1.016 1.016)
					(thickness 0.1524)
				)
			)
		)
		(property "Device Type" "R603H22"
			(at -0.0254 -4.0386 270)
			(unlocked yes)
			(layer "F.Fab")
			(hide yes)
			(effects
				(font
					(size 1.016 1.016)
					(thickness 0.1524)
				)
			)
		)
		(duplicate_pad_numbers_are_jumpers no)
		(fp_line
			(start -0.4826 0)
			(end -0.2032 0)
			(stroke
				(width 0.2032)
				(type default)
			)
			(layer "F.SilkS")
		)
		(fp_line
			(start 0.2032 0)
			(end 0.4826 0)
			(stroke
				(width 0.2032)
				(type default)
			)
			(layer "F.SilkS")
		)
		(fp_rect
			(start -0.5842 1.3335)
			(end 0.5842 -1.3335)
			(stroke
				(width 0)
				(type default)
			)
			(fill no)
			(layer "F.CrtYd")
		)
		(fp_rect
			(start -0.5842 1.3335)
			(end 0.5842 -1.3335)
			(stroke
				(width 0)
				(type default)
			)
			(fill no)
			(layer "F.Fab")
		)
		(pad "1" smd custom
			(at 0 -0.762 270)
			(size 0.2159 0.2159)
			(layers "F.Cu" "F.Mask" "F.Paste")
			(net "P12V_SW_L")
			(options
				(clearance outline)
				(anchor circle)
			)
			(primitives
				(gr_poly
					(pts
						(arc
							(start -0.3302 -0.4318)
							(mid -0.402042 -0.402042)
							(end -0.4318 -0.3302)
						)
						(arc
							(start -0.4318 0.3302)
							(mid -0.402042 0.402042)
							(end -0.3302 0.4318)
						)
						(arc
							(start 0.3302 0.4318)
							(mid 0.402042 0.402042)
							(end 0.4318 0.3302)
						)
						(arc
							(start 0.4318 -0.3302)
							(mid 0.402042 -0.402042)
							(end 0.3302 -0.4318)
						)
					)
					(width 0)
					(fill yes)
				)
			)
		)
		(pad "2" smd custom
			(at 0 0.762 270)
			(size 0.2159 0.2159)
			(layers "F.Cu" "F.Mask" "F.Paste")
			(net "12V_PRE_2")
			(options
				(clearance outline)
				(anchor circle)
			)
			(primitives
				(gr_poly
					(pts
						(arc
							(start -0.3302 -0.4318)
							(mid -0.402042 -0.402042)
							(end -0.4318 -0.3302)
						)
						(arc
							(start -0.4318 0.3302)
							(mid -0.402042 0.402042)
							(end -0.3302 0.4318)
						)
						(arc
							(start 0.3302 0.4318)
							(mid 0.402042 0.402042)
							(end 0.4318 0.3302)
						)
						(arc
							(start 0.4318 -0.3302)
							(mid 0.402042 -0.402042)
							(end 0.3302 -0.4318)
						)
					)
					(width 0)
					(fill yes)
				)
			)
		)
	)
	(footprint ""
		(layer "B.Cu")
		(at 69.144134 -6.621526 180)
		(property "Reference" "Q9"
			(at 0 0 0)
			(layer "B.SilkS")
			(hide yes)
			(effects
				(font
					(size 1.27 1.27)
				)
				(justify mirror)
			)
		)
		(property "Value" "2N7002K-1-GP"
			(at -0.127 -8.9662 180)
			(unlocked yes)
			(layer "B.Fab")
			(hide yes)
			(effects
				(font
					(size 1.016 1.016)
					(thickness 0.1524)
				)
				(justify mirror)
			)
		)
		(property "Device Type" "SOT23DGS2D4H44"
			(at -0.127 -10.4902 180)
			(unlocked yes)
			(layer "B.Fab")
			(hide yes)
			(effects
				(font
					(size 1.016 1.016)
					(thickness 0.1524)
				)
				(justify mirror)
			)
		)
		(duplicate_pad_numbers_are_jumpers no)
		(fp_line
			(start 1.651 1.778)
			(end -1.651 1.778)
			(stroke
				(width 0.1524)
				(type default)
			)
			(layer "B.SilkS")
		)
		(fp_line
			(start 1.651 -1.778)
			(end 1.651 1.778)
			(stroke
				(width 0.1524)
				(type default)
			)
			(layer "B.SilkS")
		)
		(fp_line
			(start -1.651 1.778)
			(end -1.651 -1.778)
			(stroke
				(width 0.1524)
				(type default)
			)
			(layer "B.SilkS")
		)
		(fp_line
			(start -1.651 -1.778)
			(end 1.651 -1.778)
			(stroke
				(width 0.1524)
				(type default)
			)
			(layer "B.SilkS")
		)
		(fp_poly
			(pts
				(xy 1.778 1.8796) (xy 1.778 -1.8796) (xy -1.778 -1.8796) (xy -1.778 1.8796)
			)
			(stroke
				(width 0)
				(type default)
			)
			(fill no)
			(layer "B.CrtYd")
		)
		(fp_poly
			(pts
				(xy 1.778 1.8796) (xy 1.778 -1.8796) (xy -1.778 -1.8796) (xy -1.778 1.8796)
			)
			(stroke
				(width 0)
				(type default)
			)
			(fill no)
			(layer "B.Fab")
		)
		(pad "D" smd custom
			(at 0 -0.9525)
			(size 0.1905 0.1905)
			(layers "B.Cu" "B.Mask" "B.Paste")
			(net "PWR_EN_L_P5V")
			(options
				(clearance outline)
				(anchor circle)
			)
			(primitives
				(gr_poly
					(pts
						(arc
							(start -0.1778 -0.5715)
							(mid -0.321484 -0.511984)
							(end -0.381 -0.3683)
						)
						(arc
							(start -0.381 0.3683)
							(mid -0.321484 0.511984)
							(end -0.1778 0.5715)
						)
						(arc
							(start 0.1778 0.5715)
							(mid 0.321484 0.511984)
							(end 0.381 0.3683)
						)
						(arc
							(start 0.381 -0.3683)
							(mid 0.321484 -0.511984)
							(end 0.1778 -0.5715)
						)
					)
					(width 0)
					(fill yes)
				)
			)
		)
		(pad "G" smd custom
			(at 0.98425 0.9525)
			(size 0.1905 0.1905)
			(layers "B.Cu" "B.Mask" "B.Paste")
			(net "PWR_EN_L_DELAY")
			(options
				(clearance outline)
				(anchor circle)
			)
			(primitives
				(gr_poly
					(pts
						(arc
							(start -0.1778 -0.5715)
							(mid -0.321484 -0.511984)
							(end -0.381 -0.3683)
						)
						(arc
							(start -0.381 0.3683)
							(mid -0.321484 0.511984)
							(end -0.1778 0.5715)
						)
						(arc
							(start 0.1778 0.5715)
							(mid 0.321484 0.511984)
							(end 0.381 0.3683)
						)
						(arc
							(start 0.381 -0.3683)
							(mid 0.321484 -0.511984)
							(end 0.1778 -0.5715)
						)
					)
					(width 0)
					(fill yes)
				)
			)
		)
		(pad "S" smd custom
			(at -0.98425 0.9525)
			(size 0.1905 0.1905)
			(layers "B.Cu" "B.Mask" "B.Paste")
			(net "GND")
			(options
				(clearance outline)
				(anchor circle)
			)
			(primitives
				(gr_poly
					(pts
						(arc
							(start -0.1778 -0.5715)
							(mid -0.321484 -0.511984)
							(end -0.381 -0.3683)
						)
						(arc
							(start -0.381 0.3683)
							(mid -0.321484 0.511984)
							(end -0.1778 0.5715)
						)
						(arc
							(start 0.1778 0.5715)
							(mid 0.321484 0.511984)
							(end 0.381 0.3683)
						)
						(arc
							(start 0.381 -0.3683)
							(mid 0.321484 -0.511984)
							(end 0.1778 -0.5715)
						)
					)
					(width 0)
					(fill yes)
				)
			)
		)
	)
	(footprint ""
		(layer "B.Cu")
		(at 131.520438 -27.121612 -90)
		(property "Reference" "C28"
			(at 0 0 90)
			(layer "B.SilkS")
			(hide yes)
			(effects
				(font
					(size 1.27 1.27)
				)
				(justify mirror)
			)
		)
		(property "Value" "SCD1U25V2KX-GP"
			(at -1.1811 -2.7051 270)
			(unlocked yes)
			(layer "B.Fab")
			(hide yes)
			(effects
				(font
					(size 1.016 1.016)
					(thickness 0.1524)
				)
				(justify mirror)
			)
		)
		(property "Device Type" "C402H22"
			(at -1.1811 -4.2291 270)
			(unlocked yes)
			(layer "B.Fab")
			(hide yes)
			(effects
				(font
					(size 1.016 1.016)
					(thickness 0.1524)
				)
				(justify mirror)
			)
		)
		(duplicate_pad_numbers_are_jumpers no)
		(fp_rect
			(start 0.4318 0.9525)
			(end -0.4318 -0.9525)
			(stroke
				(width 0)
				(type default)
			)
			(fill no)
			(layer "B.CrtYd")
		)
		(fp_rect
			(start 0.4318 0.9525)
			(end -0.4318 -0.9525)
			(stroke
				(width 0)
				(type default)
			)
			(fill no)
			(layer "B.Fab")
		)
		(pad "1" smd custom
			(at 0 -0.4445 90)
			(size 0.1524 0.1524)
			(layers "B.Cu" "B.Mask" "B.Paste")
			(net "P5V")
			(options
				(clearance outline)
				(anchor circle)
			)
			(primitives
				(gr_poly
					(pts
						(arc
							(start 0.3048 0.2032)
							(mid 0.275042 0.275042)
							(end 0.2032 0.3048)
						)
						(arc
							(start -0.2032 0.3048)
							(mid -0.275042 0.275042)
							(end -0.3048 0.2032)
						)
						(arc
							(start -0.3048 -0.2032)
							(mid -0.275042 -0.275042)
							(end -0.2032 -0.3048)
						)
						(arc
							(start 0.2032 -0.3048)
							(mid 0.275042 -0.275042)
							(end 0.3048 -0.2032)
						)
					)
					(width 0)
					(fill yes)
				)
			)
		)
		(pad "2" smd custom
			(at 0 0.4445 90)
			(size 0.1524 0.1524)
			(layers "B.Cu" "B.Mask" "B.Paste")
			(net "GND")
			(options
				(clearance outline)
				(anchor circle)
			)
			(primitives
				(gr_poly
					(pts
						(arc
							(start 0.3048 0.2032)
							(mid 0.275042 0.275042)
							(end 0.2032 0.3048)
						)
						(arc
							(start -0.2032 0.3048)
							(mid -0.275042 0.275042)
							(end -0.3048 0.2032)
						)
						(arc
							(start -0.3048 -0.2032)
							(mid -0.275042 -0.275042)
							(end -0.2032 -0.3048)
						)
						(arc
							(start 0.2032 -0.3048)
							(mid 0.275042 -0.275042)
							(end 0.3048 -0.2032)
						)
					)
					(width 0)
					(fill yes)
				)
			)
		)
	)
	(footprint ""
		(layer "B.Cu")
		(at 77.214476 -13.901928 90)
		(property "Reference" "PQ1"
			(at 0 0 90)
			(layer "B.SilkS")
			(hide yes)
			(effects
				(font
					(size 1.27 1.27)
				)
				(justify mirror)
			)
		)
		(property "Value" "MMBT3904W-GP-U"
			(at 2.5527 1.3716 90)
			(unlocked yes)
			(layer "B.Fab")
			(hide yes)
			(effects
				(font
					(size 1.016 1.016)
					(thickness 0.1524)
				)
				(justify mirror)
			)
		)
		(property "Device Type" "SOT323CBE2D2H44"
			(at 2.5527 -0.1524 90)
			(unlocked yes)
			(layer "B.Fab")
			(hide yes)
			(effects
				(font
					(size 1.016 1.016)
					(thickness 0.1524)
				)
				(justify mirror)
			)
		)
		(duplicate_pad_numbers_are_jumpers no)
		(fp_line
			(start 1.2573 -1.7399)
			(end -1.2573 -1.7399)
			(stroke
				(width 0.1524)
				(type default)
			)
			(layer "B.SilkS")
		)
		(fp_line
			(start -1.2573 -1.7399)
			(end -1.2573 1.7399)
			(stroke
				(width 0.1524)
				(type default)
			)
			(layer "B.SilkS")
		)
		(fp_line
			(start 1.2573 1.7399)
			(end 1.2573 -1.7399)
			(stroke
				(width 0.1524)
				(type default)
			)
			(layer "B.SilkS")
		)
		(fp_line
			(start -1.2573 1.7399)
			(end 1.2573 1.7399)
			(stroke
				(width 0.1524)
				(type default)
			)
			(layer "B.SilkS")
		)
		(fp_poly
			(pts
				(xy 0.95504 2.1209) (xy 0.65024 1.8161) (xy 0.34544 2.1209)
			)
			(stroke
				(width 0)
				(type default)
			)
			(fill yes)
			(layer "B.SilkS")
		)
		(fp_rect
			(start 1.5113 1.9939)
			(end -1.5113 -1.9939)
			(stroke
				(width 0)
				(type default)
			)
			(fill no)
			(layer "B.CrtYd")
		)
		(fp_poly
			(pts
				(xy 1.5113 1.9939) (xy 1.5113 -1.9939) (xy -1.5113 -1.9939) (xy -1.5113 1.9939)
			)
			(stroke
				(width 0)
				(type default)
			)
			(fill no)
			(layer "B.Fab")
		)
		(pad "B" smd custom
			(at 0.65024 0.9017 270)
			(size 0.1524 0.1524)
			(layers "B.Cu" "B.Mask" "B.Paste")
			(net "P5V_R_E1")
			(options
				(clearance outline)
				(anchor circle)
			)
			(primitives
				(gr_poly
					(pts
						(arc
							(start -0.098298 -0.5842)
							(mid -0.244131 -0.525866)
							(end -0.3048 -0.381)
						)
						(arc
							(start -0.3048 0.381)
							(mid -0.244112 0.525847)
							(end -0.098298 0.5842)
						)
						(arc
							(start 0.098298 0.5842)
							(mid 0.244131 0.525866)
							(end 0.3048 0.381)
						)
						(arc
							(start 0.3048 -0.381)
							(mid 0.244112 -0.525847)
							(end 0.098298 -0.5842)
						)
					)
					(width 0)
					(fill yes)
				)
			)
		)
		(pad "C" smd custom
			(at 0 -0.9017 270)
			(size 0.1524 0.1524)
			(layers "B.Cu" "B.Mask" "B.Paste")
			(net "P5V")
			(options
				(clearance outline)
				(anchor circle)
			)
			(primitives
				(gr_poly
					(pts
						(arc
							(start -0.098298 -0.5842)
							(mid -0.244131 -0.525866)
							(end -0.3048 -0.381)
						)
						(arc
							(start -0.3048 0.381)
							(mid -0.244112 0.525847)
							(end -0.098298 0.5842)
						)
						(arc
							(start 0.098298 0.5842)
							(mid 0.244131 0.525866)
							(end 0.3048 0.381)
						)
						(arc
							(start 0.3048 -0.381)
							(mid 0.244112 -0.525847)
							(end 0.098298 -0.5842)
						)
					)
					(width 0)
					(fill yes)
				)
			)
		)
		(pad "E" smd custom
			(at -0.65024 0.9017 270)
			(size 0.1524 0.1524)
			(layers "B.Cu" "B.Mask" "B.Paste")
			(net "P3V3")
			(options
				(clearance outline)
				(anchor circle)
			)
			(primitives
				(gr_poly
					(pts
						(arc
							(start -0.098298 -0.5842)
							(mid -0.244131 -0.525866)
							(end -0.3048 -0.381)
						)
						(arc
							(start -0.3048 0.381)
							(mid -0.244112 0.525847)
							(end -0.098298 0.5842)
						)
						(arc
							(start 0.098298 0.5842)
							(mid 0.244131 0.525866)
							(end 0.3048 0.381)
						)
						(arc
							(start 0.3048 -0.381)
							(mid 0.244112 -0.525847)
							(end 0.098298 -0.5842)
						)
					)
					(width 0)
					(fill yes)
				)
			)
		)
	)
	(footprint ""
		(layer "B.Cu")
		(at 82.2706 -35.941 90)
		(property "Reference" "D1"
			(at 0 0 90)
			(layer "B.SilkS")
			(hide yes)
			(effects
				(font
					(size 1.27 1.27)
				)
				(justify mirror)
			)
		)
		(property "Value" "LRB551V-30T1G-GP"
			(at 0 -6.7818 90)
			(unlocked yes)
			(layer "B.Fab")
			(hide yes)
			(effects
				(font
					(size 1.016 1.016)
					(thickness 0.1524)
				)
				(justify mirror)
			)
		)
		(property "Device Type" "SOD323AKH44"
			(at 0 -8.6868 90)
			(unlocked yes)
			(layer "B.Fab")
			(hide yes)
			(effects
				(font
					(size 1.016 1.016)
					(thickness 0.1524)
				)
				(justify mirror)
			)
		)
		(duplicate_pad_numbers_are_jumpers no)
		(fp_line
			(start 0.889 -1.9304)
			(end -0.889 -1.9304)
			(stroke
				(width 0.1524)
				(type default)
			)
			(layer "B.SilkS")
		)
		(fp_line
			(start -0.889 -1.9304)
			(end -0.889 2.159)
			(stroke
				(width 0.1524)
				(type default)
			)
			(layer "B.SilkS")
		)
		(fp_line
			(start -0.762 2.0574)
			(end 0.762 2.0574)
			(stroke
				(width 0.508)
				(type default)
			)
			(layer "B.SilkS")
		)
		(fp_line
			(start 0.889 2.159)
			(end 0.889 -1.9304)
			(stroke
				(width 0.1524)
				(type default)
			)
			(layer "B.SilkS")
		)
		(fp_line
			(start -0.889 2.159)
			(end 0.889 2.159)
			(stroke
				(width 0.1524)
				(type default)
			)
			(layer "B.SilkS")
		)
		(fp_rect
			(start 1.016 2.3114)
			(end -1.016 -2.0066)
			(stroke
				(width 0)
				(type default)
			)
			(fill no)
			(layer "B.CrtYd")
		)
		(fp_poly
			(pts
				(xy 1.016 -2.0066) (xy -1.016 -2.0066) (xy -1.016 2.3114) (xy 1.016 2.3114)
			)
			(stroke
				(width 0)
				(type default)
			)
			(fill no)
			(layer "B.Fab")
		)
		(pad "A" smd rect
			(at 0 -1.143 270)
			(size 0.5588 1.016)
			(layers "B.Cu" "B.Mask" "B.Paste")
			(net "SW_SW_R_0")
		)
		(pad "K" smd rect
			(at 0 1.143 270)
			(size 0.5588 1.016)
			(layers "B.Cu" "B.Mask" "B.Paste")
			(net "SW_SW_R_N_0")
		)
	)
	(footprint ""
		(layer "B.Cu")
		(at 71.395082 -7.169912 180)
		(property "Reference" "C517"
			(at 0 0 0)
			(layer "B.SilkS")
			(hide yes)
			(effects
				(font
					(size 1.27 1.27)
				)
				(justify mirror)
			)
		)
		(property "Value" "SCD033U25V2KX-GP"
			(at -1.1811 -2.7051 180)
			(unlocked yes)
			(layer "B.Fab")
			(hide yes)
			(effects
				(font
					(size 1.016 1.016)
					(thickness 0.1524)
				)
				(justify mirror)
			)
		)
		(property "Device Type" "C402H22"
			(at -1.1811 -4.2291 180)
			(unlocked yes)
			(layer "B.Fab")
			(hide yes)
			(effects
				(font
					(size 1.016 1.016)
					(thickness 0.1524)
				)
				(justify mirror)
			)
		)
		(duplicate_pad_numbers_are_jumpers no)
		(fp_rect
			(start 0.4318 0.9525)
			(end -0.4318 -0.9525)
			(stroke
				(width 0)
				(type default)
			)
			(fill no)
			(layer "B.CrtYd")
		)
		(fp_rect
			(start 0.4318 0.9525)
			(end -0.4318 -0.9525)
			(stroke
				(width 0)
				(type default)
			)
			(fill no)
			(layer "B.Fab")
		)
		(pad "1" smd custom
			(at 0 -0.4445)
			(size 0.1524 0.1524)
			(layers "B.Cu" "B.Mask" "B.Paste")
			(net "PWR_EN_L_P5V")
			(options
				(clearance outline)
				(anchor circle)
			)
			(primitives
				(gr_poly
					(pts
						(arc
							(start 0.3048 0.2032)
							(mid 0.275042 0.275042)
							(end 0.2032 0.3048)
						)
						(arc
							(start -0.2032 0.3048)
							(mid -0.275042 0.275042)
							(end -0.3048 0.2032)
						)
						(arc
							(start -0.3048 -0.2032)
							(mid -0.275042 -0.275042)
							(end -0.2032 -0.3048)
						)
						(arc
							(start 0.2032 -0.3048)
							(mid 0.275042 -0.275042)
							(end 0.3048 -0.2032)
						)
					)
					(width 0)
					(fill yes)
				)
			)
		)
		(pad "2" smd custom
			(at 0 0.4445)
			(size 0.1524 0.1524)
			(layers "B.Cu" "B.Mask" "B.Paste")
			(net "GND")
			(options
				(clearance outline)
				(anchor circle)
			)
			(primitives
				(gr_poly
					(pts
						(arc
							(start 0.3048 0.2032)
							(mid 0.275042 0.275042)
							(end 0.2032 0.3048)
						)
						(arc
							(start -0.2032 0.3048)
							(mid -0.275042 0.275042)
							(end -0.3048 0.2032)
						)
						(arc
							(start -0.3048 -0.2032)
							(mid -0.275042 -0.275042)
							(end -0.2032 -0.3048)
						)
						(arc
							(start 0.2032 -0.3048)
							(mid 0.275042 -0.275042)
							(end 0.3048 -0.2032)
						)
					)
					(width 0)
					(fill yes)
				)
			)
		)
	)
	(footprint ""
		(layer "B.Cu")
		(at 79.414878 -22.079966 -90)
		(property "Reference" "MISAS1"
			(at 0 0 90)
			(layer "B.SilkS")
			(hide yes)
			(effects
				(font
					(size 1.27 1.27)
				)
				(justify mirror)
			)
		)
		(property "Value" "AMP-CONN36-4R-1-GP"
			(at 7.3279 -6.5278 270)
			(unlocked yes)
			(layer "B.Fab")
			(hide yes)
			(effects
				(font
					(size 1.016 1.016)
					(thickness 0.1524)
				)
				(justify mirror)
			)
		)
		(property "Device Type" "G40H2132212HR-W"
			(at 7.3279 -8.0518 270)
			(unlocked yes)
			(layer "B.Fab")
			(hide yes)
			(effects
				(font
					(size 1.016 1.016)
					(thickness 0.1524)
				)
				(justify mirror)
			)
		)
		(duplicate_pad_numbers_are_jumpers no)
		(fp_line
			(start 3.2512 6.2611)
			(end 2.794 6.2611)
			(stroke
				(width 0.3302)
				(type default)
			)
			(layer "B.SilkS")
		)
		(fp_line
			(start -6.3373 6.1722)
			(end 6.3373 6.1722)
			(stroke
				(width 0.1524)
				(type default)
			)
			(layer "B.SilkS")
		)
		(fp_line
			(start 6.3373 6.1722)
			(end 6.3373 -8.255)
			(stroke
				(width 0.1524)
				(type default)
			)
			(layer "B.SilkS")
		)
		(fp_line
			(start -4.459732 4.84759)
			(end -4.459732 3.88239)
			(stroke
				(width 0.3048)
				(type default)
			)
			(layer "B.SilkS")
		)
		(fp_line
			(start 6.390132 4.84759)
			(end 6.390132 3.88239)
			(stroke
				(width 0.3048)
				(type default)
			)
			(layer "B.SilkS")
		)
		(fp_line
			(start -6.390132 3.88239)
			(end -6.390132 4.84759)
			(stroke
				(width 0.3048)
				(type default)
			)
			(layer "B.SilkS")
		)
		(fp_line
			(start 4.459732 3.88239)
			(end 4.459732 4.84759)
			(stroke
				(width 0.3048)
				(type default)
			)
			(layer "B.SilkS")
		)
		(fp_line
			(start -4.459732 -4.072382)
			(end -4.459732 -5.037582)
			(stroke
				(width 0.3048)
				(type default)
			)
			(layer "B.SilkS")
		)
		(fp_line
			(start 6.390132 -4.072382)
			(end 6.390132 -5.037582)
			(stroke
				(width 0.3048)
				(type default)
			)
			(layer "B.SilkS")
		)
		(fp_line
			(start -6.390132 -5.037582)
			(end -6.390132 -4.072382)
			(stroke
				(width 0.3048)
				(type default)
			)
			(layer "B.SilkS")
		)
		(fp_line
			(start 4.459732 -5.037582)
			(end 4.459732 -4.072382)
			(stroke
				(width 0.3048)
				(type default)
			)
			(layer "B.SilkS")
		)
		(fp_line
			(start -6.3373 -8.255)
			(end -6.3373 6.1722)
			(stroke
				(width 0.1524)
				(type default)
			)
			(layer "B.SilkS")
		)
		(fp_line
			(start -3.3782 -8.255)
			(end -6.3373 -8.255)
			(stroke
				(width 0.1524)
				(type default)
			)
			(layer "B.SilkS")
		)
		(fp_line
			(start 3.3782 -8.255)
			(end 3.3782 -8.509)
			(stroke
				(width 0.1524)
				(type default)
			)
			(layer "B.SilkS")
		)
		(fp_line
			(start 6.3373 -8.255)
			(end 3.3782 -8.255)
			(stroke
				(width 0.1524)
				(type default)
			)
			(layer "B.SilkS")
		)
		(fp_line
			(start -3.3782 -8.509)
			(end -3.3782 -8.255)
			(stroke
				(width 0.1524)
				(type default)
			)
			(layer "B.SilkS")
		)
		(fp_line
			(start 3.3782 -8.509)
			(end -3.3782 -8.509)
			(stroke
				(width 0.1524)
				(type default)
			)
			(layer "B.SilkS")
		)
		(fp_arc
			(start -4.459732 4.84759)
			(mid -5.424934 5.81278)
			(end -6.390132 4.84759)
			(stroke
				(width 0.3048)
				(type default)
			)
			(layer "B.SilkS")
		)
		(fp_arc
			(start 6.390132 4.84759)
			(mid 5.424966 5.812744)
			(end 4.459732 4.84759)
			(stroke
				(width 0.3048)
				(type default)
			)
			(layer "B.SilkS")
		)
		(fp_arc
			(start -6.390132 3.88239)
			(mid -5.424934 2.91718)
			(end -4.459732 3.88239)
			(stroke
				(width 0.3048)
				(type default)
			)
			(layer "B.SilkS")
		)
		(fp_arc
			(start 4.459732 3.88239)
			(mid 5.424966 2.917144)
			(end 6.390132 3.88239)
			(stroke
				(width 0.3048)
				(type default)
			)
			(layer "B.SilkS")
		)
		(fp_arc
			(start -4.459732 -4.072382)
			(mid -5.424934 -3.10722)
			(end -6.390132 -4.072382)
			(stroke
				(width 0.3048)
				(type default)
			)
			(layer "B.SilkS")
		)
		(fp_arc
			(start 6.390132 -4.072382)
			(mid 5.424966 -3.107256)
			(end 4.459732 -4.072382)
			(stroke
				(width 0.3048)
				(type default)
			)
			(layer "B.SilkS")
		)
		(fp_arc
			(start -6.390132 -5.037582)
			(mid -5.424934 -6.00282)
			(end -4.459732 -5.037582)
			(stroke
				(width 0.3048)
				(type default)
			)
			(layer "B.SilkS")
		)
		(fp_arc
			(start 4.459732 -5.037582)
			(mid 5.424966 -6.002856)
			(end 6.390132 -5.037582)
			(stroke
				(width 0.3048)
				(type default)
			)
			(layer "B.SilkS")
		)
		(fp_poly
			(pts
				(xy 3.002026 6.23951) (xy 3.637026 6.87451) (xy 2.367026 6.87451)
			)
			(stroke
				(width 0)
				(type default)
			)
			(fill yes)
			(layer "B.SilkS")
		)
		(fp_poly
			(pts
				(xy 3.177794 1.930146) (xy 3.177794 3.029966) (xy -3.177794 3.029966) (xy -3.177794 1.930146)
			)
			(stroke
				(width 0)
				(type default)
			)
			(fill yes)
			(layer "B.SilkS")
		)
		(fp_poly
			(pts
				(xy 3.177794 -1.599946) (xy 3.177794 0.329946) (xy -3.177794 0.329946) (xy -3.177794 -1.599946)
			)
			(stroke
				(width 0)
				(type default)
			)
			(fill yes)
			(layer "B.SilkS")
		)
		(fp_poly
			(pts
				(xy 3.177794 -4.299966) (xy 3.177794 -3.200146) (xy -3.177794 -3.200146) (xy -3.177794 -4.299966)
			)
			(stroke
				(width 0)
				(type default)
			)
			(fill yes)
			(layer "B.SilkS")
		)
		(fp_poly
			(pts
				(xy 6.0833 5.9182) (xy 6.0833 -8.001) (xy 3.1242 -8.001) (xy 3.1242 -8.255) (xy -3.1242 -8.255)
				(xy -3.1242 -8.001) (xy -6.0833 -8.001) (xy -6.0833 5.9182)
			)
			(stroke
				(width 0)
				(type default)
			)
			(fill no)
			(layer "B.CrtYd")
		)
		(fp_poly
			(pts
				(xy 6.5913 6.4262) (xy 6.5913 -8.509) (xy 3.6322 -8.509) (xy 3.6322 -8.763) (xy -3.6322 -8.763)
				(xy -3.6322 -8.509) (xy -6.5913 -8.509) (xy -6.5913 -0.00635) (xy -6.0833 -0.00635) (xy -6.0833 -8.001)
				(xy -3.1242 -8.001) (xy -3.1242 -8.255) (xy 3.1242 -8.255) (xy 3.1242 -8.001) (xy 6.0833 -8.001)
				(xy 6.0833 5.9182) (xy -6.0833 5.9182) (xy -6.0833 0.00635) (xy -6.5913 0.00635) (xy -6.5913 6.4262)
			)
			(stroke
				(width 0)
				(type default)
			)
			(fill no)
			(layer "B.CrtYd")
		)
		(fp_poly
			(pts
				(xy 6.5913 6.4262) (xy 6.5913 -8.509) (xy 3.6322 -8.509) (xy 3.6322 -8.763) (xy -3.6322 -8.763)
				(xy -3.6322 -8.509) (xy -6.5913 -8.509) (xy -6.5913 6.4262)
			)
			(stroke
				(width 0)
				(type default)
			)
			(fill no)
			(layer "B.Fab")
		)
		(pad "" np_thru_hole circle
			(at -5.279898 0 90)
			(size 0.254 0.254)
			(drill 1.2192)
			(layers "*.Cu" "*.Mask")
			(clearance 0.8382)
			(thermal_gap 0.8382)
		)
		(pad "" np_thru_hole circle
			(at 5.279898 0 90)
			(size 0.254 0.254)
			(drill 1.2192)
			(layers "*.Cu" "*.Mask")
			(clearance 0.8382)
			(thermal_gap 0.8382)
		)
		(pad "37" thru_hole oval
			(at 5.424932 -4.554982 90)
			(size 1.2192 2.1844)
			(drill oval 0.508 1.4732)
			(layers "*.Cu" "*.Mask")
			(remove_unused_layers no)
			(net "Net_116")
			(clearance 0.1524)
			(thermal_gap 0.1524)
		)
		(pad "38" thru_hole oval
			(at 5.424932 4.36499 90)
			(size 1.2192 2.1844)
			(drill oval 0.508 1.4732)
			(layers "*.Cu" "*.Mask")
			(remove_unused_layers no)
			(net "Net_118")
			(clearance 0.1524)
			(thermal_gap 0.1524)
		)
		(pad "39" thru_hole oval
			(at -5.424932 -4.554982 90)
			(size 1.2192 2.1844)
			(drill oval 0.508 1.4732)
			(layers "*.Cu" "*.Mask")
			(remove_unused_layers no)
			(net "Net_105")
			(clearance 0.1524)
			(thermal_gap 0.1524)
		)
		(pad "40" thru_hole oval
			(at -5.424932 4.36499 90)
			(size 1.2192 2.1844)
			(drill oval 0.508 1.4732)
			(layers "*.Cu" "*.Mask")
			(remove_unused_layers no)
			(net "Net_107")
			(clearance 0.1524)
			(thermal_gap 0.1524)
		)
		(pad "A1" smd rect
			(at 2.999994 3.830066 90)
			(size 0.3556 1.1938)
			(layers "B.Cu" "B.Mask" "B.Paste")
			(net "Net_114")
		)
		(pad "A2" smd rect
			(at 2.249932 3.830066 90)
			(size 0.3556 1.1938)
			(layers "B.Cu" "B.Mask" "B.Paste")
			(net "Net_115")
		)
		(pad "A3" smd rect
			(at 1.500124 3.830066 90)
			(size 0.3556 1.1938)
			(layers "B.Cu" "B.Mask" "B.Paste")
			(net "GND")
		)
		(pad "A4" smd rect
			(at 0.750062 3.830066 90)
			(size 0.3556 1.1938)
			(layers "B.Cu" "B.Mask" "B.Paste")
			(net "HBA_MB_RX_P1")
		)
		(pad "A5" smd rect
			(at 0 3.830066 90)
			(size 0.3556 1.1938)
			(layers "B.Cu" "B.Mask" "B.Paste")
			(net "HBA_MB_RX_N1")
		)
		(pad "A6" smd rect
			(at -0.750062 3.830066 90)
			(size 0.3556 1.1938)
			(layers "B.Cu" "B.Mask" "B.Paste")
			(net "GND")
		)
		(pad "A7" smd rect
			(at -1.500124 3.830066 90)
			(size 0.3556 1.1938)
			(layers "B.Cu" "B.Mask" "B.Paste")
			(net "HBA_MB_RX_P3")
		)
		(pad "A8" smd rect
			(at -2.249932 3.830066 90)
			(size 0.3556 1.1938)
			(layers "B.Cu" "B.Mask" "B.Paste")
			(net "HBA_MB_RX_N3")
		)
		(pad "A9" smd rect
			(at -2.999994 3.830066 90)
			(size 0.3556 1.1938)
			(layers "B.Cu" "B.Mask" "B.Paste")
			(net "GND")
		)
		(pad "B1" smd rect
			(at 2.999994 1.130046 90)
			(size 0.3556 1.1938)
			(layers "B.Cu" "B.Mask" "B.Paste")
			(net "Net_112")
		)
		(pad "B2" smd rect
			(at 2.249932 1.130046 90)
			(size 0.3556 1.1938)
			(layers "B.Cu" "B.Mask" "B.Paste")
			(net "Net_113")
		)
		(pad "B3" smd rect
			(at 1.500124 1.130046 90)
			(size 0.3556 1.1938)
			(layers "B.Cu" "B.Mask" "B.Paste")
			(net "GND")
		)
		(pad "B4" smd rect
			(at 0.750062 1.130046 90)
			(size 0.3556 1.1938)
			(layers "B.Cu" "B.Mask" "B.Paste")
			(net "HBA_MB_RX_P0")
		)
		(pad "B5" smd rect
			(at 0 1.130046 90)
			(size 0.3556 1.1938)
			(layers "B.Cu" "B.Mask" "B.Paste")
			(net "HBA_MB_RX_N0")
		)
		(pad "B6" smd rect
			(at -0.750062 1.130046 90)
			(size 0.3556 1.1938)
			(layers "B.Cu" "B.Mask" "B.Paste")
			(net "GND")
		)
		(pad "B7" smd rect
			(at -1.500124 1.130046 90)
			(size 0.3556 1.1938)
			(layers "B.Cu" "B.Mask" "B.Paste")
			(net "HBA_MB_RX_P2")
		)
		(pad "B8" smd rect
			(at -2.249932 1.130046 90)
			(size 0.3556 1.1938)
			(layers "B.Cu" "B.Mask" "B.Paste")
			(net "HBA_MB_RX_N2")
		)
		(pad "B9" smd rect
			(at -2.999994 1.130046 90)
			(size 0.3556 1.1938)
			(layers "B.Cu" "B.Mask" "B.Paste")
			(net "GND")
		)
		(pad "C1" smd rect
			(at 2.999994 -2.400046 90)
			(size 0.3556 1.1938)
			(layers "B.Cu" "B.Mask" "B.Paste")
			(net "Net_108")
		)
		(pad "C2" smd rect
			(at 2.249932 -2.400046 90)
			(size 0.3556 1.1938)
			(layers "B.Cu" "B.Mask" "B.Paste")
			(net "Net_109")
		)
		(pad "C3" smd rect
			(at 1.500124 -2.400046 90)
			(size 0.3556 1.1938)
			(layers "B.Cu" "B.Mask" "B.Paste")
			(net "GND")
		)
		(pad "C4" smd rect
			(at 0.750062 -2.400046 90)
			(size 0.3556 1.1938)
			(layers "B.Cu" "B.Mask" "B.Paste")
			(net "HBA_MB_TX_P1")
		)
		(pad "C5" smd rect
			(at 0 -2.400046 90)
			(size 0.3556 1.1938)
			(layers "B.Cu" "B.Mask" "B.Paste")
			(net "HBA_MB_TX_N1")
		)
		(pad "C6" smd rect
			(at -0.750062 -2.400046 90)
			(size 0.3556 1.1938)
			(layers "B.Cu" "B.Mask" "B.Paste")
			(net "GND")
		)
		(pad "C7" smd rect
			(at -1.500124 -2.400046 90)
			(size 0.3556 1.1938)
			(layers "B.Cu" "B.Mask" "B.Paste")
			(net "HBA_MB_TX_P3")
		)
		(pad "C8" smd rect
			(at -2.249932 -2.400046 90)
			(size 0.3556 1.1938)
			(layers "B.Cu" "B.Mask" "B.Paste")
			(net "HBA_MB_TX_N3")
		)
		(pad "C9" smd rect
			(at -2.999994 -2.400046 90)
			(size 0.3556 1.1938)
			(layers "B.Cu" "B.Mask" "B.Paste")
			(net "GND")
		)
		(pad "D1" smd rect
			(at 2.999994 -5.100066 90)
			(size 0.3556 1.1938)
			(layers "B.Cu" "B.Mask" "B.Paste")
			(net "Net_110")
		)
		(pad "D2" smd rect
			(at 2.249932 -5.100066 90)
			(size 0.3556 1.1938)
			(layers "B.Cu" "B.Mask" "B.Paste")
			(net "Net_111")
		)
		(pad "D3" smd rect
			(at 1.500124 -5.100066 90)
			(size 0.3556 1.1938)
			(layers "B.Cu" "B.Mask" "B.Paste")
			(net "GND")
		)
		(pad "D4" smd rect
			(at 0.750062 -5.100066 90)
			(size 0.3556 1.1938)
			(layers "B.Cu" "B.Mask" "B.Paste")
			(net "HBA_MB_TX_P0")
		)
		(pad "D5" smd rect
			(at 0 -5.100066 90)
			(size 0.3556 1.1938)
			(layers "B.Cu" "B.Mask" "B.Paste")
			(net "HBA_MB_TX_N0")
		)
		(pad "D6" smd rect
			(at -0.750062 -5.100066 90)
			(size 0.3556 1.1938)
			(layers "B.Cu" "B.Mask" "B.Paste")
			(net "GND")
		)
		(pad "D7" smd rect
			(at -1.500124 -5.100066 90)
			(size 0.3556 1.1938)
			(layers "B.Cu" "B.Mask" "B.Paste")
			(net "HBA_MB_TX_P2")
		)
		(pad "D8" smd rect
			(at -2.249932 -5.100066 90)
			(size 0.3556 1.1938)
			(layers "B.Cu" "B.Mask" "B.Paste")
			(net "HBA_MB_TX_N2")
		)
		(pad "D9" smd rect
			(at -2.999994 -5.100066 90)
			(size 0.3556 1.1938)
			(layers "B.Cu" "B.Mask" "B.Paste")
			(net "GND")
		)
		(zone
			(layers "F.Cu" "B.Cu" "In1.Cu" "In2.Cu" "In3.Cu" "In4.Cu")
			(hatch none 0.5)
			(connect_pads
				(clearance 0)
			)
			(min_thickness 0.25)
			(keepout
				(tracks not_allowed)
				(vias allowed)
				(pads allowed)
				(copperpour not_allowed)
				(footprints allowed)
			)
			(placement
				(enabled no)
				(sheetname "")
			)
			(fill
				(thermal_gap 0.5)
				(thermal_bridge_width 0.5)
				(island_removal_mode 0)
			)
			(polygon
				(pts
					(arc
						(start 80.329278 -27.359864)
						(mid 78.500478 -27.359864)
						(end 80.329278 -27.359864)
					)
				)
			)
		)
		(zone
			(layers "F.Cu" "B.Cu" "In1.Cu" "In2.Cu" "In3.Cu" "In4.Cu")
			(hatch none 0.5)
			(connect_pads
				(clearance 0)
			)
			(min_thickness 0.25)
			(keepout
				(tracks not_allowed)
				(vias allowed)
				(pads allowed)
				(copperpour not_allowed)
				(footprints allowed)
			)
			(placement
				(enabled no)
				(sheetname "")
			)
			(fill
				(thermal_gap 0.5)
				(thermal_bridge_width 0.5)
				(island_removal_mode 0)
			)
			(polygon
				(pts
					(arc
						(start 80.329278 -16.800068)
						(mid 78.500478 -16.800068)
						(end 80.329278 -16.800068)
					)
				)
			)
		)
		(zone
			(layer "B.Cu")
			(hatch none 0.5)
			(connect_pads
				(clearance 0)
			)
			(min_thickness 0.25)
			(keepout
				(tracks allowed)
				(vias not_allowed)
				(pads allowed)
				(copperpour not_allowed)
				(footprints allowed)
			)
			(placement
				(enabled no)
				(sheetname "")
			)
			(fill
				(thermal_gap 0.5)
				(thermal_bridge_width 0.5)
				(island_removal_mode 0)
			)
			(polygon
				(pts
					(xy 76.689712 -18.902172) (xy 76.181712 -18.902172) (xy 76.181712 -25.25776) (xy 76.689712 -25.25776)
				)
			)
		)
		(zone
			(layer "B.Cu")
			(hatch none 0.5)
			(connect_pads
				(clearance 0)
			)
			(min_thickness 0.25)
			(keepout
				(tracks allowed)
				(vias not_allowed)
				(pads allowed)
				(copperpour not_allowed)
				(footprints allowed)
			)
			(placement
				(enabled no)
				(sheetname "")
			)
			(fill
				(thermal_gap 0.5)
				(thermal_bridge_width 0.5)
				(island_removal_mode 0)
			)
			(polygon
				(pts
					(xy 79.389732 -18.902172) (xy 78.881732 -18.902172) (xy 78.881732 -25.25776) (xy 79.389732 -25.25776)
				)
			)
		)
		(zone
			(layer "B.Cu")
			(hatch none 0.5)
			(connect_pads
				(clearance 0)
			)
			(min_thickness 0.25)
			(keepout
				(tracks allowed)
				(vias not_allowed)
				(pads allowed)
				(copperpour not_allowed)
				(footprints allowed)
			)
			(placement
				(enabled no)
				(sheetname "")
			)
			(fill
				(thermal_gap 0.5)
				(thermal_bridge_width 0.5)
				(island_removal_mode 0)
			)
			(polygon
				(pts
					(xy 81.218024 -18.902172) (xy 80.710024 -18.902172) (xy 80.710024 -25.25776) (xy 81.218024 -25.25776)
				)
			)
		)
		(zone
			(layer "B.Cu")
			(hatch none 0.5)
			(connect_pads
				(clearance 0)
			)
			(min_thickness 0.25)
			(keepout
				(tracks allowed)
				(vias not_allowed)
				(pads allowed)
				(copperpour not_allowed)
				(footprints allowed)
			)
			(placement
				(enabled no)
				(sheetname "")
			)
			(fill
				(thermal_gap 0.5)
				(thermal_bridge_width 0.5)
				(island_removal_mode 0)
			)
			(polygon
				(pts
					(xy 83.918044 -18.902172) (xy 83.410044 -18.902172) (xy 83.410044 -25.25776) (xy 83.918044 -25.25776)
				)
			)
		)
	)
	(footprint ""
		(layer "B.Cu")
		(at 73.794366 -14.873478 90)
		(property "Reference" "PR1"
			(at 0 0 90)
			(layer "B.SilkS")
			(hide yes)
			(effects
				(font
					(size 1.27 1.27)
				)
				(justify mirror)
			)
		)
		(property "Value" "1K2R3F-GP"
			(at 0.0254 -2.5146 90)
			(unlocked yes)
			(layer "B.Fab")
			(hide yes)
			(effects
				(font
					(size 1.016 1.016)
					(thickness 0.1524)
				)
				(justify mirror)
			)
		)
		(property "Device Type" "R603H22"
			(at 0.0254 -4.0386 90)
			(unlocked yes)
			(layer "B.Fab")
			(hide yes)
			(effects
				(font
					(size 1.016 1.016)
					(thickness 0.1524)
				)
				(justify mirror)
			)
		)
		(duplicate_pad_numbers_are_jumpers no)
		(fp_line
			(start 0.4826 0)
			(end 0.2032 0)
			(stroke
				(width 0.2032)
				(type default)
			)
			(layer "B.SilkS")
		)
		(fp_line
			(start -0.2032 0)
			(end -0.4826 0)
			(stroke
				(width 0.2032)
				(type default)
			)
			(layer "B.SilkS")
		)
		(fp_rect
			(start 0.5842 1.3335)
			(end -0.5842 -1.3335)
			(stroke
				(width 0)
				(type default)
			)
			(fill no)
			(layer "B.CrtYd")
		)
		(fp_rect
			(start 0.5842 1.3335)
			(end -0.5842 -1.3335)
			(stroke
				(width 0)
				(type default)
			)
			(fill no)
			(layer "B.Fab")
		)
		(pad "1" smd custom
			(at 0 -0.762 270)
			(size 0.2159 0.2159)
			(layers "B.Cu" "B.Mask" "B.Paste")
			(net "P5V")
			(options
				(clearance outline)
				(anchor circle)
			)
			(primitives
				(gr_poly
					(pts
						(arc
							(start -0.3302 0.4318)
							(mid -0.402042 0.402042)
							(end -0.4318 0.3302)
						)
						(arc
							(start -0.4318 -0.3302)
							(mid -0.402042 -0.402042)
							(end -0.3302 -0.4318)
						)
						(arc
							(start 0.3302 -0.4318)
							(mid 0.402042 -0.402042)
							(end 0.4318 -0.3302)
						)
						(arc
							(start 0.4318 0.3302)
							(mid 0.402042 0.402042)
							(end 0.3302 0.4318)
						)
					)
					(width 0)
					(fill yes)
				)
			)
		)
		(pad "2" smd custom
			(at 0 0.762 270)
			(size 0.2159 0.2159)
			(layers "B.Cu" "B.Mask" "B.Paste")
			(net "P5V_R_E1")
			(options
				(clearance outline)
				(anchor circle)
			)
			(primitives
				(gr_poly
					(pts
						(arc
							(start -0.3302 0.4318)
							(mid -0.402042 0.402042)
							(end -0.4318 0.3302)
						)
						(arc
							(start -0.4318 -0.3302)
							(mid -0.402042 -0.402042)
							(end -0.3302 -0.4318)
						)
						(arc
							(start 0.3302 -0.4318)
							(mid 0.402042 -0.402042)
							(end 0.4318 -0.3302)
						)
						(arc
							(start 0.4318 0.3302)
							(mid 0.402042 0.402042)
							(end 0.3302 0.4318)
						)
					)
					(width 0)
					(fill yes)
				)
			)
		)
	)
	(footprint ""
		(layer "B.Cu")
		(at 84.328 -45.212)
		(property "Reference" "R164"
			(at 0 0 0)
			(layer "B.SilkS")
			(hide yes)
			(effects
				(font
					(size 1.27 1.27)
				)
				(justify mirror)
			)
		)
		(property "Value" "4K7R2J-2-GP"
			(at -0.064008 -3.993896 0)
			(unlocked yes)
			(layer "B.Fab")
			(hide yes)
			(effects
				(font
					(size 1.016 1.016)
					(thickness 0.1524)
				)
				(justify mirror)
			)
		)
		(property "Device Type" "R402H16"
			(at -0.064008 -5.517896 0)
			(unlocked yes)
			(layer "B.Fab")
			(hide yes)
			(effects
				(font
					(size 1.016 1.016)
					(thickness 0.1524)
				)
				(justify mirror)
			)
		)
		(duplicate_pad_numbers_are_jumpers no)
		(fp_line
			(start -0.508 -0.9398)
			(end 0.508 -0.9398)
			(stroke
				(width 0.1524)
				(type default)
			)
			(layer "B.SilkS")
		)
		(fp_line
			(start 0.508 -0.9398)
			(end 0.508 0.9398)
			(stroke
				(width 0.1524)
				(type default)
			)
			(layer "B.SilkS")
		)
		(fp_rect
			(start 0.508 0.9398)
			(end -0.508 -0.9398)
			(stroke
				(width 0)
				(type default)
			)
			(fill no)
			(layer "B.CrtYd")
		)
		(fp_rect
			(start 0.508 0.9398)
			(end -0.508 -0.9398)
			(stroke
				(width 0)
				(type default)
			)
			(fill no)
			(layer "B.Fab")
		)
		(pad "1" smd custom
			(at 0 -0.4445 180)
			(size 0.1397 0.1397)
			(layers "B.Cu" "B.Mask" "B.Paste")
			(net "P12V")
			(options
				(clearance outline)
				(anchor circle)
			)
			(primitives
				(gr_poly
					(pts
						(arc
							(start -0.1778 0.2794)
							(mid -0.249642 0.249642)
							(end -0.2794 0.1778)
						)
						(arc
							(start -0.2794 -0.1778)
							(mid -0.249642 -0.249642)
							(end -0.1778 -0.2794)
						)
						(arc
							(start 0.1778 -0.2794)
							(mid 0.249642 -0.249642)
							(end 0.2794 -0.1778)
						)
						(arc
							(start 0.2794 0.1778)
							(mid 0.249642 0.249642)
							(end 0.1778 0.2794)
						)
					)
					(width 0)
					(fill yes)
				)
			)
		)
		(pad "2" smd custom
			(at 0 0.4445 180)
			(size 0.1397 0.1397)
			(layers "B.Cu" "B.Mask" "B.Paste")
			(net "PWR_EN_R_P5V")
			(options
				(clearance outline)
				(anchor circle)
			)
			(primitives
				(gr_poly
					(pts
						(arc
							(start -0.1778 0.2794)
							(mid -0.249642 0.249642)
							(end -0.2794 0.1778)
						)
						(arc
							(start -0.2794 -0.1778)
							(mid -0.249642 -0.249642)
							(end -0.1778 -0.2794)
						)
						(arc
							(start 0.1778 -0.2794)
							(mid 0.249642 -0.249642)
							(end 0.2794 -0.1778)
						)
						(arc
							(start 0.2794 0.1778)
							(mid 0.249642 0.249642)
							(end 0.1778 0.2794)
						)
					)
					(width 0)
					(fill yes)
				)
			)
		)
	)
	(footprint ""
		(layer "B.Cu")
		(at 90.0176 -7.4676 90)
		(property "Reference" "D3"
			(at 0 0 90)
			(layer "B.SilkS")
			(hide yes)
			(effects
				(font
					(size 1.27 1.27)
				)
				(justify mirror)
			)
		)
		(property "Value" "LRB551V-30T1G-GP"
			(at 0 -6.7818 90)
			(unlocked yes)
			(layer "B.Fab")
			(hide yes)
			(effects
				(font
					(size 1.016 1.016)
					(thickness 0.1524)
				)
				(justify mirror)
			)
		)
		(property "Device Type" "SOD323AKH44"
			(at 0 -8.6868 90)
			(unlocked yes)
			(layer "B.Fab")
			(hide yes)
			(effects
				(font
					(size 1.016 1.016)
					(thickness 0.1524)
				)
				(justify mirror)
			)
		)
		(duplicate_pad_numbers_are_jumpers no)
		(fp_line
			(start 0.889 -1.9304)
			(end -0.889 -1.9304)
			(stroke
				(width 0.1524)
				(type default)
			)
			(layer "B.SilkS")
		)
		(fp_line
			(start -0.889 -1.9304)
			(end -0.889 2.159)
			(stroke
				(width 0.1524)
				(type default)
			)
			(layer "B.SilkS")
		)
		(fp_line
			(start -0.762 2.0574)
			(end 0.762 2.0574)
			(stroke
				(width 0.508)
				(type default)
			)
			(layer "B.SilkS")
		)
		(fp_line
			(start 0.889 2.159)
			(end 0.889 -1.9304)
			(stroke
				(width 0.1524)
				(type default)
			)
			(layer "B.SilkS")
		)
		(fp_line
			(start -0.889 2.159)
			(end 0.889 2.159)
			(stroke
				(width 0.1524)
				(type default)
			)
			(layer "B.SilkS")
		)
		(fp_rect
			(start 1.016 2.3114)
			(end -1.016 -2.0066)
			(stroke
				(width 0)
				(type default)
			)
			(fill no)
			(layer "B.CrtYd")
		)
		(fp_poly
			(pts
				(xy 1.016 -2.0066) (xy -1.016 -2.0066) (xy -1.016 2.3114) (xy 1.016 2.3114)
			)
			(stroke
				(width 0)
				(type default)
			)
			(fill no)
			(layer "B.Fab")
		)
		(pad "A" smd rect
			(at 0 -1.143 270)
			(size 0.5588 1.016)
			(layers "B.Cu" "B.Mask" "B.Paste")
			(net "SW_SW_L_0")
		)
		(pad "K" smd rect
			(at 0 1.143 270)
			(size 0.5588 1.016)
			(layers "B.Cu" "B.Mask" "B.Paste")
			(net "SW_SW_L_N_0")
		)
	)
	(footprint ""
		(layer "B.Cu")
		(at 75.0062 -38.1 -90)
		(property "Reference" "C11"
			(at 0 0 90)
			(layer "B.SilkS")
			(hide yes)
			(effects
				(font
					(size 1.27 1.27)
				)
				(justify mirror)
			)
		)
		(property "Value" "SC10U25V6KX-1GP"
			(at 0.0762 -5.1308 270)
			(unlocked yes)
			(layer "B.Fab")
			(hide yes)
			(effects
				(font
					(size 1.016 1.016)
					(thickness 0.1524)
				)
				(justify mirror)
			)
		)
		(property "Device Type" "C1206H71"
			(at 0.127 -6.6548 270)
			(unlocked yes)
			(layer "B.Fab")
			(hide yes)
			(effects
				(font
					(size 1.016 1.016)
					(thickness 0.1524)
				)
				(justify mirror)
			)
		)
		(duplicate_pad_numbers_are_jumpers no)
		(fp_line
			(start -1.016 2.2352)
			(end 1.016 2.2352)
			(stroke
				(width 0.1524)
				(type default)
			)
			(layer "B.SilkS")
		)
		(fp_line
			(start 1.016 2.2352)
			(end 1.016 0.8382)
			(stroke
				(width 0.1524)
				(type default)
			)
			(layer "B.SilkS")
		)
		(fp_line
			(start -1.016 0.8382)
			(end -1.016 2.2352)
			(stroke
				(width 0.1524)
				(type default)
			)
			(layer "B.SilkS")
		)
		(fp_line
			(start 1.016 -0.8382)
			(end 1.016 -2.2352)
			(stroke
				(width 0.1524)
				(type default)
			)
			(layer "B.SilkS")
		)
		(fp_line
			(start -1.016 -2.2352)
			(end -1.016 -0.8382)
			(stroke
				(width 0.1524)
				(type default)
			)
			(layer "B.SilkS")
		)
		(fp_line
			(start 1.016 -2.2352)
			(end -1.016 -2.2352)
			(stroke
				(width 0.1524)
				(type default)
			)
			(layer "B.SilkS")
		)
		(fp_rect
			(start 1.0922 2.3114)
			(end -1.0922 -2.3114)
			(stroke
				(width 0)
				(type default)
			)
			(fill no)
			(layer "B.CrtYd")
		)
		(fp_poly
			(pts
				(xy -1.0922 -2.3114) (xy -1.0922 2.3114) (xy 1.0922 2.3114) (xy 1.0922 -2.3114)
			)
			(stroke
				(width 0)
				(type default)
			)
			(fill no)
			(layer "B.Fab")
		)
		(pad "1" smd rect
			(at 0 -1.397 90)
			(size 1.651 1.27)
			(layers "B.Cu" "B.Mask" "B.Paste")
			(net "P12V_SW_R")
		)
		(pad "2" smd rect
			(at 0 1.397 90)
			(size 1.651 1.27)
			(layers "B.Cu" "B.Mask" "B.Paste")
			(net "GND")
		)
	)
	(footprint ""
		(layer "B.Cu")
		(at 81.059274 -49.797716 90)
		(property "Reference" "Q1"
			(at 0 0 90)
			(layer "B.SilkS")
			(hide yes)
			(effects
				(font
					(size 1.27 1.27)
				)
				(justify mirror)
			)
		)
		(property "Value" "FDS8878-G-GP"
			(at 3.707384 -1.5367 90)
			(unlocked yes)
			(layer "B.Fab")
			(hide yes)
			(effects
				(font
					(size 1.016 1.016)
					(thickness 0.1524)
				)
				(justify mirror)
			)
		)
		(property "Device Type" "SOIC8H69"
			(at 3.707384 -3.0607 90)
			(unlocked yes)
			(layer "B.Fab")
			(hide yes)
			(effects
				(font
					(size 1.016 1.016)
					(thickness 0.1524)
				)
				(justify mirror)
			)
		)
		(duplicate_pad_numbers_are_jumpers no)
		(fp_line
			(start 2.7432 -1.4224)
			(end 2.7432 1.4224)
			(stroke
				(width 0.1524)
				(type default)
			)
			(layer "B.SilkS")
		)
		(fp_line
			(start -2.1336 -1.4224)
			(end 2.7432 -1.4224)
			(stroke
				(width 0.1524)
				(type default)
			)
			(layer "B.SilkS")
		)
		(fp_line
			(start 2.7178 -0.508)
			(end 2.1844 -0.0508)
			(stroke
				(width 0.1524)
				(type default)
			)
			(layer "B.SilkS")
		)
		(fp_line
			(start 2.1844 -0.0508)
			(end 2.7178 0.508)
			(stroke
				(width 0.1524)
				(type default)
			)
			(layer "B.SilkS")
		)
		(fp_line
			(start 2.7432 1.4224)
			(end 2.6416 1.4224)
			(stroke
				(width 0.1524)
				(type default)
			)
			(layer "B.SilkS")
		)
		(fp_line
			(start 2.7432 1.4224)
			(end -2.1336 1.4224)
			(stroke
				(width 0.1524)
				(type default)
			)
			(layer "B.SilkS")
		)
		(fp_line
			(start -2.1336 1.4224)
			(end -2.1336 -1.4224)
			(stroke
				(width 0.1524)
				(type default)
			)
			(layer "B.SilkS")
		)
		(fp_line
			(start 2.6289 3.4417)
			(end 2.6289 1.4732)
			(stroke
				(width 0.381)
				(type default)
			)
			(layer "B.SilkS")
		)
		(fp_poly
			(pts
				(xy 2.2098 -1.4224) (xy 2.2098 1.4224) (xy -2.2098 1.4224) (xy -2.2098 -1.4224)
			)
			(stroke
				(width 0)
				(type default)
			)
			(fill yes)
			(layer "B.SilkS")
		)
		(fp_rect
			(start 2.450084 2.999994)
			(end -2.450084 -2.999994)
			(stroke
				(width 0)
				(type default)
			)
			(fill no)
			(layer "B.CrtYd")
		)
		(fp_poly
			(pts
				(xy 2.8194 3.6322) (xy 2.8194 -3.6322) (xy -2.8194 -3.6322) (xy -2.8194 1.18364) (xy -2.450084 1.18364)
				(xy -2.450084 -2.999994) (xy 2.450084 -2.999994) (xy 2.450084 2.999994) (xy -2.450084 2.999994)
				(xy -2.450084 1.18618) (xy -2.8194 1.18618) (xy -2.8194 3.6322)
			)
			(stroke
				(width 0)
				(type default)
			)
			(fill no)
			(layer "B.CrtYd")
		)
		(fp_rect
			(start 2.8194 3.6322)
			(end -2.8194 -3.6322)
			(stroke
				(width 0)
				(type default)
			)
			(fill no)
			(layer "B.Fab")
		)
		(pad "1" smd rect
			(at 1.905 2.54 270)
			(size 0.635 1.651)
			(layers "B.Cu" "B.Mask" "B.Paste")
			(net "P5V")
		)
		(pad "2" smd rect
			(at 0.635 2.54 270)
			(size 0.635 1.651)
			(layers "B.Cu" "B.Mask" "B.Paste")
			(net "P5V")
		)
		(pad "3" smd rect
			(at -0.635 2.54 270)
			(size 0.635 1.651)
			(layers "B.Cu" "B.Mask" "B.Paste")
			(net "P5V")
		)
		(pad "4" smd rect
			(at -1.905 2.54 270)
			(size 0.635 1.651)
			(layers "B.Cu" "B.Mask" "B.Paste")
			(net "PWR_EN_R_P5V")
		)
		(pad "5" smd rect
			(at -1.905 -2.54 270)
			(size 0.635 1.651)
			(layers "B.Cu" "B.Mask" "B.Paste")
			(net "P5V_SW_R")
		)
		(pad "6" smd rect
			(at -0.635 -2.54 270)
			(size 0.635 1.651)
			(layers "B.Cu" "B.Mask" "B.Paste")
			(net "P5V_SW_R")
		)
		(pad "7" smd rect
			(at 0.635 -2.54 270)
			(size 0.635 1.651)
			(layers "B.Cu" "B.Mask" "B.Paste")
			(net "P5V_SW_R")
		)
		(pad "8" smd rect
			(at 1.905 -2.54 270)
			(size 0.635 1.651)
			(layers "B.Cu" "B.Mask" "B.Paste")
			(net "P5V_SW_R")
		)
	)
	(footprint ""
		(layer "B.Cu")
		(at 83.320636 -45.220636 180)
		(property "Reference" "C516"
			(at 0 0 0)
			(layer "B.SilkS")
			(hide yes)
			(effects
				(font
					(size 1.27 1.27)
				)
				(justify mirror)
			)
		)
		(property "Value" "SCD033U25V2KX-GP"
			(at -1.1811 -2.7051 180)
			(unlocked yes)
			(layer "B.Fab")
			(hide yes)
			(effects
				(font
					(size 1.016 1.016)
					(thickness 0.1524)
				)
				(justify mirror)
			)
		)
		(property "Device Type" "C402H22"
			(at -1.1811 -4.2291 180)
			(unlocked yes)
			(layer "B.Fab")
			(hide yes)
			(effects
				(font
					(size 1.016 1.016)
					(thickness 0.1524)
				)
				(justify mirror)
			)
		)
		(duplicate_pad_numbers_are_jumpers no)
		(fp_rect
			(start 0.4318 0.9525)
			(end -0.4318 -0.9525)
			(stroke
				(width 0)
				(type default)
			)
			(fill no)
			(layer "B.CrtYd")
		)
		(fp_rect
			(start 0.4318 0.9525)
			(end -0.4318 -0.9525)
			(stroke
				(width 0)
				(type default)
			)
			(fill no)
			(layer "B.Fab")
		)
		(pad "1" smd custom
			(at 0 -0.4445)
			(size 0.1524 0.1524)
			(layers "B.Cu" "B.Mask" "B.Paste")
			(net "PWR_EN_R_P5V")
			(options
				(clearance outline)
				(anchor circle)
			)
			(primitives
				(gr_poly
					(pts
						(arc
							(start 0.3048 0.2032)
							(mid 0.275042 0.275042)
							(end 0.2032 0.3048)
						)
						(arc
							(start -0.2032 0.3048)
							(mid -0.275042 0.275042)
							(end -0.3048 0.2032)
						)
						(arc
							(start -0.3048 -0.2032)
							(mid -0.275042 -0.275042)
							(end -0.2032 -0.3048)
						)
						(arc
							(start 0.2032 -0.3048)
							(mid 0.275042 -0.275042)
							(end 0.3048 -0.2032)
						)
					)
					(width 0)
					(fill yes)
				)
			)
		)
		(pad "2" smd custom
			(at 0 0.4445)
			(size 0.1524 0.1524)
			(layers "B.Cu" "B.Mask" "B.Paste")
			(net "GND")
			(options
				(clearance outline)
				(anchor circle)
			)
			(primitives
				(gr_poly
					(pts
						(arc
							(start 0.3048 0.2032)
							(mid 0.275042 0.275042)
							(end 0.2032 0.3048)
						)
						(arc
							(start -0.2032 0.3048)
							(mid -0.275042 0.275042)
							(end -0.3048 0.2032)
						)
						(arc
							(start -0.3048 -0.2032)
							(mid -0.275042 -0.275042)
							(end -0.2032 -0.3048)
						)
						(arc
							(start 0.2032 -0.3048)
							(mid 0.275042 -0.275042)
							(end 0.3048 -0.2032)
						)
					)
					(width 0)
					(fill yes)
				)
			)
		)
	)
	(footprint ""
		(layer "B.Cu")
		(at 11.34999 -13.299948 -90)
		(property "Reference" "CN1"
			(at 0 0 90)
			(layer "B.SilkS")
			(hide yes)
			(effects
				(font
					(size 1.27 1.27)
				)
				(justify mirror)
			)
		)
		(property "Value" "SMC-CON15-1-GP"
			(at 9.9568 -1.2573 270)
			(unlocked yes)
			(layer "B.Fab")
			(hide yes)
			(effects
				(font
					(size 1.016 1.016)
					(thickness 0.1524)
				)
				(justify mirror)
			)
		)
		(property "Device Type" "T1M-15-F-SV-L-P"
			(at 9.9568 -2.7813 270)
			(unlocked yes)
			(layer "B.Fab")
			(hide yes)
			(effects
				(font
					(size 1.016 1.016)
					(thickness 0.1524)
				)
				(justify mirror)
			)
		)
		(duplicate_pad_numbers_are_jumpers no)
		(fp_line
			(start -3.7592 2.0574)
			(end 3.7592 2.0574)
			(stroke
				(width 0.1524)
				(type default)
			)
			(layer "B.SilkS")
		)
		(fp_line
			(start 3.7592 2.0574)
			(end 3.7592 1.1684)
			(stroke
				(width 0.1524)
				(type default)
			)
			(layer "B.SilkS")
		)
		(fp_line
			(start -8.9662 1.1684)
			(end -3.7592 1.1684)
			(stroke
				(width 0.1524)
				(type default)
			)
			(layer "B.SilkS")
		)
		(fp_line
			(start -3.7592 1.1684)
			(end -3.7592 2.0574)
			(stroke
				(width 0.1524)
				(type default)
			)
			(layer "B.SilkS")
		)
		(fp_line
			(start 3.7592 1.1684)
			(end 8.9662 1.1684)
			(stroke
				(width 0.1524)
				(type default)
			)
			(layer "B.SilkS")
		)
		(fp_line
			(start 8.9662 1.1684)
			(end 8.9662 -3.6068)
			(stroke
				(width 0.1524)
				(type default)
			)
			(layer "B.SilkS")
		)
		(fp_line
			(start -8.9662 -3.6068)
			(end -8.9662 1.1684)
			(stroke
				(width 0.1524)
				(type default)
			)
			(layer "B.SilkS")
		)
		(fp_line
			(start 8.9662 -3.6068)
			(end -8.9662 -3.6068)
			(stroke
				(width 0.1524)
				(type default)
			)
			(layer "B.SilkS")
		)
		(fp_line
			(start -6.5659 -3.6957)
			(end -7.4549 -3.6957)
			(stroke
				(width 0.3302)
				(type default)
			)
			(layer "B.SilkS")
		)
		(fp_poly
			(pts
				(xy -7.018528 -3.679444) (xy -7.653528 -4.314444) (xy -6.383528 -4.314444)
			)
			(stroke
				(width 0)
				(type default)
			)
			(fill yes)
			(layer "B.SilkS")
		)
		(fp_poly
			(pts
				(xy 3.7592 2.0574) (xy 3.7592 1.1684) (xy 7.690358 1.1684) (xy 7.690358 -1.546606) (xy -7.690358 -1.546606)
				(xy -7.690358 1.1684) (xy -3.7592 1.1684) (xy -3.7592 2.0574)
			)
			(stroke
				(width 0)
				(type default)
			)
			(fill yes)
			(layer "B.SilkS")
		)
		(fp_poly
			(pts
				(xy 3.5052 1.8034) (xy -3.5052 1.8034) (xy -3.5052 0.762) (xy -8.6995 0.762) (xy -8.6995 -2.6416)
				(xy -7.0993 -2.6416) (xy -7.0993 -3.1496) (xy 7.0993 -3.1496) (xy 7.0993 -2.6416) (xy 8.6995 -2.6416)
				(xy 8.6995 0.762) (xy 3.5052 0.762)
			)
			(stroke
				(width 0)
				(type default)
			)
			(fill no)
			(layer "B.CrtYd")
		)
		(fp_poly
			(pts
				(xy 4.0132 2.3114) (xy 4.0132 1.4224) (xy 9.2202 1.4224) (xy 9.2202 -3.8608) (xy -9.2202 -3.8608)
				(xy -9.2202 -0.00635) (xy -8.6995 -0.00635) (xy -8.6995 -2.6416) (xy -7.0993 -2.6416) (xy -7.0993 -3.1496)
				(xy 7.0993 -3.1496) (xy 7.0993 -2.6416) (xy 8.6995 -2.6416) (xy 8.6995 0.762) (xy 3.5052 0.762)
				(xy 3.5052 1.8034) (xy -3.5052 1.8034) (xy -3.5052 0.762) (xy -8.6995 0.762) (xy -8.6995 0.00635)
				(xy -9.2202 0.00635) (xy -9.2202 1.4224) (xy -4.0132 1.4224) (xy -4.0132 2.3114)
			)
			(stroke
				(width 0)
				(type default)
			)
			(fill no)
			(layer "B.CrtYd")
		)
		(fp_poly
			(pts
				(xy 4.0132 2.3114) (xy 4.0132 1.4224) (xy 9.2202 1.4224) (xy 9.2202 -3.8608) (xy -9.2202 -3.8608)
				(xy -9.2202 1.4224) (xy -4.0132 1.4224) (xy -4.0132 2.3114)
			)
			(stroke
				(width 0)
				(type default)
			)
			(fill no)
			(layer "B.Fab")
		)
		(pad "1" smd rect
			(at -6.999986 -2.549906 90)
			(size 0.6096 1.6002)
			(layers "B.Cu" "B.Mask" "B.Paste")
			(net "P5V")
		)
		(pad "2" smd rect
			(at -5.999988 -2.549906 90)
			(size 0.6096 1.6002)
			(layers "B.Cu" "B.Mask" "B.Paste")
			(net "HBA_PRSNT0_N")
		)
		(pad "3" smd rect
			(at -4.99999 -2.549906 90)
			(size 0.6096 1.6002)
			(layers "B.Cu" "B.Mask" "B.Paste")
			(net "HBA_PRSNT1_N")
		)
		(pad "4" smd rect
			(at -3.999992 -2.549906 90)
			(size 0.6096 1.6002)
			(layers "B.Cu" "B.Mask" "B.Paste")
			(net "HBA_PRSNT2_N")
		)
		(pad "5" smd rect
			(at -2.999994 -2.549906 90)
			(size 0.6096 1.6002)
			(layers "B.Cu" "B.Mask" "B.Paste")
			(net "HBA_PRSNT3_N")
		)
		(pad "6" smd rect
			(at -1.999996 -2.549906 90)
			(size 0.6096 1.6002)
			(layers "B.Cu" "B.Mask" "B.Paste")
			(net "GND")
		)
		(pad "7" smd rect
			(at -0.999998 -2.549906 90)
			(size 0.6096 1.6002)
			(layers "B.Cu" "B.Mask" "B.Paste")
			(net "GND")
		)
		(pad "8" smd rect
			(at 0 -2.549906 90)
			(size 0.6096 1.6002)
			(layers "B.Cu" "B.Mask" "B.Paste")
			(net "GND")
		)
		(pad "9" smd rect
			(at 0.999998 -2.549906 90)
			(size 0.6096 1.6002)
			(layers "B.Cu" "B.Mask" "B.Paste")
			(net "HDD_ACT_LED0")
		)
		(pad "10" smd rect
			(at 1.999996 -2.549906 90)
			(size 0.6096 1.6002)
			(layers "B.Cu" "B.Mask" "B.Paste")
			(net "HDD_ACT_LED1")
		)
		(pad "11" smd rect
			(at 2.999994 -2.549906 90)
			(size 0.6096 1.6002)
			(layers "B.Cu" "B.Mask" "B.Paste")
			(net "HDD_ACT_LED2")
		)
		(pad "12" smd rect
			(at 3.999992 -2.549906 90)
			(size 0.6096 1.6002)
			(layers "B.Cu" "B.Mask" "B.Paste")
			(net "HDD_ACT_LED3")
		)
		(pad "13" smd rect
			(at 4.99999 -2.549906 90)
			(size 0.6096 1.6002)
			(layers "B.Cu" "B.Mask" "B.Paste")
			(net "GND")
		)
		(pad "14" smd rect
			(at 5.999988 -2.549906 90)
			(size 0.6096 1.6002)
			(layers "B.Cu" "B.Mask" "B.Paste")
			(net "GND")
		)
		(pad "15" smd rect
			(at 6.999986 -2.549906 90)
			(size 0.6096 1.6002)
			(layers "B.Cu" "B.Mask" "B.Paste")
			(net "GND")
		)
		(pad "PTH1" smd rect
			(at -8.299958 0 90)
			(size 0.8128 1.8034)
			(layers "B.Cu" "B.Mask" "B.Paste")
			(net "GND")
		)
		(pad "PTH2" smd rect
			(at 8.299958 0 90)
			(size 0.8128 1.8034)
			(layers "B.Cu" "B.Mask" "B.Paste")
			(net "GND")
		)
	)
	(footprint ""
		(layer "B.Cu")
		(at 88.552274 -11.316716 90)
		(property "Reference" "U12"
			(at 0 0 90)
			(layer "B.SilkS")
			(hide yes)
			(effects
				(font
					(size 1.27 1.27)
				)
				(justify mirror)
			)
		)
		(property "Value" "P2003EVG-GP"
			(at 0 -11.1252 90)
			(unlocked yes)
			(layer "B.Fab")
			(hide yes)
			(effects
				(font
					(size 1.016 1.016)
					(thickness 0.1524)
				)
				(justify mirror)
			)
		)
		(property "Device Type" "SOIC8H79"
			(at 0 -12.6492 90)
			(unlocked yes)
			(layer "B.Fab")
			(hide yes)
			(effects
				(font
					(size 1.016 1.016)
					(thickness 0.1524)
				)
				(justify mirror)
			)
		)
		(duplicate_pad_numbers_are_jumpers no)
		(fp_line
			(start 2.7432 -1.4224)
			(end 2.7432 1.4224)
			(stroke
				(width 0.1524)
				(type default)
			)
			(layer "B.SilkS")
		)
		(fp_line
			(start -2.1336 -1.4224)
			(end 2.7432 -1.4224)
			(stroke
				(width 0.1524)
				(type default)
			)
			(layer "B.SilkS")
		)
		(fp_line
			(start 2.7432 -0.508)
			(end 2.2352 0)
			(stroke
				(width 0.1524)
				(type default)
			)
			(layer "B.SilkS")
		)
		(fp_line
			(start 2.2352 0)
			(end 2.7432 0.508)
			(stroke
				(width 0.1524)
				(type default)
			)
			(layer "B.SilkS")
		)
		(fp_line
			(start 2.7432 1.4224)
			(end -2.1336 1.4224)
			(stroke
				(width 0.1524)
				(type default)
			)
			(layer "B.SilkS")
		)
		(fp_line
			(start -2.1336 1.4224)
			(end -2.1336 -1.4224)
			(stroke
				(width 0.1524)
				(type default)
			)
			(layer "B.SilkS")
		)
		(fp_line
			(start 2.6162 3.429)
			(end 2.6162 1.4732)
			(stroke
				(width 0.4064)
				(type default)
			)
			(layer "B.SilkS")
		)
		(fp_poly
			(pts
				(xy -2.2098 -1.4224) (xy -2.2098 1.4224) (xy 2.2225 1.4224) (xy 2.2225 -1.4224)
			)
			(stroke
				(width 0)
				(type default)
			)
			(fill yes)
			(layer "B.SilkS")
		)
		(fp_rect
			(start 2.4511 2.9972)
			(end -2.4511 -2.9972)
			(stroke
				(width 0)
				(type default)
			)
			(fill no)
			(layer "B.CrtYd")
		)
		(fp_poly
			(pts
				(xy 2.8194 3.6322) (xy 2.8194 -3.6322) (xy -2.8194 -3.6322) (xy -2.8194 -2.2987) (xy -2.4511 -2.2987)
				(xy -2.4511 -2.9972) (xy 2.4511 -2.9972) (xy 2.4511 2.9972) (xy -2.4511 2.9972) (xy -2.4511 -2.286)
				(xy -2.8194 -2.286) (xy -2.8194 3.6322)
			)
			(stroke
				(width 0)
				(type default)
			)
			(fill no)
			(layer "B.CrtYd")
		)
		(fp_rect
			(start 2.8194 3.6322)
			(end -2.8194 -3.6322)
			(stroke
				(width 0)
				(type default)
			)
			(fill no)
			(layer "B.Fab")
		)
		(pad "1" smd rect
			(at 1.905 2.54 270)
			(size 0.635 1.651)
			(layers "B.Cu" "B.Mask" "B.Paste")
			(net "P12V")
		)
		(pad "2" smd rect
			(at 0.635 2.54 270)
			(size 0.635 1.651)
			(layers "B.Cu" "B.Mask" "B.Paste")
			(net "P12V")
		)
		(pad "3" smd rect
			(at -0.635 2.54 270)
			(size 0.635 1.651)
			(layers "B.Cu" "B.Mask" "B.Paste")
			(net "P12V")
		)
		(pad "4" smd rect
			(at -1.905 2.54 270)
			(size 0.635 1.651)
			(layers "B.Cu" "B.Mask" "B.Paste")
			(net "SW_SW_L_N_0")
		)
		(pad "5" smd rect
			(at -1.905 -2.54 270)
			(size 0.635 1.651)
			(layers "B.Cu" "B.Mask" "B.Paste")
			(net "P12V_SW_L")
		)
		(pad "6" smd rect
			(at -0.635 -2.54 270)
			(size 0.635 1.651)
			(layers "B.Cu" "B.Mask" "B.Paste")
			(net "P12V_SW_L")
		)
		(pad "7" smd rect
			(at 0.635 -2.54 270)
			(size 0.635 1.651)
			(layers "B.Cu" "B.Mask" "B.Paste")
			(net "P12V_SW_L")
		)
		(pad "8" smd rect
			(at 1.905 -2.54 270)
			(size 0.635 1.651)
			(layers "B.Cu" "B.Mask" "B.Paste")
			(net "P12V_SW_L")
		)
	)
	(footprint ""
		(layer "B.Cu")
		(at 77.1906 -9.1948)
		(property "Reference" "U17"
			(at 0 0 0)
			(layer "B.SilkS")
			(hide yes)
			(effects
				(font
					(size 1.27 1.27)
				)
				(justify mirror)
			)
		)
		(property "Value" "SN74LVC1G08DCKR-GP"
			(at 2.3368 -8.6868 0)
			(unlocked yes)
			(layer "B.Fab")
			(hide yes)
			(effects
				(font
					(size 1.016 1.016)
					(thickness 0.1524)
				)
				(justify mirror)
			)
		)
		(property "Device Type" "SC70-5H44"
			(at 2.3114 -10.414 0)
			(unlocked yes)
			(layer "B.Fab")
			(hide yes)
			(effects
				(font
					(size 1.016 1.016)
					(thickness 0.1524)
				)
				(justify mirror)
			)
		)
		(duplicate_pad_numbers_are_jumpers no)
		(fp_line
			(start -1.3843 -1.8034)
			(end -1.3843 -1.1176)
			(stroke
				(width 0.3302)
				(type default)
			)
			(layer "B.SilkS")
		)
		(fp_line
			(start -1.27 -1.7018)
			(end -1.27 1.7018)
			(stroke
				(width 0.1524)
				(type default)
			)
			(layer "B.SilkS")
		)
		(fp_line
			(start -1.27 1.7018)
			(end 1.27 1.7018)
			(stroke
				(width 0.1524)
				(type default)
			)
			(layer "B.SilkS")
		)
		(fp_line
			(start -0.6604 -1.8034)
			(end -1.3843 -1.8034)
			(stroke
				(width 0.3302)
				(type default)
			)
			(layer "B.SilkS")
		)
		(fp_line
			(start 1.27 -1.7018)
			(end -1.27 -1.7018)
			(stroke
				(width 0.1524)
				(type default)
			)
			(layer "B.SilkS")
		)
		(fp_line
			(start 1.27 1.7018)
			(end 1.27 -1.7018)
			(stroke
				(width 0.1524)
				(type default)
			)
			(layer "B.SilkS")
		)
		(fp_rect
			(start 1.524 1.9558)
			(end -1.524 -1.9558)
			(stroke
				(width 0)
				(type default)
			)
			(fill no)
			(layer "B.CrtYd")
		)
		(fp_poly
			(pts
				(xy 1.524 -1.9558) (xy -1.524 -1.9558) (xy -1.524 1.9558) (xy 1.524 1.9558)
			)
			(stroke
				(width 0)
				(type default)
			)
			(fill no)
			(layer "B.Fab")
		)
		(pad "1" smd rect
			(at -0.65024 -0.8255 180)
			(size 0.4064 1.2192)
			(layers "B.Cu" "B.Mask" "B.Paste")
			(net "HBA_PRSNT2_N")
		)
		(pad "2" smd rect
			(at 0 -0.8255 180)
			(size 0.4064 1.2192)
			(layers "B.Cu" "B.Mask" "B.Paste")
			(net "HBA_PRSNT3_N")
		)
		(pad "3" smd rect
			(at 0.65024 -0.8255 180)
			(size 0.4064 1.2192)
			(layers "B.Cu" "B.Mask" "B.Paste")
			(net "GND")
		)
		(pad "4" smd rect
			(at 0.65024 0.8255 180)
			(size 0.4064 1.2192)
			(layers "B.Cu" "B.Mask" "B.Paste")
			(net "PWR_EN_L")
		)
		(pad "5" smd rect
			(at -0.65024 0.8255 180)
			(size 0.4064 1.2192)
			(layers "B.Cu" "B.Mask" "B.Paste")
			(net "P3V3")
		)
	)
	(footprint ""
		(layer "B.Cu")
		(at 78.613 -34.798 180)
		(property "Reference" "U8"
			(at 0 0 0)
			(layer "B.SilkS")
			(hide yes)
			(effects
				(font
					(size 1.27 1.27)
				)
				(justify mirror)
			)
		)
		(property "Value" "DMN63D1LDW-7-GP"
			(at 2.3622 -8.2042 180)
			(unlocked yes)
			(layer "B.Fab")
			(hide yes)
			(effects
				(font
					(size 1.016 1.016)
					(thickness 0.1524)
				)
				(justify mirror)
			)
		)
		(property "Device Type" "SOT-363H44"
			(at 2.3622 -10.1092 180)
			(unlocked yes)
			(layer "B.Fab")
			(hide yes)
			(effects
				(font
					(size 1.016 1.016)
					(thickness 0.1524)
				)
				(justify mirror)
			)
		)
		(duplicate_pad_numbers_are_jumpers no)
		(fp_line
			(start 1.4478 1.7018)
			(end -1.4478 1.7018)
			(stroke
				(width 0.1524)
				(type default)
			)
			(layer "B.SilkS")
		)
		(fp_line
			(start 1.4478 -1.7018)
			(end 1.4478 1.7018)
			(stroke
				(width 0.1524)
				(type default)
			)
			(layer "B.SilkS")
		)
		(fp_line
			(start 1.27 1.524)
			(end 1.27 0.6604)
			(stroke
				(width 0.4826)
				(type default)
			)
			(layer "B.SilkS")
		)
		(fp_line
			(start -1.4478 1.7018)
			(end -1.4478 -1.7018)
			(stroke
				(width 0.1524)
				(type default)
			)
			(layer "B.SilkS")
		)
		(fp_line
			(start -1.4478 -1.7018)
			(end 1.4478 -1.7018)
			(stroke
				(width 0.1524)
				(type default)
			)
			(layer "B.SilkS")
		)
		(fp_poly
			(pts
				(xy 1.524 -1.778) (xy -1.524 -1.778) (xy -1.524 1.778) (xy 1.524 1.778)
			)
			(stroke
				(width 0)
				(type default)
			)
			(fill no)
			(layer "B.CrtYd")
		)
		(fp_poly
			(pts
				(xy 1.524 -1.778) (xy -1.524 -1.778) (xy -1.524 1.778) (xy 1.524 1.778)
			)
			(stroke
				(width 0)
				(type default)
			)
			(fill no)
			(layer "B.Fab")
		)
		(pad "1" smd rect
			(at 0.65024 0.9398)
			(size 0.4064 1.016)
			(layers "B.Cu" "B.Mask" "B.Paste")
			(net "GND")
		)
		(pad "2" smd rect
			(at 0 0.9398)
			(size 0.4064 1.016)
			(layers "B.Cu" "B.Mask" "B.Paste")
			(net "PWR_EN_R_N")
		)
		(pad "3" smd rect
			(at -0.65024 0.9398)
			(size 0.4064 1.016)
			(layers "B.Cu" "B.Mask" "B.Paste")
			(net "SW_SW_R_0")
		)
		(pad "4" smd rect
			(at -0.65024 -0.9398)
			(size 0.4064 1.016)
			(layers "B.Cu" "B.Mask" "B.Paste")
			(net "GND")
		)
		(pad "5" smd rect
			(at 0 -0.9398)
			(size 0.4064 1.016)
			(layers "B.Cu" "B.Mask" "B.Paste")
			(net "PWR_EN_D_0")
		)
		(pad "6" smd rect
			(at 0.65024 -0.9398)
			(size 0.4064 1.016)
			(layers "B.Cu" "B.Mask" "B.Paste")
			(net "PWR_EN_D_0")
		)
	)
	(footprint ""
		(layer "B.Cu")
		(at 80.3656 -9.3218)
		(property "Reference" "U18"
			(at 0 0 0)
			(layer "B.SilkS")
			(hide yes)
			(effects
				(font
					(size 1.27 1.27)
				)
				(justify mirror)
			)
		)
		(property "Value" "ADM1085AKSZ-GP"
			(at 2.3622 -8.2042 0)
			(unlocked yes)
			(layer "B.Fab")
			(hide yes)
			(effects
				(font
					(size 1.016 1.016)
					(thickness 0.1524)
				)
				(justify mirror)
			)
		)
		(property "Device Type" "SC70-6H44"
			(at 2.3622 -10.1092 0)
			(unlocked yes)
			(layer "B.Fab")
			(hide yes)
			(effects
				(font
					(size 1.016 1.016)
					(thickness 0.1524)
				)
				(justify mirror)
			)
		)
		(duplicate_pad_numbers_are_jumpers no)
		(fp_line
			(start -1.4478 -1.7018)
			(end 1.4478 -1.7018)
			(stroke
				(width 0.1524)
				(type default)
			)
			(layer "B.SilkS")
		)
		(fp_line
			(start -1.4478 1.7018)
			(end -1.4478 -1.7018)
			(stroke
				(width 0.1524)
				(type default)
			)
			(layer "B.SilkS")
		)
		(fp_line
			(start 0.5715 1.7907)
			(end 1.5494 1.7907)
			(stroke
				(width 0.3302)
				(type default)
			)
			(layer "B.SilkS")
		)
		(fp_line
			(start 1.4478 -1.7018)
			(end 1.4478 1.7018)
			(stroke
				(width 0.1524)
				(type default)
			)
			(layer "B.SilkS")
		)
		(fp_line
			(start 1.4478 1.7018)
			(end -1.4478 1.7018)
			(stroke
				(width 0.1524)
				(type default)
			)
			(layer "B.SilkS")
		)
		(fp_line
			(start 1.5494 1.7907)
			(end 1.5494 0.8255)
			(stroke
				(width 0.3302)
				(type default)
			)
			(layer "B.SilkS")
		)
		(fp_poly
			(pts
				(xy 0.6604 1.7272) (xy 1.016 2.0828) (xy 0.3048 2.0828)
			)
			(stroke
				(width 0)
				(type default)
			)
			(fill yes)
			(layer "B.SilkS")
		)
		(fp_poly
			(pts
				(xy 1.524 -1.778) (xy -1.524 -1.778) (xy -1.524 1.778) (xy 1.524 1.778)
			)
			(stroke
				(width 0)
				(type default)
			)
			(fill no)
			(layer "B.CrtYd")
		)
		(fp_poly
			(pts
				(xy 1.524 -1.778) (xy -1.524 -1.778) (xy -1.524 1.778) (xy 1.524 1.778)
			)
			(stroke
				(width 0)
				(type default)
			)
			(fill no)
			(layer "B.Fab")
		)
		(pad "1" smd rect
			(at 0.65024 0.9398 180)
			(size 0.4064 1.016)
			(layers "B.Cu" "B.Mask" "B.Paste")
			(net "ENIN_P1")
		)
		(pad "2" smd rect
			(at 0 0.9398 180)
			(size 0.4064 1.016)
			(layers "B.Cu" "B.Mask" "B.Paste")
			(net "GND")
		)
		(pad "3" smd rect
			(at -0.65024 0.9398 180)
			(size 0.4064 1.016)
			(layers "B.Cu" "B.Mask" "B.Paste")
			(net "VIN_P3")
		)
		(pad "4" smd rect
			(at -0.65024 -0.9398 180)
			(size 0.4064 1.016)
			(layers "B.Cu" "B.Mask" "B.Paste")
			(net "PWR_EN_L_DELAY")
		)
		(pad "5" smd rect
			(at 0 -0.9398 180)
			(size 0.4064 1.016)
			(layers "B.Cu" "B.Mask" "B.Paste")
			(net "CEXT_P5")
		)
		(pad "6" smd rect
			(at 0.65024 -0.9398 180)
			(size 0.4064 1.016)
			(layers "B.Cu" "B.Mask" "B.Paste")
			(net "P3V3")
		)
	)
	(footprint ""
		(layer "B.Cu")
		(at 70.485 -11.43 90)
		(property "Reference" "Q10"
			(at 0 0 90)
			(layer "B.SilkS")
			(hide yes)
			(effects
				(font
					(size 1.27 1.27)
				)
				(justify mirror)
			)
		)
		(property "Value" "FDS8878-G-GP"
			(at 3.707384 -1.5367 90)
			(unlocked yes)
			(layer "B.Fab")
			(hide yes)
			(effects
				(font
					(size 1.016 1.016)
					(thickness 0.1524)
				)
				(justify mirror)
			)
		)
		(property "Device Type" "SOIC8H69"
			(at 3.707384 -3.0607 90)
			(unlocked yes)
			(layer "B.Fab")
			(hide yes)
			(effects
				(font
					(size 1.016 1.016)
					(thickness 0.1524)
				)
				(justify mirror)
			)
		)
		(duplicate_pad_numbers_are_jumpers no)
		(fp_line
			(start 2.7432 -1.4224)
			(end 2.7432 1.4224)
			(stroke
				(width 0.1524)
				(type default)
			)
			(layer "B.SilkS")
		)
		(fp_line
			(start -2.1336 -1.4224)
			(end 2.7432 -1.4224)
			(stroke
				(width 0.1524)
				(type default)
			)
			(layer "B.SilkS")
		)
		(fp_line
			(start 2.7178 -0.508)
			(end 2.1844 -0.0508)
			(stroke
				(width 0.1524)
				(type default)
			)
			(layer "B.SilkS")
		)
		(fp_line
			(start 2.1844 -0.0508)
			(end 2.7178 0.508)
			(stroke
				(width 0.1524)
				(type default)
			)
			(layer "B.SilkS")
		)
		(fp_line
			(start 2.7432 1.4224)
			(end 2.6416 1.4224)
			(stroke
				(width 0.1524)
				(type default)
			)
			(layer "B.SilkS")
		)
		(fp_line
			(start 2.7432 1.4224)
			(end -2.1336 1.4224)
			(stroke
				(width 0.1524)
				(type default)
			)
			(layer "B.SilkS")
		)
		(fp_line
			(start -2.1336 1.4224)
			(end -2.1336 -1.4224)
			(stroke
				(width 0.1524)
				(type default)
			)
			(layer "B.SilkS")
		)
		(fp_line
			(start 2.6289 3.4417)
			(end 2.6289 1.4732)
			(stroke
				(width 0.381)
				(type default)
			)
			(layer "B.SilkS")
		)
		(fp_poly
			(pts
				(xy 2.2098 -1.4224) (xy 2.2098 1.4224) (xy -2.2098 1.4224) (xy -2.2098 -1.4224)
			)
			(stroke
				(width 0)
				(type default)
			)
			(fill yes)
			(layer "B.SilkS")
		)
		(fp_rect
			(start 2.450084 2.999994)
			(end -2.450084 -2.999994)
			(stroke
				(width 0)
				(type default)
			)
			(fill no)
			(layer "B.CrtYd")
		)
		(fp_poly
			(pts
				(xy 2.8194 3.6322) (xy 2.8194 -3.6322) (xy -2.8194 -3.6322) (xy -2.8194 1.18364) (xy -2.450084 1.18364)
				(xy -2.450084 -2.999994) (xy 2.450084 -2.999994) (xy 2.450084 2.999994) (xy -2.450084 2.999994)
				(xy -2.450084 1.18618) (xy -2.8194 1.18618) (xy -2.8194 3.6322)
			)
			(stroke
				(width 0)
				(type default)
			)
			(fill no)
			(layer "B.CrtYd")
		)
		(fp_rect
			(start 2.8194 3.6322)
			(end -2.8194 -3.6322)
			(stroke
				(width 0)
				(type default)
			)
			(fill no)
			(layer "B.Fab")
		)
		(pad "1" smd rect
			(at 1.905 2.54 270)
			(size 0.635 1.651)
			(layers "B.Cu" "B.Mask" "B.Paste")
			(net "P5V")
		)
		(pad "2" smd rect
			(at 0.635 2.54 270)
			(size 0.635 1.651)
			(layers "B.Cu" "B.Mask" "B.Paste")
			(net "P5V")
		)
		(pad "3" smd rect
			(at -0.635 2.54 270)
			(size 0.635 1.651)
			(layers "B.Cu" "B.Mask" "B.Paste")
			(net "P5V")
		)
		(pad "4" smd rect
			(at -1.905 2.54 270)
			(size 0.635 1.651)
			(layers "B.Cu" "B.Mask" "B.Paste")
			(net "PWR_EN_L_P5V")
		)
		(pad "5" smd rect
			(at -1.905 -2.54 270)
			(size 0.635 1.651)
			(layers "B.Cu" "B.Mask" "B.Paste")
			(net "P5V_SW_L")
		)
		(pad "6" smd rect
			(at -0.635 -2.54 270)
			(size 0.635 1.651)
			(layers "B.Cu" "B.Mask" "B.Paste")
			(net "P5V_SW_L")
		)
		(pad "7" smd rect
			(at 0.635 -2.54 270)
			(size 0.635 1.651)
			(layers "B.Cu" "B.Mask" "B.Paste")
			(net "P5V_SW_L")
		)
		(pad "8" smd rect
			(at 1.905 -2.54 270)
			(size 0.635 1.651)
			(layers "B.Cu" "B.Mask" "B.Paste")
			(net "P5V_SW_L")
		)
	)
	(footprint ""
		(layer "B.Cu")
		(at 86.36 -6.096 180)
		(property "Reference" "U13"
			(at 0 0 0)
			(layer "B.SilkS")
			(hide yes)
			(effects
				(font
					(size 1.27 1.27)
				)
				(justify mirror)
			)
		)
		(property "Value" "DMN63D1LDW-7-GP"
			(at 2.3622 -8.2042 180)
			(unlocked yes)
			(layer "B.Fab")
			(hide yes)
			(effects
				(font
					(size 1.016 1.016)
					(thickness 0.1524)
				)
				(justify mirror)
			)
		)
		(property "Device Type" "SOT-363H44"
			(at 2.3622 -10.1092 180)
			(unlocked yes)
			(layer "B.Fab")
			(hide yes)
			(effects
				(font
					(size 1.016 1.016)
					(thickness 0.1524)
				)
				(justify mirror)
			)
		)
		(duplicate_pad_numbers_are_jumpers no)
		(fp_line
			(start 1.4478 1.7018)
			(end -1.4478 1.7018)
			(stroke
				(width 0.1524)
				(type default)
			)
			(layer "B.SilkS")
		)
		(fp_line
			(start 1.4478 -1.7018)
			(end 1.4478 1.7018)
			(stroke
				(width 0.1524)
				(type default)
			)
			(layer "B.SilkS")
		)
		(fp_line
			(start 1.27 1.524)
			(end 1.27 0.6604)
			(stroke
				(width 0.4826)
				(type default)
			)
			(layer "B.SilkS")
		)
		(fp_line
			(start -1.4478 1.7018)
			(end -1.4478 -1.7018)
			(stroke
				(width 0.1524)
				(type default)
			)
			(layer "B.SilkS")
		)
		(fp_line
			(start -1.4478 -1.7018)
			(end 1.4478 -1.7018)
			(stroke
				(width 0.1524)
				(type default)
			)
			(layer "B.SilkS")
		)
		(fp_poly
			(pts
				(xy 1.524 -1.778) (xy -1.524 -1.778) (xy -1.524 1.778) (xy 1.524 1.778)
			)
			(stroke
				(width 0)
				(type default)
			)
			(fill no)
			(layer "B.CrtYd")
		)
		(fp_poly
			(pts
				(xy 1.524 -1.778) (xy -1.524 -1.778) (xy -1.524 1.778) (xy 1.524 1.778)
			)
			(stroke
				(width 0)
				(type default)
			)
			(fill no)
			(layer "B.Fab")
		)
		(pad "1" smd rect
			(at 0.65024 0.9398)
			(size 0.4064 1.016)
			(layers "B.Cu" "B.Mask" "B.Paste")
			(net "GND")
		)
		(pad "2" smd rect
			(at 0 0.9398)
			(size 0.4064 1.016)
			(layers "B.Cu" "B.Mask" "B.Paste")
			(net "PWR_EN_L_DELAY")
		)
		(pad "3" smd rect
			(at -0.65024 0.9398)
			(size 0.4064 1.016)
			(layers "B.Cu" "B.Mask" "B.Paste")
			(net "SW_SW_L_0")
		)
		(pad "4" smd rect
			(at -0.65024 -0.9398)
			(size 0.4064 1.016)
			(layers "B.Cu" "B.Mask" "B.Paste")
			(net "GND")
		)
		(pad "5" smd rect
			(at 0 -0.9398)
			(size 0.4064 1.016)
			(layers "B.Cu" "B.Mask" "B.Paste")
			(net "PWR_EN_D_2")
		)
		(pad "6" smd rect
			(at 0.65024 -0.9398)
			(size 0.4064 1.016)
			(layers "B.Cu" "B.Mask" "B.Paste")
			(net "PWR_EN_D_2")
		)
	)
	(footprint ""
		(layer "B.Cu")
		(at 81.565496 -14.402562 -90)
		(property "Reference" "PD1"
			(at 0 0 90)
			(layer "B.SilkS")
			(hide yes)
			(effects
				(font
					(size 1.27 1.27)
				)
				(justify mirror)
			)
		)
		(property "Value" "MMPZ5228BPT-GP"
			(at 0 -6.7818 270)
			(unlocked yes)
			(layer "B.Fab")
			(hide yes)
			(effects
				(font
					(size 1.016 1.016)
					(thickness 0.1524)
				)
				(justify mirror)
			)
		)
		(property "Device Type" "SOD323AKH40"
			(at 0 -8.6868 270)
			(unlocked yes)
			(layer "B.Fab")
			(hide yes)
			(effects
				(font
					(size 1.016 1.016)
					(thickness 0.1524)
				)
				(justify mirror)
			)
		)
		(duplicate_pad_numbers_are_jumpers no)
		(fp_line
			(start -0.889 2.159)
			(end 0.889 2.159)
			(stroke
				(width 0.1524)
				(type default)
			)
			(layer "B.SilkS")
		)
		(fp_line
			(start 0.889 2.159)
			(end 0.889 -1.9304)
			(stroke
				(width 0.1524)
				(type default)
			)
			(layer "B.SilkS")
		)
		(fp_line
			(start -0.762 2.0574)
			(end 0.762 2.0574)
			(stroke
				(width 0.508)
				(type default)
			)
			(layer "B.SilkS")
		)
		(fp_line
			(start -0.889 -1.9304)
			(end -0.889 2.159)
			(stroke
				(width 0.1524)
				(type default)
			)
			(layer "B.SilkS")
		)
		(fp_line
			(start 0.889 -1.9304)
			(end -0.889 -1.9304)
			(stroke
				(width 0.1524)
				(type default)
			)
			(layer "B.SilkS")
		)
		(fp_rect
			(start 1.016 2.3114)
			(end -1.016 -2.0066)
			(stroke
				(width 0)
				(type default)
			)
			(fill no)
			(layer "B.CrtYd")
		)
		(fp_poly
			(pts
				(xy 1.016 -2.0066) (xy -1.016 -2.0066) (xy -1.016 2.3114) (xy 1.016 2.3114)
			)
			(stroke
				(width 0)
				(type default)
			)
			(fill no)
			(layer "B.Fab")
		)
		(pad "A" smd rect
			(at 0 -1.143 90)
			(size 0.5588 1.016)
			(layers "B.Cu" "B.Mask" "B.Paste")
			(net "GND")
		)
		(pad "K" smd rect
			(at 0 1.143 90)
			(size 0.5588 1.016)
			(layers "B.Cu" "B.Mask" "B.Paste")
			(net "P5V_R_E1")
		)
	)
	(footprint ""
		(layer "B.Cu")
		(at 81.28 -54.991)
		(property "Reference" "U16"
			(at 0 0 0)
			(layer "B.SilkS")
			(hide yes)
			(effects
				(font
					(size 1.27 1.27)
				)
				(justify mirror)
			)
		)
		(property "Value" "SN74LVC1G08DCKR-GP"
			(at 2.3368 -8.6868 0)
			(unlocked yes)
			(layer "B.Fab")
			(hide yes)
			(effects
				(font
					(size 1.016 1.016)
					(thickness 0.1524)
				)
				(justify mirror)
			)
		)
		(property "Device Type" "SC70-5H44"
			(at 2.3114 -10.414 0)
			(unlocked yes)
			(layer "B.Fab")
			(hide yes)
			(effects
				(font
					(size 1.016 1.016)
					(thickness 0.1524)
				)
				(justify mirror)
			)
		)
		(duplicate_pad_numbers_are_jumpers no)
		(fp_line
			(start -1.3843 -1.8034)
			(end -1.3843 -1.1176)
			(stroke
				(width 0.3302)
				(type default)
			)
			(layer "B.SilkS")
		)
		(fp_line
			(start -1.27 -1.7018)
			(end -1.27 1.7018)
			(stroke
				(width 0.1524)
				(type default)
			)
			(layer "B.SilkS")
		)
		(fp_line
			(start -1.27 1.7018)
			(end 1.27 1.7018)
			(stroke
				(width 0.1524)
				(type default)
			)
			(layer "B.SilkS")
		)
		(fp_line
			(start -0.6604 -1.8034)
			(end -1.3843 -1.8034)
			(stroke
				(width 0.3302)
				(type default)
			)
			(layer "B.SilkS")
		)
		(fp_line
			(start 1.27 -1.7018)
			(end -1.27 -1.7018)
			(stroke
				(width 0.1524)
				(type default)
			)
			(layer "B.SilkS")
		)
		(fp_line
			(start 1.27 1.7018)
			(end 1.27 -1.7018)
			(stroke
				(width 0.1524)
				(type default)
			)
			(layer "B.SilkS")
		)
		(fp_rect
			(start 1.524 1.9558)
			(end -1.524 -1.9558)
			(stroke
				(width 0)
				(type default)
			)
			(fill no)
			(layer "B.CrtYd")
		)
		(fp_poly
			(pts
				(xy 1.524 -1.9558) (xy -1.524 -1.9558) (xy -1.524 1.9558) (xy 1.524 1.9558)
			)
			(stroke
				(width 0)
				(type default)
			)
			(fill no)
			(layer "B.Fab")
		)
		(pad "1" smd rect
			(at -0.65024 -0.8255 180)
			(size 0.4064 1.2192)
			(layers "B.Cu" "B.Mask" "B.Paste")
			(net "HBA_PRSNT0_N")
		)
		(pad "2" smd rect
			(at 0 -0.8255 180)
			(size 0.4064 1.2192)
			(layers "B.Cu" "B.Mask" "B.Paste")
			(net "HBA_PRSNT1_N")
		)
		(pad "3" smd rect
			(at 0.65024 -0.8255 180)
			(size 0.4064 1.2192)
			(layers "B.Cu" "B.Mask" "B.Paste")
			(net "GND")
		)
		(pad "4" smd rect
			(at 0.65024 0.8255 180)
			(size 0.4064 1.2192)
			(layers "B.Cu" "B.Mask" "B.Paste")
			(net "PWR_EN_R_N")
		)
		(pad "5" smd rect
			(at -0.65024 0.8255 180)
			(size 0.4064 1.2192)
			(layers "B.Cu" "B.Mask" "B.Paste")
			(net "P3V3")
		)
	)
	(footprint ""
		(layer "B.Cu")
		(at 75.0062 -40.3098 -90)
		(property "Reference" "C7"
			(at 0 0 90)
			(layer "B.SilkS")
			(hide yes)
			(effects
				(font
					(size 1.27 1.27)
				)
				(justify mirror)
			)
		)
		(property "Value" "SC10U25V6KX-1GP"
			(at 0.0762 -5.1308 270)
			(unlocked yes)
			(layer "B.Fab")
			(hide yes)
			(effects
				(font
					(size 1.016 1.016)
					(thickness 0.1524)
				)
				(justify mirror)
			)
		)
		(property "Device Type" "C1206H71"
			(at 0.127 -6.6548 270)
			(unlocked yes)
			(layer "B.Fab")
			(hide yes)
			(effects
				(font
					(size 1.016 1.016)
					(thickness 0.1524)
				)
				(justify mirror)
			)
		)
		(duplicate_pad_numbers_are_jumpers no)
		(fp_line
			(start -1.016 2.2352)
			(end 1.016 2.2352)
			(stroke
				(width 0.1524)
				(type default)
			)
			(layer "B.SilkS")
		)
		(fp_line
			(start 1.016 2.2352)
			(end 1.016 0.8382)
			(stroke
				(width 0.1524)
				(type default)
			)
			(layer "B.SilkS")
		)
		(fp_line
			(start -1.016 0.8382)
			(end -1.016 2.2352)
			(stroke
				(width 0.1524)
				(type default)
			)
			(layer "B.SilkS")
		)
		(fp_line
			(start 1.016 -0.8382)
			(end 1.016 -2.2352)
			(stroke
				(width 0.1524)
				(type default)
			)
			(layer "B.SilkS")
		)
		(fp_line
			(start -1.016 -2.2352)
			(end -1.016 -0.8382)
			(stroke
				(width 0.1524)
				(type default)
			)
			(layer "B.SilkS")
		)
		(fp_line
			(start 1.016 -2.2352)
			(end -1.016 -2.2352)
			(stroke
				(width 0.1524)
				(type default)
			)
			(layer "B.SilkS")
		)
		(fp_rect
			(start 1.0922 2.3114)
			(end -1.0922 -2.3114)
			(stroke
				(width 0)
				(type default)
			)
			(fill no)
			(layer "B.CrtYd")
		)
		(fp_poly
			(pts
				(xy -1.0922 -2.3114) (xy -1.0922 2.3114) (xy 1.0922 2.3114) (xy 1.0922 -2.3114)
			)
			(stroke
				(width 0)
				(type default)
			)
			(fill no)
			(layer "B.Fab")
		)
		(pad "1" smd rect
			(at 0 -1.397 90)
			(size 1.651 1.27)
			(layers "B.Cu" "B.Mask" "B.Paste")
			(net "P12V_SW_R")
		)
		(pad "2" smd rect
			(at 0 1.397 90)
			(size 1.651 1.27)
			(layers "B.Cu" "B.Mask" "B.Paste")
			(net "GND")
		)
	)
	(footprint ""
		(layer "B.Cu")
		(at 131.510532 -25.662636 -90)
		(property "Reference" "TC2"
			(at 0 0 90)
			(layer "B.SilkS")
			(hide yes)
			(effects
				(font
					(size 1.27 1.27)
				)
				(justify mirror)
			)
		)
		(property "Value" "SC22U25V5MX-GP"
			(at 0.0762 -6.1214 270)
			(unlocked yes)
			(layer "B.Fab")
			(hide yes)
			(effects
				(font
					(size 1.016 1.016)
					(thickness 0.1524)
				)
				(justify mirror)
			)
		)
		(property "Device Type" "C805H58"
			(at 0.0762 -8.1534 270)
			(unlocked yes)
			(layer "B.Fab")
			(hide yes)
			(effects
				(font
					(size 1.016 1.016)
					(thickness 0.1524)
				)
				(justify mirror)
			)
		)
		(duplicate_pad_numbers_are_jumpers no)
		(fp_line
			(start -0.635 0)
			(end 0.635 0)
			(stroke
				(width 0.508)
				(type default)
			)
			(layer "B.SilkS")
		)
		(fp_rect
			(start 0.9652 1.778)
			(end -0.9652 -1.778)
			(stroke
				(width 0)
				(type default)
			)
			(fill no)
			(layer "B.CrtYd")
		)
		(fp_poly
			(pts
				(xy 0.9652 -1.778) (xy -0.9652 -1.778) (xy -0.9652 1.778) (xy 0.9652 1.778)
			)
			(stroke
				(width 0)
				(type default)
			)
			(fill no)
			(layer "B.Fab")
		)
		(pad "1" smd rect
			(at 0 -0.9652 90)
			(size 1.397 1.143)
			(layers "B.Cu" "B.Mask" "B.Paste")
			(net "P5V")
		)
		(pad "2" smd rect
			(at 0 0.9652 90)
			(size 1.397 1.143)
			(layers "B.Cu" "B.Mask" "B.Paste")
			(net "GND")
		)
	)
	(footprint ""
		(layer "B.Cu")
		(at 78.7908 -11.7602 -90)
		(property "Reference" "C35"
			(at 0 0 90)
			(layer "B.SilkS")
			(hide yes)
			(effects
				(font
					(size 1.27 1.27)
				)
				(justify mirror)
			)
		)
		(property "Value" "SC2D2U25V3KX-GP"
			(at 0 -2.8194 270)
			(unlocked yes)
			(layer "B.Fab")
			(hide yes)
			(effects
				(font
					(size 1.016 1.016)
					(thickness 0.1524)
				)
				(justify mirror)
			)
		)
		(property "Device Type" "C603H38"
			(at 0 -4.3434 270)
			(unlocked yes)
			(layer "B.Fab")
			(hide yes)
			(effects
				(font
					(size 1.016 1.016)
					(thickness 0.1524)
				)
				(justify mirror)
			)
		)
		(duplicate_pad_numbers_are_jumpers no)
		(fp_line
			(start -0.508 0)
			(end 0.508 0)
			(stroke
				(width 0.2032)
				(type default)
			)
			(layer "B.SilkS")
		)
		(fp_rect
			(start 0.5842 1.3335)
			(end -0.5842 -1.3335)
			(stroke
				(width 0)
				(type default)
			)
			(fill no)
			(layer "B.CrtYd")
		)
		(fp_rect
			(start 0.5842 1.3335)
			(end -0.5842 -1.3335)
			(stroke
				(width 0)
				(type default)
			)
			(fill no)
			(layer "B.Fab")
		)
		(pad "1" smd custom
			(at 0 -0.762 90)
			(size 0.2159 0.2159)
			(layers "B.Cu" "B.Mask" "B.Paste")
			(net "CEXT_P5")
			(options
				(clearance outline)
				(anchor circle)
			)
			(primitives
				(gr_poly
					(pts
						(arc
							(start -0.3302 0.4318)
							(mid -0.402042 0.402042)
							(end -0.4318 0.3302)
						)
						(arc
							(start -0.4318 -0.3302)
							(mid -0.402042 -0.402042)
							(end -0.3302 -0.4318)
						)
						(arc
							(start 0.3302 -0.4318)
							(mid 0.402042 -0.402042)
							(end 0.4318 -0.3302)
						)
						(arc
							(start 0.4318 0.3302)
							(mid 0.402042 0.402042)
							(end 0.3302 0.4318)
						)
					)
					(width 0)
					(fill yes)
				)
			)
		)
		(pad "2" smd custom
			(at 0 0.762 90)
			(size 0.2159 0.2159)
			(layers "B.Cu" "B.Mask" "B.Paste")
			(net "GND")
			(options
				(clearance outline)
				(anchor circle)
			)
			(primitives
				(gr_poly
					(pts
						(arc
							(start -0.3302 0.4318)
							(mid -0.402042 0.402042)
							(end -0.4318 0.3302)
						)
						(arc
							(start -0.4318 -0.3302)
							(mid -0.402042 -0.402042)
							(end -0.3302 -0.4318)
						)
						(arc
							(start 0.3302 -0.4318)
							(mid 0.402042 -0.402042)
							(end 0.4318 -0.3302)
						)
						(arc
							(start 0.4318 0.3302)
							(mid 0.402042 0.402042)
							(end 0.3302 0.4318)
						)
					)
					(width 0)
					(fill yes)
				)
			)
		)
	)
	(footprint ""
		(layer "B.Cu")
		(at 81.417922 -12.933426 90)
		(property "Reference" "PC1"
			(at 0 0 90)
			(layer "B.SilkS")
			(hide yes)
			(effects
				(font
					(size 1.27 1.27)
				)
				(justify mirror)
			)
		)
		(property "Value" "SC1U6D3V2KX-GP"
			(at -1.1811 -2.7051 90)
			(unlocked yes)
			(layer "B.Fab")
			(hide yes)
			(effects
				(font
					(size 1.016 1.016)
					(thickness 0.1524)
				)
				(justify mirror)
			)
		)
		(property "Device Type" "C402H22"
			(at -1.1811 -4.2291 90)
			(unlocked yes)
			(layer "B.Fab")
			(hide yes)
			(effects
				(font
					(size 1.016 1.016)
					(thickness 0.1524)
				)
				(justify mirror)
			)
		)
		(duplicate_pad_numbers_are_jumpers no)
		(fp_rect
			(start 0.4318 0.9525)
			(end -0.4318 -0.9525)
			(stroke
				(width 0)
				(type default)
			)
			(fill no)
			(layer "B.CrtYd")
		)
		(fp_rect
			(start 0.4318 0.9525)
			(end -0.4318 -0.9525)
			(stroke
				(width 0)
				(type default)
			)
			(fill no)
			(layer "B.Fab")
		)
		(pad "1" smd custom
			(at 0 -0.4445 270)
			(size 0.1524 0.1524)
			(layers "B.Cu" "B.Mask" "B.Paste")
			(net "P3V3")
			(options
				(clearance outline)
				(anchor circle)
			)
			(primitives
				(gr_poly
					(pts
						(arc
							(start 0.3048 0.2032)
							(mid 0.275042 0.275042)
							(end 0.2032 0.3048)
						)
						(arc
							(start -0.2032 0.3048)
							(mid -0.275042 0.275042)
							(end -0.3048 0.2032)
						)
						(arc
							(start -0.3048 -0.2032)
							(mid -0.275042 -0.275042)
							(end -0.2032 -0.3048)
						)
						(arc
							(start 0.2032 -0.3048)
							(mid 0.275042 -0.275042)
							(end 0.3048 -0.2032)
						)
					)
					(width 0)
					(fill yes)
				)
			)
		)
		(pad "2" smd custom
			(at 0 0.4445 270)
			(size 0.1524 0.1524)
			(layers "B.Cu" "B.Mask" "B.Paste")
			(net "GND")
			(options
				(clearance outline)
				(anchor circle)
			)
			(primitives
				(gr_poly
					(pts
						(arc
							(start 0.3048 0.2032)
							(mid 0.275042 0.275042)
							(end 0.2032 0.3048)
						)
						(arc
							(start -0.2032 0.3048)
							(mid -0.275042 0.275042)
							(end -0.3048 0.2032)
						)
						(arc
							(start -0.3048 -0.2032)
							(mid -0.275042 -0.275042)
							(end -0.2032 -0.3048)
						)
						(arc
							(start 0.2032 -0.3048)
							(mid 0.275042 -0.275042)
							(end 0.3048 -0.2032)
						)
					)
					(width 0)
					(fill yes)
				)
			)
		)
	)
	(footprint ""
		(layer "B.Cu")
		(at 123.77928 -25.680416 90)
		(property "Reference" "TC1"
			(at 0 0 90)
			(layer "B.SilkS")
			(hide yes)
			(effects
				(font
					(size 1.27 1.27)
				)
				(justify mirror)
			)
		)
		(property "Value" "SC22U25V5MX-GP"
			(at 0.0762 -6.1214 90)
			(unlocked yes)
			(layer "B.Fab")
			(hide yes)
			(effects
				(font
					(size 1.016 1.016)
					(thickness 0.1524)
				)
				(justify mirror)
			)
		)
		(property "Device Type" "C805H58"
			(at 0.0762 -8.1534 90)
			(unlocked yes)
			(layer "B.Fab")
			(hide yes)
			(effects
				(font
					(size 1.016 1.016)
					(thickness 0.1524)
				)
				(justify mirror)
			)
		)
		(duplicate_pad_numbers_are_jumpers no)
		(fp_line
			(start -0.635 0)
			(end 0.635 0)
			(stroke
				(width 0.508)
				(type default)
			)
			(layer "B.SilkS")
		)
		(fp_rect
			(start 0.9652 1.778)
			(end -0.9652 -1.778)
			(stroke
				(width 0)
				(type default)
			)
			(fill no)
			(layer "B.CrtYd")
		)
		(fp_poly
			(pts
				(xy 0.9652 -1.778) (xy -0.9652 -1.778) (xy -0.9652 1.778) (xy 0.9652 1.778)
			)
			(stroke
				(width 0)
				(type default)
			)
			(fill no)
			(layer "B.Fab")
		)
		(pad "1" smd rect
			(at 0 -0.9652 270)
			(size 1.397 1.143)
			(layers "B.Cu" "B.Mask" "B.Paste")
			(net "P12V")
		)
		(pad "2" smd rect
			(at 0 0.9652 270)
			(size 1.397 1.143)
			(layers "B.Cu" "B.Mask" "B.Paste")
			(net "GND")
		)
	)
	(footprint ""
		(layer "B.Cu")
		(at 72.411082 -7.169912)
		(property "Reference" "R167"
			(at 0 0 0)
			(layer "B.SilkS")
			(hide yes)
			(effects
				(font
					(size 1.27 1.27)
				)
				(justify mirror)
			)
		)
		(property "Value" "4K7R2J-2-GP"
			(at -0.064008 -3.993896 0)
			(unlocked yes)
			(layer "B.Fab")
			(hide yes)
			(effects
				(font
					(size 1.016 1.016)
					(thickness 0.1524)
				)
				(justify mirror)
			)
		)
		(property "Device Type" "R402H16"
			(at -0.064008 -5.517896 0)
			(unlocked yes)
			(layer "B.Fab")
			(hide yes)
			(effects
				(font
					(size 1.016 1.016)
					(thickness 0.1524)
				)
				(justify mirror)
			)
		)
		(duplicate_pad_numbers_are_jumpers no)
		(fp_line
			(start -0.508 -0.9398)
			(end 0.508 -0.9398)
			(stroke
				(width 0.1524)
				(type default)
			)
			(layer "B.SilkS")
		)
		(fp_line
			(start 0.508 -0.9398)
			(end 0.508 0.9398)
			(stroke
				(width 0.1524)
				(type default)
			)
			(layer "B.SilkS")
		)
		(fp_rect
			(start 0.508 0.9398)
			(end -0.508 -0.9398)
			(stroke
				(width 0)
				(type default)
			)
			(fill no)
			(layer "B.CrtYd")
		)
		(fp_rect
			(start 0.508 0.9398)
			(end -0.508 -0.9398)
			(stroke
				(width 0)
				(type default)
			)
			(fill no)
			(layer "B.Fab")
		)
		(pad "1" smd custom
			(at 0 -0.4445 180)
			(size 0.1397 0.1397)
			(layers "B.Cu" "B.Mask" "B.Paste")
			(net "P12V")
			(options
				(clearance outline)
				(anchor circle)
			)
			(primitives
				(gr_poly
					(pts
						(arc
							(start -0.1778 0.2794)
							(mid -0.249642 0.249642)
							(end -0.2794 0.1778)
						)
						(arc
							(start -0.2794 -0.1778)
							(mid -0.249642 -0.249642)
							(end -0.1778 -0.2794)
						)
						(arc
							(start 0.1778 -0.2794)
							(mid 0.249642 -0.249642)
							(end 0.2794 -0.1778)
						)
						(arc
							(start 0.2794 0.1778)
							(mid 0.249642 0.249642)
							(end 0.1778 0.2794)
						)
					)
					(width 0)
					(fill yes)
				)
			)
		)
		(pad "2" smd custom
			(at 0 0.4445 180)
			(size 0.1397 0.1397)
			(layers "B.Cu" "B.Mask" "B.Paste")
			(net "PWR_EN_L_P5V")
			(options
				(clearance outline)
				(anchor circle)
			)
			(primitives
				(gr_poly
					(pts
						(arc
							(start -0.1778 0.2794)
							(mid -0.249642 0.249642)
							(end -0.2794 0.1778)
						)
						(arc
							(start -0.2794 -0.1778)
							(mid -0.249642 -0.249642)
							(end -0.1778 -0.2794)
						)
						(arc
							(start 0.1778 -0.2794)
							(mid 0.249642 -0.249642)
							(end 0.2794 -0.1778)
						)
						(arc
							(start 0.2794 0.1778)
							(mid 0.249642 0.249642)
							(end 0.1778 0.2794)
						)
					)
					(width 0)
					(fill yes)
				)
			)
		)
	)
	(footprint ""
		(layer "B.Cu")
		(at 74.9046 -41.8592 -90)
		(property "Reference" "C12"
			(at 0 0 90)
			(layer "B.SilkS")
			(hide yes)
			(effects
				(font
					(size 1.27 1.27)
				)
				(justify mirror)
			)
		)
		(property "Value" "SCD1U25V2KX-GP"
			(at -1.1811 -2.7051 270)
			(unlocked yes)
			(layer "B.Fab")
			(hide yes)
			(effects
				(font
					(size 1.016 1.016)
					(thickness 0.1524)
				)
				(justify mirror)
			)
		)
		(property "Device Type" "C402H22"
			(at -1.1811 -4.2291 270)
			(unlocked yes)
			(layer "B.Fab")
			(hide yes)
			(effects
				(font
					(size 1.016 1.016)
					(thickness 0.1524)
				)
				(justify mirror)
			)
		)
		(duplicate_pad_numbers_are_jumpers no)
		(fp_rect
			(start 0.4318 0.9525)
			(end -0.4318 -0.9525)
			(stroke
				(width 0)
				(type default)
			)
			(fill no)
			(layer "B.CrtYd")
		)
		(fp_rect
			(start 0.4318 0.9525)
			(end -0.4318 -0.9525)
			(stroke
				(width 0)
				(type default)
			)
			(fill no)
			(layer "B.Fab")
		)
		(pad "1" smd custom
			(at 0 -0.4445 90)
			(size 0.1524 0.1524)
			(layers "B.Cu" "B.Mask" "B.Paste")
			(net "P12V_SW_R")
			(options
				(clearance outline)
				(anchor circle)
			)
			(primitives
				(gr_poly
					(pts
						(arc
							(start 0.3048 0.2032)
							(mid 0.275042 0.275042)
							(end 0.2032 0.3048)
						)
						(arc
							(start -0.2032 0.3048)
							(mid -0.275042 0.275042)
							(end -0.3048 0.2032)
						)
						(arc
							(start -0.3048 -0.2032)
							(mid -0.275042 -0.275042)
							(end -0.2032 -0.3048)
						)
						(arc
							(start 0.2032 -0.3048)
							(mid 0.275042 -0.275042)
							(end 0.3048 -0.2032)
						)
					)
					(width 0)
					(fill yes)
				)
			)
		)
		(pad "2" smd custom
			(at 0 0.4445 90)
			(size 0.1524 0.1524)
			(layers "B.Cu" "B.Mask" "B.Paste")
			(net "GND")
			(options
				(clearance outline)
				(anchor circle)
			)
			(primitives
				(gr_poly
					(pts
						(arc
							(start 0.3048 0.2032)
							(mid 0.275042 0.275042)
							(end 0.2032 0.3048)
						)
						(arc
							(start -0.2032 0.3048)
							(mid -0.275042 0.275042)
							(end -0.3048 0.2032)
						)
						(arc
							(start -0.3048 -0.2032)
							(mid -0.275042 -0.275042)
							(end -0.2032 -0.3048)
						)
						(arc
							(start 0.2032 -0.3048)
							(mid 0.275042 -0.275042)
							(end 0.3048 -0.2032)
						)
					)
					(width 0)
					(fill yes)
				)
			)
		)
	)
	(footprint ""
		(layer "B.Cu")
		(at 81.084166 -44.880276 180)
		(property "Reference" "Q8"
			(at 0 0 0)
			(layer "B.SilkS")
			(hide yes)
			(effects
				(font
					(size 1.27 1.27)
				)
				(justify mirror)
			)
		)
		(property "Value" "2N7002K-1-GP"
			(at -0.127 -8.9662 180)
			(unlocked yes)
			(layer "B.Fab")
			(hide yes)
			(effects
				(font
					(size 1.016 1.016)
					(thickness 0.1524)
				)
				(justify mirror)
			)
		)
		(property "Device Type" "SOT23DGS2D4H44"
			(at -0.127 -10.4902 180)
			(unlocked yes)
			(layer "B.Fab")
			(hide yes)
			(effects
				(font
					(size 1.016 1.016)
					(thickness 0.1524)
				)
				(justify mirror)
			)
		)
		(duplicate_pad_numbers_are_jumpers no)
		(fp_line
			(start 1.651 1.778)
			(end -1.651 1.778)
			(stroke
				(width 0.1524)
				(type default)
			)
			(layer "B.SilkS")
		)
		(fp_line
			(start 1.651 -1.778)
			(end 1.651 1.778)
			(stroke
				(width 0.1524)
				(type default)
			)
			(layer "B.SilkS")
		)
		(fp_line
			(start -1.651 1.778)
			(end -1.651 -1.778)
			(stroke
				(width 0.1524)
				(type default)
			)
			(layer "B.SilkS")
		)
		(fp_line
			(start -1.651 -1.778)
			(end 1.651 -1.778)
			(stroke
				(width 0.1524)
				(type default)
			)
			(layer "B.SilkS")
		)
		(fp_poly
			(pts
				(xy 1.778 1.8796) (xy 1.778 -1.8796) (xy -1.778 -1.8796) (xy -1.778 1.8796)
			)
			(stroke
				(width 0)
				(type default)
			)
			(fill no)
			(layer "B.CrtYd")
		)
		(fp_poly
			(pts
				(xy 1.778 1.8796) (xy 1.778 -1.8796) (xy -1.778 -1.8796) (xy -1.778 1.8796)
			)
			(stroke
				(width 0)
				(type default)
			)
			(fill no)
			(layer "B.Fab")
		)
		(pad "D" smd custom
			(at 0 -0.9525)
			(size 0.1905 0.1905)
			(layers "B.Cu" "B.Mask" "B.Paste")
			(net "PWR_EN_R_P5V")
			(options
				(clearance outline)
				(anchor circle)
			)
			(primitives
				(gr_poly
					(pts
						(arc
							(start -0.1778 -0.5715)
							(mid -0.321484 -0.511984)
							(end -0.381 -0.3683)
						)
						(arc
							(start -0.381 0.3683)
							(mid -0.321484 0.511984)
							(end -0.1778 0.5715)
						)
						(arc
							(start 0.1778 0.5715)
							(mid 0.321484 0.511984)
							(end 0.381 0.3683)
						)
						(arc
							(start 0.381 -0.3683)
							(mid 0.321484 -0.511984)
							(end 0.1778 -0.5715)
						)
					)
					(width 0)
					(fill yes)
				)
			)
		)
		(pad "G" smd custom
			(at 0.98425 0.9525)
			(size 0.1905 0.1905)
			(layers "B.Cu" "B.Mask" "B.Paste")
			(net "PWR_EN_R_N")
			(options
				(clearance outline)
				(anchor circle)
			)
			(primitives
				(gr_poly
					(pts
						(arc
							(start -0.1778 -0.5715)
							(mid -0.321484 -0.511984)
							(end -0.381 -0.3683)
						)
						(arc
							(start -0.381 0.3683)
							(mid -0.321484 0.511984)
							(end -0.1778 0.5715)
						)
						(arc
							(start 0.1778 0.5715)
							(mid 0.321484 0.511984)
							(end 0.381 0.3683)
						)
						(arc
							(start 0.381 -0.3683)
							(mid 0.321484 -0.511984)
							(end 0.1778 -0.5715)
						)
					)
					(width 0)
					(fill yes)
				)
			)
		)
		(pad "S" smd custom
			(at -0.98425 0.9525)
			(size 0.1905 0.1905)
			(layers "B.Cu" "B.Mask" "B.Paste")
			(net "GND")
			(options
				(clearance outline)
				(anchor circle)
			)
			(primitives
				(gr_poly
					(pts
						(arc
							(start -0.1778 -0.5715)
							(mid -0.321484 -0.511984)
							(end -0.381 -0.3683)
						)
						(arc
							(start -0.381 0.3683)
							(mid -0.321484 0.511984)
							(end -0.1778 0.5715)
						)
						(arc
							(start 0.1778 0.5715)
							(mid 0.321484 0.511984)
							(end 0.381 0.3683)
						)
						(arc
							(start 0.381 -0.3683)
							(mid 0.321484 -0.511984)
							(end 0.1778 -0.5715)
						)
					)
					(width 0)
					(fill yes)
				)
			)
		)
	)
	(footprint ""
		(layer "B.Cu")
		(at 123.735592 -27.125676 90)
		(property "Reference" "C27"
			(at 0 0 90)
			(layer "B.SilkS")
			(hide yes)
			(effects
				(font
					(size 1.27 1.27)
				)
				(justify mirror)
			)
		)
		(property "Value" "SCD1U25V2KX-GP"
			(at -1.1811 -2.7051 90)
			(unlocked yes)
			(layer "B.Fab")
			(hide yes)
			(effects
				(font
					(size 1.016 1.016)
					(thickness 0.1524)
				)
				(justify mirror)
			)
		)
		(property "Device Type" "C402H22"
			(at -1.1811 -4.2291 90)
			(unlocked yes)
			(layer "B.Fab")
			(hide yes)
			(effects
				(font
					(size 1.016 1.016)
					(thickness 0.1524)
				)
				(justify mirror)
			)
		)
		(duplicate_pad_numbers_are_jumpers no)
		(fp_rect
			(start 0.4318 0.9525)
			(end -0.4318 -0.9525)
			(stroke
				(width 0)
				(type default)
			)
			(fill no)
			(layer "B.CrtYd")
		)
		(fp_rect
			(start 0.4318 0.9525)
			(end -0.4318 -0.9525)
			(stroke
				(width 0)
				(type default)
			)
			(fill no)
			(layer "B.Fab")
		)
		(pad "1" smd custom
			(at 0 -0.4445 270)
			(size 0.1524 0.1524)
			(layers "B.Cu" "B.Mask" "B.Paste")
			(net "P12V")
			(options
				(clearance outline)
				(anchor circle)
			)
			(primitives
				(gr_poly
					(pts
						(arc
							(start 0.3048 0.2032)
							(mid 0.275042 0.275042)
							(end 0.2032 0.3048)
						)
						(arc
							(start -0.2032 0.3048)
							(mid -0.275042 0.275042)
							(end -0.3048 0.2032)
						)
						(arc
							(start -0.3048 -0.2032)
							(mid -0.275042 -0.275042)
							(end -0.2032 -0.3048)
						)
						(arc
							(start 0.2032 -0.3048)
							(mid 0.275042 -0.275042)
							(end 0.3048 -0.2032)
						)
					)
					(width 0)
					(fill yes)
				)
			)
		)
		(pad "2" smd custom
			(at 0 0.4445 270)
			(size 0.1524 0.1524)
			(layers "B.Cu" "B.Mask" "B.Paste")
			(net "GND")
			(options
				(clearance outline)
				(anchor circle)
			)
			(primitives
				(gr_poly
					(pts
						(arc
							(start 0.3048 0.2032)
							(mid 0.275042 0.275042)
							(end 0.2032 0.3048)
						)
						(arc
							(start -0.2032 0.3048)
							(mid -0.275042 0.275042)
							(end -0.3048 0.2032)
						)
						(arc
							(start -0.3048 -0.2032)
							(mid -0.275042 -0.275042)
							(end -0.2032 -0.3048)
						)
						(arc
							(start 0.2032 -0.3048)
							(mid 0.275042 -0.275042)
							(end 0.3048 -0.2032)
						)
					)
					(width 0)
					(fill yes)
				)
			)
		)
	)
	(footprint ""
		(layer "B.Cu")
		(at 127.679958 -22.049994)
		(property "Reference" "CN2"
			(at 0 0 0)
			(layer "B.SilkS")
			(hide yes)
			(effects
				(font
					(size 1.27 1.27)
				)
				(justify mirror)
			)
		)
		(property "Value" "AMP-CON4-S7-GP"
			(at -3.5306 -4.9784 0)
			(unlocked yes)
			(layer "B.Fab")
			(hide yes)
			(effects
				(font
					(size 1.016 1.016)
					(thickness 0.1524)
				)
				(justify mirror)
			)
		)
		(property "Device Type" "G88MPB04102CEU"
			(at -3.5306 -6.5024 0)
			(unlocked yes)
			(layer "B.Fab")
			(hide yes)
			(effects
				(font
					(size 1.016 1.016)
					(thickness 0.1524)
				)
				(justify mirror)
			)
		)
		(duplicate_pad_numbers_are_jumpers no)
		(fp_line
			(start -8.509 -2.286)
			(end -7.239 -2.286)
			(stroke
				(width 0.4064)
				(type default)
			)
			(layer "B.SilkS")
		)
		(fp_line
			(start -8.509 -1.016)
			(end -8.509 -2.286)
			(stroke
				(width 0.4064)
				(type default)
			)
			(layer "B.SilkS")
		)
		(fp_line
			(start -8.382 -2.159)
			(end -8.382 2.8448)
			(stroke
				(width 0.1524)
				(type default)
			)
			(layer "B.SilkS")
		)
		(fp_line
			(start -8.382 2.8448)
			(end 8.382 2.8448)
			(stroke
				(width 0.1524)
				(type default)
			)
			(layer "B.SilkS")
		)
		(fp_line
			(start -1.7526 -3.3528)
			(end -1.7526 -2.159)
			(stroke
				(width 0.1524)
				(type default)
			)
			(layer "B.SilkS")
		)
		(fp_line
			(start -1.7526 -2.159)
			(end -8.382 -2.159)
			(stroke
				(width 0.1524)
				(type default)
			)
			(layer "B.SilkS")
		)
		(fp_line
			(start 1.7526 -3.3528)
			(end -1.7526 -3.3528)
			(stroke
				(width 0.1524)
				(type default)
			)
			(layer "B.SilkS")
		)
		(fp_line
			(start 1.7526 -2.159)
			(end 1.7526 -3.3528)
			(stroke
				(width 0.1524)
				(type default)
			)
			(layer "B.SilkS")
		)
		(fp_line
			(start 8.382 -2.159)
			(end 1.7526 -2.159)
			(stroke
				(width 0.1524)
				(type default)
			)
			(layer "B.SilkS")
		)
		(fp_line
			(start 8.382 2.8448)
			(end 8.382 -2.159)
			(stroke
				(width 0.1524)
				(type default)
			)
			(layer "B.SilkS")
		)
		(fp_circle
			(center -4.500118 0)
			(end -3.242818 0)
			(stroke
				(width 0.3048)
				(type default)
			)
			(fill no)
			(layer "B.SilkS")
		)
		(fp_circle
			(center -1.500124 0)
			(end -0.242824 0)
			(stroke
				(width 0.3048)
				(type default)
			)
			(fill no)
			(layer "B.SilkS")
		)
		(fp_circle
			(center 1.500124 0)
			(end 2.757424 0)
			(stroke
				(width 0.3048)
				(type default)
			)
			(fill no)
			(layer "B.SilkS")
		)
		(fp_circle
			(center 4.500118 0)
			(end 5.757418 0)
			(stroke
				(width 0.3048)
				(type default)
			)
			(fill no)
			(layer "B.SilkS")
		)
		(fp_poly
			(pts
				(xy 7.8232 -1.905) (xy 1.4986 -1.905) (xy 1.4986 -3.0988) (xy -1.4986 -3.0988) (xy -1.4986 -1.905)
				(xy -7.8232 -1.905) (xy -7.8232 2.4638) (xy 7.8232 2.4638)
			)
			(stroke
				(width 0)
				(type default)
			)
			(fill no)
			(layer "B.CrtYd")
		)
		(fp_poly
			(pts
				(xy 8.636 3.0988) (xy 8.636 -2.413) (xy 2.0066 -2.413) (xy 2.0066 -3.6068) (xy -2.0066 -3.6068)
				(xy -2.0066 -2.413) (xy -8.636 -2.413) (xy -8.636 -0.00635) (xy -7.8232 -0.00635) (xy -7.8232 -1.905)
				(xy -1.4986 -1.905) (xy -1.4986 -3.0988) (xy 1.4986 -3.0988) (xy 1.4986 -1.905) (xy 7.8232 -1.905)
				(xy 7.8232 2.4638) (xy -7.8232 2.4638) (xy -7.8232 0.00635) (xy -8.636 0.00635) (xy -8.636 3.0988)
			)
			(stroke
				(width 0)
				(type default)
			)
			(fill no)
			(layer "B.CrtYd")
		)
		(fp_poly
			(pts
				(xy 8.636 3.0988) (xy 8.636 -2.413) (xy 2.0066 -2.413) (xy 2.0066 -3.6068) (xy -2.0066 -3.6068)
				(xy -2.0066 -2.413) (xy -8.636 -2.413) (xy -8.636 3.0988)
			)
			(stroke
				(width 0)
				(type default)
			)
			(fill no)
			(layer "B.Fab")
		)
		(pad "" np_thru_hole circle
			(at -7.500112 1.960118 180)
			(size 0.254 0.254)
			(drill 1.27)
			(layers "*.Cu" "*.Mask")
			(clearance 0.8636)
			(thermal_gap 0.8636)
		)
		(pad "" np_thru_hole circle
			(at 7.500112 1.960118 180)
			(size 0.254 0.254)
			(drill 1.27)
			(layers "*.Cu" "*.Mask")
			(clearance 0.8636)
			(thermal_gap 0.8636)
		)
		(pad "1" thru_hole circle
			(at -4.500118 0 180)
			(size 1.8034 1.8034)
			(drill 1.1684)
			(layers "*.Cu" "*.Mask")
			(remove_unused_layers no)
			(net "P12V")
			(clearance 0.1905)
			(thermal_gap 0.1905)
		)
		(pad "2" thru_hole circle
			(at -1.500124 0 180)
			(size 1.8034 1.8034)
			(drill 1.1684)
			(layers "*.Cu" "*.Mask")
			(remove_unused_layers no)
			(net "GND")
			(clearance 0.1905)
			(thermal_gap 0.1905)
		)
		(pad "3" thru_hole circle
			(at 1.500124 0 180)
			(size 1.8034 1.8034)
			(drill 1.1684)
			(layers "*.Cu" "*.Mask")
			(remove_unused_layers no)
			(net "GND")
			(clearance 0.1905)
			(thermal_gap 0.1905)
		)
		(pad "4" thru_hole circle
			(at 4.500118 0 180)
			(size 1.8034 1.8034)
			(drill 1.1684)
			(layers "*.Cu" "*.Mask")
			(remove_unused_layers no)
			(net "P5V")
			(clearance 0.1905)
			(thermal_gap 0.1905)
		)
		(zone
			(layers "F.Cu" "B.Cu" "In1.Cu" "In2.Cu" "In3.Cu" "In4.Cu")
			(hatch none 0.5)
			(connect_pads
				(clearance 0)
			)
			(min_thickness 0.25)
			(keepout
				(tracks not_allowed)
				(vias allowed)
				(pads allowed)
				(copperpour not_allowed)
				(footprints allowed)
			)
			(placement
				(enabled no)
				(sheetname "")
			)
			(fill
				(thermal_gap 0.5)
				(thermal_bridge_width 0.5)
				(island_removal_mode 0)
			)
			(polygon
				(pts
					(arc
						(start 121.119646 -20.089876)
						(mid 119.240046 -20.089876)
						(end 121.119646 -20.089876)
					)
				)
			)
		)
		(zone
			(layers "F.Cu" "B.Cu" "In1.Cu" "In2.Cu" "In3.Cu" "In4.Cu")
			(hatch none 0.5)
			(connect_pads
				(clearance 0)
			)
			(min_thickness 0.25)
			(keepout
				(tracks not_allowed)
				(vias allowed)
				(pads allowed)
				(copperpour not_allowed)
				(footprints allowed)
			)
			(placement
				(enabled no)
				(sheetname "")
			)
			(fill
				(thermal_gap 0.5)
				(thermal_bridge_width 0.5)
				(island_removal_mode 0)
			)
			(polygon
				(pts
					(arc
						(start 136.11987 -20.089876)
						(mid 134.24027 -20.089876)
						(end 136.11987 -20.089876)
					)
				)
			)
		)
	)
	(footprint ""
		(layer "B.Cu")
		(at 81.026 -39.878 90)
		(property "Reference" "U9"
			(at 0 0 90)
			(layer "B.SilkS")
			(hide yes)
			(effects
				(font
					(size 1.27 1.27)
				)
				(justify mirror)
			)
		)
		(property "Value" "P2003EVG-GP"
			(at 0 -11.1252 90)
			(unlocked yes)
			(layer "B.Fab")
			(hide yes)
			(effects
				(font
					(size 1.016 1.016)
					(thickness 0.1524)
				)
				(justify mirror)
			)
		)
		(property "Device Type" "SOIC8H79"
			(at 0 -12.6492 90)
			(unlocked yes)
			(layer "B.Fab")
			(hide yes)
			(effects
				(font
					(size 1.016 1.016)
					(thickness 0.1524)
				)
				(justify mirror)
			)
		)
		(duplicate_pad_numbers_are_jumpers no)
		(fp_line
			(start 2.7432 -1.4224)
			(end 2.7432 1.4224)
			(stroke
				(width 0.1524)
				(type default)
			)
			(layer "B.SilkS")
		)
		(fp_line
			(start -2.1336 -1.4224)
			(end 2.7432 -1.4224)
			(stroke
				(width 0.1524)
				(type default)
			)
			(layer "B.SilkS")
		)
		(fp_line
			(start 2.7432 -0.508)
			(end 2.2352 0)
			(stroke
				(width 0.1524)
				(type default)
			)
			(layer "B.SilkS")
		)
		(fp_line
			(start 2.2352 0)
			(end 2.7432 0.508)
			(stroke
				(width 0.1524)
				(type default)
			)
			(layer "B.SilkS")
		)
		(fp_line
			(start 2.7432 1.4224)
			(end -2.1336 1.4224)
			(stroke
				(width 0.1524)
				(type default)
			)
			(layer "B.SilkS")
		)
		(fp_line
			(start -2.1336 1.4224)
			(end -2.1336 -1.4224)
			(stroke
				(width 0.1524)
				(type default)
			)
			(layer "B.SilkS")
		)
		(fp_line
			(start 2.6162 3.429)
			(end 2.6162 1.4732)
			(stroke
				(width 0.4064)
				(type default)
			)
			(layer "B.SilkS")
		)
		(fp_poly
			(pts
				(xy -2.2098 -1.4224) (xy -2.2098 1.4224) (xy 2.2225 1.4224) (xy 2.2225 -1.4224)
			)
			(stroke
				(width 0)
				(type default)
			)
			(fill yes)
			(layer "B.SilkS")
		)
		(fp_rect
			(start 2.4511 2.9972)
			(end -2.4511 -2.9972)
			(stroke
				(width 0)
				(type default)
			)
			(fill no)
			(layer "B.CrtYd")
		)
		(fp_poly
			(pts
				(xy 2.8194 3.6322) (xy 2.8194 -3.6322) (xy -2.8194 -3.6322) (xy -2.8194 -2.2987) (xy -2.4511 -2.2987)
				(xy -2.4511 -2.9972) (xy 2.4511 -2.9972) (xy 2.4511 2.9972) (xy -2.4511 2.9972) (xy -2.4511 -2.286)
				(xy -2.8194 -2.286) (xy -2.8194 3.6322)
			)
			(stroke
				(width 0)
				(type default)
			)
			(fill no)
			(layer "B.CrtYd")
		)
		(fp_rect
			(start 2.8194 3.6322)
			(end -2.8194 -3.6322)
			(stroke
				(width 0)
				(type default)
			)
			(fill no)
			(layer "B.Fab")
		)
		(pad "1" smd rect
			(at 1.905 2.54 270)
			(size 0.635 1.651)
			(layers "B.Cu" "B.Mask" "B.Paste")
			(net "P12V")
		)
		(pad "2" smd rect
			(at 0.635 2.54 270)
			(size 0.635 1.651)
			(layers "B.Cu" "B.Mask" "B.Paste")
			(net "P12V")
		)
		(pad "3" smd rect
			(at -0.635 2.54 270)
			(size 0.635 1.651)
			(layers "B.Cu" "B.Mask" "B.Paste")
			(net "P12V")
		)
		(pad "4" smd rect
			(at -1.905 2.54 270)
			(size 0.635 1.651)
			(layers "B.Cu" "B.Mask" "B.Paste")
			(net "SW_SW_R_N_0")
		)
		(pad "5" smd rect
			(at -1.905 -2.54 270)
			(size 0.635 1.651)
			(layers "B.Cu" "B.Mask" "B.Paste")
			(net "P12V_SW_R")
		)
		(pad "6" smd rect
			(at -0.635 -2.54 270)
			(size 0.635 1.651)
			(layers "B.Cu" "B.Mask" "B.Paste")
			(net "P12V_SW_R")
		)
		(pad "7" smd rect
			(at 0.635 -2.54 270)
			(size 0.635 1.651)
			(layers "B.Cu" "B.Mask" "B.Paste")
			(net "P12V_SW_R")
		)
		(pad "8" smd rect
			(at 1.905 -2.54 270)
			(size 0.635 1.651)
			(layers "B.Cu" "B.Mask" "B.Paste")
			(net "P12V_SW_R")
		)
	)
	(gr_line
		(start 80.920336 -20.748752)
		(end 80.947768 -20.614894)
		(stroke
			(width 0.10668)
			(type default)
		)
		(layer "F.Cu")
	)
	(gr_line
		(start 80.920336 -20.748752)
		(end 80.997044 -20.864322)
		(stroke
			(width 0.10668)
			(type default)
		)
		(layer "F.Cu")
	)
	(gr_line
		(start 81.26984 -19.032982)
		(end 81.297526 -18.8976)
		(stroke
			(width 0.10668)
			(type default)
		)
		(layer "F.Cu")
	)
	(gr_line
		(start 81.297526 -18.8976)
		(end 81.412588 -18.8214)
		(stroke
			(width 0.10668)
			(type default)
		)
		(layer "F.Cu")
	)
	(gr_line
		(start 81.542382 -21.68779)
		(end 81.618074 -21.801836)
		(stroke
			(width 0.10668)
			(type default)
		)
		(layer "F.Cu")
	)
	(gr_line
		(start 81.618074 -21.801836)
		(end 81.752186 -21.829268)
		(stroke
			(width 0.10668)
			(type default)
		)
		(layer "F.Cu")
	)
	(gr_line
		(start 82.207354 -18.295366)
		(end 82.3214 -18.219928)
		(stroke
			(width 0.10668)
			(type default)
		)
		(layer "F.Cu")
	)
	(gr_line
		(start 82.3214 -18.219928)
		(end 82.453734 -18.246852)
		(stroke
			(width 0.10668)
			(type default)
		)
		(layer "F.Cu")
	)
	(gr_line
		(start 82.971894 -22.067774)
		(end 83.086956 -22.182836)
		(stroke
			(width 0.10668)
			(type default)
		)
		(layer "F.Cu")
	)
	(gr_line
		(start 82.971894 -21.439124)
		(end 83.086956 -21.324062)
		(stroke
			(width 0.10668)
			(type default)
		)
		(layer "F.Cu")
	)
	(gr_line
		(start 83.041998 -18.82013)
		(end 83.218528 -19.08683)
		(stroke
			(width 0.10668)
			(type default)
		)
		(layer "F.Cu")
	)
	(gr_line
		(start 83.086956 -21.166836)
		(end 83.086956 -21.324062)
		(stroke
			(width 0.10668)
			(type default)
		)
		(layer "F.Cu")
	)
	(gr_line
		(start 83.174586 -18.39341)
		(end 84.158328 -18.593562)
		(stroke
			(width 0.10668)
			(type default)
		)
		(layer "F.Cu")
	)
	(gr_line
		(start 83.218528 -19.08683)
		(end 83.845654 -19.214338)
		(stroke
			(width 0.10668)
			(type default)
		)
		(layer "F.Cu")
	)
	(gr_line
		(start 83.845654 -19.214338)
		(end 84.112608 -19.037808)
		(stroke
			(width 0.10668)
			(type default)
		)
		(layer "F.Cu")
	)
	(gr_line
		(start 84.450936 -23.889462)
		(end 84.459572 -23.93188)
		(stroke
			(width 0.10668)
			(type default)
		)
		(layer "F.Cu")
	)
	(gr_line
		(start 84.450936 -23.889462)
		(end 84.459572 -23.847044)
		(stroke
			(width 0.10668)
			(type default)
		)
		(layer "F.Cu")
	)
	(gr_line
		(start 84.459572 -23.846536)
		(end 84.459572 -23.84679)
		(stroke
			(width 0.10668)
			(type default)
		)
		(layer "F.Cu")
	)
	(gr_line
		(start 84.696046 -22.682962)
		(end 84.723224 -22.549358)
		(stroke
			(width 0.10668)
			(type default)
		)
		(layer "F.Cu")
	)
	(gr_line
		(start 84.704174 -25.133808)
		(end 84.712048 -25.172162)
		(stroke
			(width 0.10668)
			(type default)
		)
		(layer "F.Cu")
	)
	(gr_line
		(start 84.712048 -25.172162)
		(end 84.733384 -25.20442)
		(stroke
			(width 0.10668)
			(type default)
		)
		(layer "F.Cu")
	)
	(gr_line
		(start 84.723224 -22.549358)
		(end 84.836762 -22.474174)
		(stroke
			(width 0.10668)
			(type default)
		)
		(layer "F.Cu")
	)
	(gr_line
		(start 84.74456 -19.166332)
		(end 84.92109 -19.433286)
		(stroke
			(width 0.10668)
			(type default)
		)
		(layer "F.Cu")
	)
	(gr_line
		(start 84.876386 -18.739612)
		(end 85.858858 -18.93951)
		(stroke
			(width 0.10668)
			(type default)
		)
		(layer "F.Cu")
	)
	(gr_line
		(start 84.92109 -19.433286)
		(end 85.548216 -19.560794)
		(stroke
			(width 0.10668)
			(type default)
		)
		(layer "F.Cu")
	)
	(gr_line
		(start 85.548216 -19.560794)
		(end 85.814916 -19.384264)
		(stroke
			(width 0.10668)
			(type default)
		)
		(layer "F.Cu")
	)
	(gr_line
		(start 86.263988 -21.529548)
		(end 86.335108 -21.482558)
		(stroke
			(width 0.10668)
			(type default)
		)
		(layer "F.Cu")
	)
	(gr_line
		(start 86.328504 -28.02255)
		(end 86.528656 -29.006546)
		(stroke
			(width 0.10668)
			(type default)
		)
		(layer "F.Cu")
	)
	(gr_line
		(start 86.603332 -27.228292)
		(end 86.624668 -27.260804)
		(stroke
			(width 0.10668)
			(type default)
		)
		(layer "F.Cu")
	)
	(gr_line
		(start 86.624668 -27.260804)
		(end 86.632542 -27.298904)
		(stroke
			(width 0.10668)
			(type default)
		)
		(layer "F.Cu")
	)
	(gr_line
		(start 86.624668 -19.095212)
		(end 86.663022 -19.103086)
		(stroke
			(width 0.10668)
			(type default)
		)
		(layer "F.Cu")
	)
	(gr_line
		(start 86.663022 -19.103086)
		(end 86.695026 -19.124168)
		(stroke
			(width 0.10668)
			(type default)
		)
		(layer "F.Cu")
	)
	(gr_line
		(start 86.674706 -29.72435)
		(end 86.875112 -30.709108)
		(stroke
			(width 0.10668)
			(type default)
		)
		(layer "F.Cu")
	)
	(gr_line
		(start 86.755224 -27.889962)
		(end 87.021924 -28.066492)
		(stroke
			(width 0.10668)
			(type default)
		)
		(layer "F.Cu")
	)
	(gr_line
		(start 86.93531 -22.017736)
		(end 87.129112 -22.211538)
		(stroke
			(width 0.10668)
			(type default)
		)
		(layer "F.Cu")
	)
	(gr_line
		(start 86.93531 -21.38934)
		(end 87.129112 -21.195538)
		(stroke
			(width 0.10668)
			(type default)
		)
		(layer "F.Cu")
	)
	(gr_line
		(start 86.972902 -28.960572)
		(end 87.149432 -28.693618)
		(stroke
			(width 0.10668)
			(type default)
		)
		(layer "F.Cu")
	)
	(gr_line
		(start 87.021162 -31.426912)
		(end 87.221568 -32.41167)
		(stroke
			(width 0.10668)
			(type default)
		)
		(layer "F.Cu")
	)
	(gr_line
		(start 87.021924 -28.066492)
		(end 87.149432 -28.693618)
		(stroke
			(width 0.10668)
			(type default)
		)
		(layer "F.Cu")
	)
	(gr_line
		(start 87.101426 -29.592524)
		(end 87.36838 -29.769054)
		(stroke
			(width 0.10668)
			(type default)
		)
		(layer "F.Cu")
	)
	(gr_line
		(start 87.319358 -30.663134)
		(end 87.495888 -30.39618)
		(stroke
			(width 0.10668)
			(type default)
		)
		(layer "F.Cu")
	)
	(gr_line
		(start 87.367618 -33.128966)
		(end 87.56777 -34.113724)
		(stroke
			(width 0.10668)
			(type default)
		)
		(layer "F.Cu")
	)
	(gr_line
		(start 87.36838 -29.769054)
		(end 87.495888 -30.39618)
		(stroke
			(width 0.10668)
			(type default)
		)
		(layer "F.Cu")
	)
	(gr_line
		(start 87.447882 -31.294832)
		(end 87.714836 -31.471616)
		(stroke
			(width 0.10668)
			(type default)
		)
		(layer "F.Cu")
	)
	(gr_line
		(start 87.59825 -20.254976)
		(end 87.662004 -20.568666)
		(stroke
			(width 0.10668)
			(type default)
		)
		(layer "F.Cu")
	)
	(gr_line
		(start 87.662004 -20.568666)
		(end 88.195658 -20.92198)
		(stroke
			(width 0.10668)
			(type default)
		)
		(layer "F.Cu")
	)
	(gr_line
		(start 87.665814 -32.36595)
		(end 87.842344 -32.098742)
		(stroke
			(width 0.10668)
			(type default)
		)
		(layer "F.Cu")
	)
	(gr_line
		(start 87.714836 -31.471616)
		(end 87.842344 -32.098742)
		(stroke
			(width 0.10668)
			(type default)
		)
		(layer "F.Cu")
	)
	(gr_line
		(start 87.794338 -32.997394)
		(end 88.061292 -33.174178)
		(stroke
			(width 0.10668)
			(type default)
		)
		(layer "F.Cu")
	)
	(gr_line
		(start 87.879936 -19.908266)
		(end 88.719152 -20.463764)
		(stroke
			(width 0.10668)
			(type default)
		)
		(layer "F.Cu")
	)
	(gr_line
		(start 88.012016 -34.068258)
		(end 88.1888 -33.801304)
		(stroke
			(width 0.10668)
			(type default)
		)
		(layer "F.Cu")
	)
	(gr_line
		(start 88.061292 -33.174178)
		(end 88.1888 -33.801304)
		(stroke
			(width 0.10668)
			(type default)
		)
		(layer "F.Cu")
	)
	(gr_line
		(start 88.195658 -20.92198)
		(end 88.509348 -20.858226)
		(stroke
			(width 0.10668)
			(type default)
		)
		(layer "F.Cu")
	)
	(gr_line
		(start 89.03081 -41.305226)
		(end 89.038684 -41.34358)
		(stroke
			(width 0.10668)
			(type default)
		)
		(layer "F.Cu")
	)
	(gr_line
		(start 89.038684 -41.34358)
		(end 89.06002 -41.376092)
		(stroke
			(width 0.10668)
			(type default)
		)
		(layer "F.Cu")
	)
	(gr_line
		(start 89.047066 -21.21408)
		(end 89.11082 -21.527516)
		(stroke
			(width 0.10668)
			(type default)
		)
		(layer "F.Cu")
	)
	(gr_line
		(start 89.11082 -21.527516)
		(end 89.644474 -21.88083)
		(stroke
			(width 0.10668)
			(type default)
		)
		(layer "F.Cu")
	)
	(gr_line
		(start 89.32799 -20.867116)
		(end 90.16619 -21.421598)
		(stroke
			(width 0.10668)
			(type default)
		)
		(layer "F.Cu")
	)
	(gr_line
		(start 89.644474 -21.88083)
		(end 89.95791 -21.817076)
		(stroke
			(width 0.10668)
			(type default)
		)
		(layer "F.Cu")
	)
	(gr_line
		(start 90.778076 -21.826728)
		(end 90.814144 -21.850604)
		(stroke
			(width 0.10668)
			(type default)
		)
		(layer "F.Cu")
	)
	(gr_line
		(start 90.783918 -23.020274)
		(end 90.847672 -22.706584)
		(stroke
			(width 0.10668)
			(type default)
		)
		(layer "F.Cu")
	)
	(gr_line
		(start 90.783918 -23.020274)
		(end 91.137232 -23.553928)
		(stroke
			(width 0.10668)
			(type default)
		)
		(layer "F.Cu")
	)
	(gr_line
		(start 90.814144 -21.850604)
		(end 90.83802 -21.886672)
		(stroke
			(width 0.10668)
			(type default)
		)
		(layer "F.Cu")
	)
	(gr_line
		(start 91.137232 -23.553928)
		(end 91.450668 -23.617682)
		(stroke
			(width 0.10668)
			(type default)
		)
		(layer "F.Cu")
	)
	(gr_line
		(start 91.242896 -22.498558)
		(end 91.797886 -23.336758)
		(stroke
			(width 0.10668)
			(type default)
		)
		(layer "F.Cu")
	)
	(gr_line
		(start 91.742768 -24.46909)
		(end 91.806522 -24.1554)
		(stroke
			(width 0.10668)
			(type default)
		)
		(layer "F.Cu")
	)
	(gr_line
		(start 91.742768 -24.46909)
		(end 92.096082 -25.002744)
		(stroke
			(width 0.10668)
			(type default)
		)
		(layer "F.Cu")
	)
	(gr_line
		(start 92.096082 -25.002744)
		(end 92.409772 -25.066752)
		(stroke
			(width 0.10668)
			(type default)
		)
		(layer "F.Cu")
	)
	(gr_line
		(start 92.201238 -23.946104)
		(end 92.757498 -24.78659)
		(stroke
			(width 0.10668)
			(type default)
		)
		(layer "F.Cu")
	)
	(gr_line
		(start 92.468954 -46.52645)
		(end 92.49283 -46.562518)
		(stroke
			(width 0.10668)
			(type default)
		)
		(layer "F.Cu")
	)
	(gr_line
		(start 92.49283 -46.562518)
		(end 92.528898 -46.586394)
		(stroke
			(width 0.10668)
			(type default)
		)
		(layer "F.Cu")
	)
	(gr_line
		(start 92.701618 -25.917906)
		(end 92.765372 -25.603962)
		(stroke
			(width 0.10668)
			(type default)
		)
		(layer "F.Cu")
	)
	(gr_line
		(start 92.701618 -25.917906)
		(end 93.054932 -26.45156)
		(stroke
			(width 0.10668)
			(type default)
		)
		(layer "F.Cu")
	)
	(gr_line
		(start 93.054932 -26.45156)
		(end 93.368876 -26.515568)
		(stroke
			(width 0.10668)
			(type default)
		)
		(layer "F.Cu")
	)
	(gr_line
		(start 93.15958 -25.393904)
		(end 93.716856 -26.235914)
		(stroke
			(width 0.10668)
			(type default)
		)
		(layer "F.Cu")
	)
	(gr_line
		(start 93.660468 -27.366722)
		(end 93.724476 -27.052778)
		(stroke
			(width 0.10668)
			(type default)
		)
		(layer "F.Cu")
	)
	(gr_line
		(start 93.660468 -27.366722)
		(end 94.013782 -27.900376)
		(stroke
			(width 0.10668)
			(type default)
		)
		(layer "F.Cu")
	)
	(gr_line
		(start 94.013782 -27.900376)
		(end 94.327726 -27.964384)
		(stroke
			(width 0.10668)
			(type default)
		)
		(layer "F.Cu")
	)
	(gr_line
		(start 94.117922 -26.841958)
		(end 94.675452 -27.684222)
		(stroke
			(width 0.10668)
			(type default)
		)
		(layer "F.Cu")
	)
	(gr_line
		(start 95.892112 -30.737556)
		(end 95.955612 -30.423866)
		(stroke
			(width 0.10668)
			(type default)
		)
		(layer "F.Cu")
	)
	(gr_line
		(start 95.892112 -30.737556)
		(end 96.245426 -31.27121)
		(stroke
			(width 0.10668)
			(type default)
		)
		(layer "F.Cu")
	)
	(gr_line
		(start 96.245426 -31.27121)
		(end 96.558862 -31.334964)
		(stroke
			(width 0.10668)
			(type default)
		)
		(layer "F.Cu")
	)
	(gr_line
		(start 96.350582 -30.215078)
		(end 96.904302 -31.051754)
		(stroke
			(width 0.10668)
			(type default)
		)
		(layer "F.Cu")
	)
	(gr_line
		(start 96.850962 -32.186372)
		(end 96.914716 -31.872936)
		(stroke
			(width 0.10668)
			(type default)
		)
		(layer "F.Cu")
	)
	(gr_line
		(start 96.850962 -32.186372)
		(end 97.204276 -32.720026)
		(stroke
			(width 0.10668)
			(type default)
		)
		(layer "F.Cu")
	)
	(gr_line
		(start 97.204276 -32.720026)
		(end 97.517712 -32.78378)
		(stroke
			(width 0.10668)
			(type default)
		)
		(layer "F.Cu")
	)
	(gr_line
		(start 97.310956 -31.666434)
		(end 97.863152 -32.50057)
		(stroke
			(width 0.10668)
			(type default)
		)
		(layer "F.Cu")
	)
	(gr_line
		(start 97.620074 -51.74996)
		(end 97.940876 -51.429158)
		(stroke
			(width 0.10668)
			(type default)
		)
		(layer "F.Cu")
	)
	(gr_line
		(start 97.620074 -35.049968)
		(end 98.172778 -34.497264)
		(stroke
			(width 0.10668)
			(type default)
		)
		(layer "F.Cu")
	)
	(gr_line
		(start 97.88017 -49.598072)
		(end 97.916238 -49.621948)
		(stroke
			(width 0.10668)
			(type default)
		)
		(layer "F.Cu")
	)
	(gr_line
		(start 97.916238 -49.621948)
		(end 97.940114 -49.658016)
		(stroke
			(width 0.10668)
			(type default)
		)
		(layer "F.Cu")
	)
	(gr_line
		(start 98.477324 -33.427924)
		(end 98.49866 -33.460436)
		(stroke
			(width 0.10668)
			(type default)
		)
		(layer "F.Cu")
	)
	(gr_line
		(start 98.48088 -50.475388)
		(end 98.528378 -50.54727)
		(stroke
			(width 0.10668)
			(type default)
		)
		(layer "F.Cu")
	)
	(gr_line
		(start 98.49866 -33.460436)
		(end 98.506534 -33.49879)
		(stroke
			(width 0.10668)
			(type default)
		)
		(layer "F.Cu")
	)
	(gr_line
		(start 98.569272 -51.429158)
		(end 98.890074 -51.74996)
		(stroke
			(width 0.10668)
			(type default)
		)
		(layer "F.Cu")
	)
	(gr_line
		(start 98.617278 -34.777172)
		(end 98.890074 -35.049968)
		(stroke
			(width 0.10668)
			(type default)
		)
		(layer "F.Cu")
	)
	(gr_line
		(start 27.504898 -13.850112)
		(end 27.8257 -14.170914)
		(stroke
			(width 0.10668)
			(type default)
		)
		(layer "B.Cu")
	)
	(gr_line
		(start 27.504898 -2.549906)
		(end 27.8257 -2.870708)
		(stroke
			(width 0.10668)
			(type default)
		)
		(layer "B.Cu")
	)
	(gr_line
		(start 27.918918 -14.749526)
		(end 27.966924 -14.821916)
		(stroke
			(width 0.10668)
			(type default)
		)
		(layer "B.Cu")
	)
	(gr_line
		(start 27.951684 -3.50901)
		(end 28.021788 -3.594862)
		(stroke
			(width 0.10668)
			(type default)
		)
		(layer "B.Cu")
	)
	(gr_line
		(start 28.22194 -15.205456)
		(end 28.296616 -15.318232)
		(stroke
			(width 0.10668)
			(type default)
		)
		(layer "B.Cu")
	)
	(gr_line
		(start 28.296616 -15.318232)
		(end 28.429966 -15.34541)
		(stroke
			(width 0.10668)
			(type default)
		)
		(layer "B.Cu")
	)
	(gr_line
		(start 28.311348 -3.949192)
		(end 28.381706 -4.035552)
		(stroke
			(width 0.10668)
			(type default)
		)
		(layer "B.Cu")
	)
	(gr_line
		(start 28.381706 -4.035552)
		(end 28.49118 -4.05765)
		(stroke
			(width 0.10668)
			(type default)
		)
		(layer "B.Cu")
	)
	(gr_line
		(start 28.454096 -14.170914)
		(end 28.774898 -13.850112)
		(stroke
			(width 0.10668)
			(type default)
		)
		(layer "B.Cu")
	)
	(gr_line
		(start 28.454096 -2.870708)
		(end 28.774898 -2.549906)
		(stroke
			(width 0.10668)
			(type default)
		)
		(layer "B.Cu")
	)
	(gr_line
		(start 30.627828 -4.492498)
		(end 30.670246 -4.501134)
		(stroke
			(width 0.10668)
			(type default)
		)
		(layer "B.Cu")
	)
	(gr_line
		(start 30.670246 -4.501134)
		(end 30.712664 -4.492498)
		(stroke
			(width 0.10668)
			(type default)
		)
		(layer "B.Cu")
	)
	(gr_line
		(start 31.371286 -15.943834)
		(end 31.413704 -15.95247)
		(stroke
			(width 0.10668)
			(type default)
		)
		(layer "B.Cu")
	)
	(gr_line
		(start 31.413704 -15.95247)
		(end 31.456122 -15.943834)
		(stroke
			(width 0.10668)
			(type default)
		)
		(layer "B.Cu")
	)
	(gr_line
		(start 33.279588 -3.51917)
		(end 33.322006 -3.510534)
		(stroke
			(width 0.10668)
			(type default)
		)
		(layer "B.Cu")
	)
	(gr_line
		(start 33.322006 -3.510534)
		(end 33.364678 -3.51917)
		(stroke
			(width 0.10668)
			(type default)
		)
		(layer "B.Cu")
	)
	(gr_line
		(start 33.90519 -4.080256)
		(end 34.889948 -4.280662)
		(stroke
			(width 0.10668)
			(type default)
		)
		(layer "B.Cu")
	)
	(gr_line
		(start 33.951926 -3.636264)
		(end 34.21888 -3.459734)
		(stroke
			(width 0.10668)
			(type default)
		)
		(layer "B.Cu")
	)
	(gr_line
		(start 34.21888 -3.459734)
		(end 34.846006 -3.587242)
		(stroke
			(width 0.10668)
			(type default)
		)
		(layer "B.Cu")
	)
	(gr_line
		(start 34.39541 -14.894814)
		(end 34.437828 -14.886178)
		(stroke
			(width 0.10668)
			(type default)
		)
		(layer "B.Cu")
	)
	(gr_line
		(start 34.437828 -14.886178)
		(end 34.480246 -14.894814)
		(stroke
			(width 0.10668)
			(type default)
		)
		(layer "B.Cu")
	)
	(gr_line
		(start 34.846006 -3.587242)
		(end 35.022536 -3.853942)
		(stroke
			(width 0.10668)
			(type default)
		)
		(layer "B.Cu")
	)
	(gr_line
		(start 35.02152 -15.456154)
		(end 36.006024 -15.656306)
		(stroke
			(width 0.10668)
			(type default)
		)
		(layer "B.Cu")
	)
	(gr_line
		(start 35.067748 -15.011908)
		(end 35.334702 -14.835378)
		(stroke
			(width 0.10668)
			(type default)
		)
		(layer "B.Cu")
	)
	(gr_line
		(start 35.334702 -14.835378)
		(end 35.961828 -14.962886)
		(stroke
			(width 0.10668)
			(type default)
		)
		(layer "B.Cu")
	)
	(gr_line
		(start 35.610292 -4.426966)
		(end 36.58997 -4.626356)
		(stroke
			(width 0.10668)
			(type default)
		)
		(layer "B.Cu")
	)
	(gr_line
		(start 35.654488 -3.98272)
		(end 35.921442 -3.80619)
		(stroke
			(width 0.10668)
			(type default)
		)
		(layer "B.Cu")
	)
	(gr_line
		(start 35.921442 -3.80619)
		(end 36.548568 -3.933698)
		(stroke
			(width 0.10668)
			(type default)
		)
		(layer "B.Cu")
	)
	(gr_line
		(start 35.961828 -14.962886)
		(end 36.138358 -15.229586)
		(stroke
			(width 0.10668)
			(type default)
		)
		(layer "B.Cu")
	)
	(gr_line
		(start 36.548568 -3.933698)
		(end 36.725098 -4.200398)
		(stroke
			(width 0.10668)
			(type default)
		)
		(layer "B.Cu")
	)
	(gr_line
		(start 36.72459 -15.80261)
		(end 37.708332 -16.002762)
		(stroke
			(width 0.10668)
			(type default)
		)
		(layer "B.Cu")
	)
	(gr_line
		(start 36.77031 -15.358364)
		(end 37.037264 -15.181834)
		(stroke
			(width 0.10668)
			(type default)
		)
		(layer "B.Cu")
	)
	(gr_line
		(start 37.037264 -15.181834)
		(end 37.66439 -15.309342)
		(stroke
			(width 0.10668)
			(type default)
		)
		(layer "B.Cu")
	)
	(gr_line
		(start 37.313616 -4.773676)
		(end 38.293294 -4.973066)
		(stroke
			(width 0.10668)
			(type default)
		)
		(layer "B.Cu")
	)
	(gr_line
		(start 37.35705 -4.328922)
		(end 37.624004 -4.152646)
		(stroke
			(width 0.10668)
			(type default)
		)
		(layer "B.Cu")
	)
	(gr_line
		(start 37.624004 -4.152646)
		(end 38.25113 -4.280154)
		(stroke
			(width 0.10668)
			(type default)
		)
		(layer "B.Cu")
	)
	(gr_line
		(start 37.66439 -15.309342)
		(end 37.84092 -15.576042)
		(stroke
			(width 0.10668)
			(type default)
		)
		(layer "B.Cu")
	)
	(gr_line
		(start 38.25113 -4.280154)
		(end 38.42766 -4.546854)
		(stroke
			(width 0.10668)
			(type default)
		)
		(layer "B.Cu")
	)
	(gr_line
		(start 38.428168 -16.149066)
		(end 39.409116 -16.34871)
		(stroke
			(width 0.10668)
			(type default)
		)
		(layer "B.Cu")
	)
	(gr_line
		(start 38.473126 -15.704566)
		(end 38.739826 -15.52829)
		(stroke
			(width 0.10668)
			(type default)
		)
		(layer "B.Cu")
	)
	(gr_line
		(start 38.739826 -15.52829)
		(end 39.366952 -15.655798)
		(stroke
			(width 0.10668)
			(type default)
		)
		(layer "B.Cu")
	)
	(gr_line
		(start 39.015416 -5.119878)
		(end 39.99738 -5.319776)
		(stroke
			(width 0.10668)
			(type default)
		)
		(layer "B.Cu")
	)
	(gr_line
		(start 39.059866 -4.675378)
		(end 39.326566 -4.499102)
		(stroke
			(width 0.10668)
			(type default)
		)
		(layer "B.Cu")
	)
	(gr_line
		(start 39.326566 -4.499102)
		(end 39.953692 -4.62661)
		(stroke
			(width 0.10668)
			(type default)
		)
		(layer "B.Cu")
	)
	(gr_line
		(start 39.366952 -15.655798)
		(end 39.543482 -15.922498)
		(stroke
			(width 0.10668)
			(type default)
		)
		(layer "B.Cu")
	)
	(gr_line
		(start 39.953692 -4.62661)
		(end 40.130222 -4.89331)
		(stroke
			(width 0.10668)
			(type default)
		)
		(layer "B.Cu")
	)
	(gr_line
		(start 40.132508 -16.495776)
		(end 41.113456 -16.69542)
		(stroke
			(width 0.10668)
			(type default)
		)
		(layer "B.Cu")
	)
	(gr_line
		(start 40.175688 -16.051022)
		(end 40.442388 -15.874746)
		(stroke
			(width 0.10668)
			(type default)
		)
		(layer "B.Cu")
	)
	(gr_line
		(start 40.442388 -15.874746)
		(end 41.069514 -16.002254)
		(stroke
			(width 0.10668)
			(type default)
		)
		(layer "B.Cu")
	)
	(gr_line
		(start 41.069514 -16.002254)
		(end 41.246044 -16.268954)
		(stroke
			(width 0.10668)
			(type default)
		)
		(layer "B.Cu")
	)
	(gr_line
		(start 43.566334 -5.594858)
		(end 43.604688 -5.602732)
		(stroke
			(width 0.10668)
			(type default)
		)
		(layer "B.Cu")
	)
	(gr_line
		(start 43.604688 -5.602732)
		(end 43.6372 -5.624068)
		(stroke
			(width 0.10668)
			(type default)
		)
		(layer "B.Cu")
	)
	(gr_line
		(start 46.772576 -17.846802)
		(end 46.814994 -17.855438)
		(stroke
			(width 0.10668)
			(type default)
		)
		(layer "B.Cu")
	)
	(gr_line
		(start 46.814994 -17.855438)
		(end 46.857412 -17.846802)
		(stroke
			(width 0.10668)
			(type default)
		)
		(layer "B.Cu")
	)
	(gr_line
		(start 51.271424 -11.207242)
		(end 51.303936 -11.228578)
		(stroke
			(width 0.10668)
			(type default)
		)
		(layer "B.Cu")
	)
	(gr_line
		(start 51.303936 -11.228578)
		(end 51.34229 -11.236452)
		(stroke
			(width 0.10668)
			(type default)
		)
		(layer "B.Cu")
	)
	(gr_line
		(start 53.804566 -15.982696)
		(end 53.846984 -15.97406)
		(stroke
			(width 0.10668)
			(type default)
		)
		(layer "B.Cu")
	)
	(gr_line
		(start 53.846984 -15.97406)
		(end 53.889402 -15.982696)
		(stroke
			(width 0.10668)
			(type default)
		)
		(layer "B.Cu")
	)
	(gr_line
		(start 60.17768 -12.583668)
		(end 60.216034 -12.591542)
		(stroke
			(width 0.10668)
			(type default)
		)
		(layer "B.Cu")
	)
	(gr_line
		(start 60.216034 -12.591542)
		(end 60.248546 -12.612878)
		(stroke
			(width 0.10668)
			(type default)
		)
		(layer "B.Cu")
	)
	(gr_line
		(start 63.6397 -17.966436)
		(end 63.678054 -17.97431)
		(stroke
			(width 0.10668)
			(type default)
		)
		(layer "B.Cu")
	)
	(gr_line
		(start 63.678054 -17.97431)
		(end 63.710566 -17.995646)
		(stroke
			(width 0.10668)
			(type default)
		)
		(layer "B.Cu")
	)
	(gr_line
		(start 71.82104 -23.363174)
		(end 71.857108 -23.38705)
		(stroke
			(width 0.10668)
			(type default)
		)
		(layer "B.Cu")
	)
	(gr_line
		(start 71.857108 -23.38705)
		(end 71.880984 -23.423118)
		(stroke
			(width 0.10668)
			(type default)
		)
		(layer "B.Cu")
	)
	(gr_line
		(start 72.404478 -25.014682)
		(end 72.424544 -25.045162)
		(stroke
			(width 0.10668)
			(type default)
		)
		(layer "B.Cu")
	)
	(gr_line
		(start 72.424544 -25.045162)
		(end 72.455024 -25.066498)
		(stroke
			(width 0.10668)
			(type default)
		)
		(layer "B.Cu")
	)
	(gr_line
		(start 72.707246 -20.858988)
		(end 72.743314 -20.882864)
		(stroke
			(width 0.10668)
			(type default)
		)
		(layer "B.Cu")
	)
	(gr_line
		(start 72.743314 -20.882864)
		(end 72.767698 -20.91944)
		(stroke
			(width 0.10668)
			(type default)
		)
		(layer "B.Cu")
	)
	(gr_line
		(start 73.890632 -26.07183)
		(end 73.927716 -26.097738)
		(stroke
			(width 0.10668)
			(type default)
		)
		(layer "B.Cu")
	)
	(gr_line
		(start 73.927716 -26.097738)
		(end 73.970896 -26.106374)
		(stroke
			(width 0.10668)
			(type default)
		)
		(layer "B.Cu")
	)
	(gr_line
		(start 74.178922 -23.852378)
		(end 74.198734 -23.882604)
		(stroke
			(width 0.10668)
			(type default)
		)
		(layer "B.Cu")
	)
	(gr_line
		(start 74.198734 -23.882604)
		(end 74.228706 -23.903686)
		(stroke
			(width 0.10668)
			(type default)
		)
		(layer "B.Cu")
	)
	(gr_line
		(start 74.544174 -24.124412)
		(end 74.617326 -24.175974)
		(stroke
			(width 0.10668)
			(type default)
		)
		(layer "B.Cu")
	)
	(gr_line
		(start 75.131676 -24.280114)
		(end 75.18146 -24.329898)
		(stroke
			(width 0.10668)
			(type default)
		)
		(layer "B.Cu")
	)
	(gr_line
		(start 75.131676 -23.651718)
		(end 75.203304 -23.58009)
		(stroke
			(width 0.10668)
			(type default)
		)
		(layer "B.Cu")
	)
	(gr_line
		(start 75.18146 -24.329898)
		(end 75.584812 -24.329898)
		(stroke
			(width 0.10668)
			(type default)
		)
		(layer "B.Cu")
	)
	(gr_line
		(start 75.203304 -23.58009)
		(end 75.584812 -23.58009)
		(stroke
			(width 0.10668)
			(type default)
		)
		(layer "B.Cu")
	)
	(gr_line
		(start 75.53198 -26.424128)
		(end 75.665584 -26.451306)
		(stroke
			(width 0.10668)
			(type default)
		)
		(layer "B.Cu")
	)
	(gr_line
		(start 75.584812 -22.079966)
		(end 76.012802 -22.079966)
		(stroke
			(width 0.10668)
			(type default)
		)
		(layer "B.Cu")
	)
	(gr_line
		(start 75.584812 -21.329904)
		(end 75.954128 -21.329904)
		(stroke
			(width 0.10668)
			(type default)
		)
		(layer "B.Cu")
	)
	(gr_line
		(start 75.665584 -26.451306)
		(end 75.778614 -26.37663)
		(stroke
			(width 0.10668)
			(type default)
		)
		(layer "B.Cu")
	)
	(gr_line
		(start 75.954128 -21.329904)
		(end 76.044298 -21.420074)
		(stroke
			(width 0.10668)
			(type default)
		)
		(layer "B.Cu")
	)
	(gr_line
		(start 76.012802 -22.079966)
		(end 76.044298 -22.04847)
		(stroke
			(width 0.10668)
			(type default)
		)
		(layer "B.Cu")
	)
	(gr_line
		(start 76.869798 -18.523204)
		(end 76.896976 -18.388838)
		(stroke
			(width 0.10668)
			(type default)
		)
		(layer "B.Cu")
	)
	(gr_line
		(start 76.896976 -18.388838)
		(end 77.012038 -18.312892)
		(stroke
			(width 0.10668)
			(type default)
		)
		(layer "B.Cu")
	)
	(gr_line
		(start 77.824584 -17.774666)
		(end 77.937868 -17.699482)
		(stroke
			(width 0.10668)
			(type default)
		)
		(layer "B.Cu")
	)
	(gr_line
		(start 77.868526 -24.26462)
		(end 77.933804 -24.329898)
		(stroke
			(width 0.10668)
			(type default)
		)
		(layer "B.Cu")
	)
	(gr_line
		(start 77.868526 -23.636224)
		(end 77.92466 -23.58009)
		(stroke
			(width 0.10668)
			(type default)
		)
		(layer "B.Cu")
	)
	(gr_line
		(start 77.92466 -23.58009)
		(end 78.284832 -23.58009)
		(stroke
			(width 0.10668)
			(type default)
		)
		(layer "B.Cu")
	)
	(gr_line
		(start 77.933804 -24.329898)
		(end 78.284832 -24.329898)
		(stroke
			(width 0.10668)
			(type default)
		)
		(layer "B.Cu")
	)
	(gr_line
		(start 77.937868 -17.699482)
		(end 78.07071 -17.72666)
		(stroke
			(width 0.10668)
			(type default)
		)
		(layer "B.Cu")
	)
	(gr_line
		(start 78.284832 -22.079966)
		(end 78.798928 -22.079966)
		(stroke
			(width 0.10668)
			(type default)
		)
		(layer "B.Cu")
	)
	(gr_line
		(start 78.284832 -21.329904)
		(end 78.79207 -21.329904)
		(stroke
			(width 0.10668)
			(type default)
		)
		(layer "B.Cu")
	)
	(gr_line
		(start 78.79207 -21.329904)
		(end 78.856332 -21.394166)
		(stroke
			(width 0.10668)
			(type default)
		)
		(layer "B.Cu")
	)
	(gr_line
		(start 78.798928 -22.079966)
		(end 78.856332 -22.022562)
		(stroke
			(width 0.10668)
			(type default)
		)
		(layer "B.Cu")
	)
	(gr_line
		(start 79.517748 -18.47215)
		(end 79.560166 -18.480786)
		(stroke
			(width 0.10668)
			(type default)
		)
		(layer "B.Cu")
	)
	(gr_line
		(start 79.560166 -18.480786)
		(end 79.602584 -18.47215)
		(stroke
			(width 0.10668)
			(type default)
		)
		(layer "B.Cu")
	)
	(gr_line
		(start 79.870554 -24.001476)
		(end 79.87919 -24.043894)
		(stroke
			(width 0.10668)
			(type default)
		)
		(layer "B.Cu")
	)
	(gr_line
		(start 79.870554 -24.001476)
		(end 79.87919 -23.959058)
		(stroke
			(width 0.10668)
			(type default)
		)
		(layer "B.Cu")
	)
	(gr_line
		(start 79.944976 -21.589492)
		(end 80.079596 -21.616924)
		(stroke
			(width 0.10668)
			(type default)
		)
		(layer "B.Cu")
	)
	(gr_line
		(start 80.079596 -21.616924)
		(end 80.155542 -21.731732)
		(stroke
			(width 0.10668)
			(type default)
		)
		(layer "B.Cu")
	)
	(gr_line
		(start 80.273398 -25.981406)
		(end 80.281272 -26.01976)
		(stroke
			(width 0.10668)
			(type default)
		)
		(layer "B.Cu")
	)
	(gr_line
		(start 80.281272 -26.01976)
		(end 80.302608 -26.052018)
		(stroke
			(width 0.10668)
			(type default)
		)
		(layer "B.Cu")
	)
	(gr_line
		(start 80.560418 -22.343618)
		(end 80.635602 -22.457664)
		(stroke
			(width 0.10668)
			(type default)
		)
		(layer "B.Cu")
	)
	(gr_line
		(start 80.57007 -26.870406)
		(end 80.633824 -26.55697)
		(stroke
			(width 0.10668)
			(type default)
		)
		(layer "B.Cu")
	)
	(gr_line
		(start 80.57007 -26.870406)
		(end 80.923384 -27.40406)
		(stroke
			(width 0.10668)
			(type default)
		)
		(layer "B.Cu")
	)
	(gr_line
		(start 80.608424 -22.591268)
		(end 80.635602 -22.457664)
		(stroke
			(width 0.10668)
			(type default)
		)
		(layer "B.Cu")
	)
	(gr_line
		(start 80.896968 -17.757648)
		(end 80.939386 -17.749012)
		(stroke
			(width 0.10668)
			(type default)
		)
		(layer "B.Cu")
	)
	(gr_line
		(start 80.923384 -27.40406)
		(end 81.23682 -27.467814)
		(stroke
			(width 0.10668)
			(type default)
		)
		(layer "B.Cu")
	)
	(gr_line
		(start 80.939386 -17.749012)
		(end 80.981804 -17.757648)
		(stroke
			(width 0.10668)
			(type default)
		)
		(layer "B.Cu")
	)
	(gr_line
		(start 81.02981 -26.349706)
		(end 81.582514 -27.185112)
		(stroke
			(width 0.10668)
			(type default)
		)
		(layer "B.Cu")
	)
	(gr_line
		(start 81.52892 -28.319222)
		(end 81.592674 -28.005786)
		(stroke
			(width 0.10668)
			(type default)
		)
		(layer "B.Cu")
	)
	(gr_line
		(start 81.52892 -28.319222)
		(end 81.882234 -28.852876)
		(stroke
			(width 0.10668)
			(type default)
		)
		(layer "B.Cu")
	)
	(gr_line
		(start 81.814924 -24.329898)
		(end 82.299048 -24.329898)
		(stroke
			(width 0.10668)
			(type default)
		)
		(layer "B.Cu")
	)
	(gr_line
		(start 81.814924 -23.58009)
		(end 82.236564 -23.58009)
		(stroke
			(width 0.10668)
			(type default)
		)
		(layer "B.Cu")
	)
	(gr_line
		(start 81.814924 -22.079966)
		(end 82.253328 -22.079966)
		(stroke
			(width 0.10668)
			(type default)
		)
		(layer "B.Cu")
	)
	(gr_line
		(start 81.814924 -21.329904)
		(end 82.26933 -21.329904)
		(stroke
			(width 0.10668)
			(type default)
		)
		(layer "B.Cu")
	)
	(gr_line
		(start 81.882234 -28.852876)
		(end 82.19567 -28.91663)
		(stroke
			(width 0.10668)
			(type default)
		)
		(layer "B.Cu")
	)
	(gr_line
		(start 81.987898 -27.797506)
		(end 82.54238 -28.634944)
		(stroke
			(width 0.10668)
			(type default)
		)
		(layer "B.Cu")
	)
	(gr_line
		(start 82.236564 -23.58009)
		(end 82.328512 -23.672038)
		(stroke
			(width 0.10668)
			(type default)
		)
		(layer "B.Cu")
	)
	(gr_line
		(start 82.253328 -22.079966)
		(end 82.322162 -22.011132)
		(stroke
			(width 0.10668)
			(type default)
		)
		(layer "B.Cu")
	)
	(gr_line
		(start 82.26933 -21.329904)
		(end 82.322162 -21.382736)
		(stroke
			(width 0.10668)
			(type default)
		)
		(layer "B.Cu")
	)
	(gr_line
		(start 82.299048 -24.329898)
		(end 82.328512 -24.300434)
		(stroke
			(width 0.10668)
			(type default)
		)
		(layer "B.Cu")
	)
	(gr_line
		(start 82.652616 -25.70861)
		(end 82.846418 -25.514808)
		(stroke
			(width 0.10668)
			(type default)
		)
		(layer "B.Cu")
	)
	(gr_line
		(start 82.893154 -21.989034)
		(end 83.086956 -22.182836)
		(stroke
			(width 0.10668)
			(type default)
		)
		(layer "B.Cu")
	)
	(gr_line
		(start 82.893154 -21.360638)
		(end 83.086956 -21.166836)
		(stroke
			(width 0.10668)
			(type default)
		)
		(layer "B.Cu")
	)
	(gr_line
		(start 82.981546 -18.61566)
		(end 83.023964 -18.624296)
		(stroke
			(width 0.10668)
			(type default)
		)
		(layer "B.Cu")
	)
	(gr_line
		(start 83.023964 -18.624296)
		(end 83.066382 -18.61566)
		(stroke
			(width 0.10668)
			(type default)
		)
		(layer "B.Cu")
	)
	(gr_line
		(start 83.474814 -25.514808)
		(end 83.668616 -25.70861)
		(stroke
			(width 0.10668)
			(type default)
		)
		(layer "B.Cu")
	)
	(gr_line
		(start 84.237068 -17.926304)
		(end 84.279486 -17.917668)
		(stroke
			(width 0.10668)
			(type default)
		)
		(layer "B.Cu")
	)
	(gr_line
		(start 84.279486 -17.917668)
		(end 84.321904 -17.926304)
		(stroke
			(width 0.10668)
			(type default)
		)
		(layer "B.Cu")
	)
	(gr_line
		(start 84.514944 -24.329898)
		(end 84.943188 -24.329898)
		(stroke
			(width 0.10668)
			(type default)
		)
		(layer "B.Cu")
	)
	(gr_line
		(start 84.514944 -23.58009)
		(end 84.964524 -23.58009)
		(stroke
			(width 0.10668)
			(type default)
		)
		(layer "B.Cu")
	)
	(gr_line
		(start 84.514944 -22.079966)
		(end 85.012784 -22.079966)
		(stroke
			(width 0.10668)
			(type default)
		)
		(layer "B.Cu")
	)
	(gr_line
		(start 84.514944 -21.329904)
		(end 84.933028 -21.329904)
		(stroke
			(width 0.10668)
			(type default)
		)
		(layer "B.Cu")
	)
	(gr_line
		(start 84.933028 -21.329904)
		(end 85.033612 -21.430488)
		(stroke
			(width 0.10668)
			(type default)
		)
		(layer "B.Cu")
	)
	(gr_line
		(start 84.943188 -24.329898)
		(end 85.014562 -24.258524)
		(stroke
			(width 0.10668)
			(type default)
		)
		(layer "B.Cu")
	)
	(gr_line
		(start 84.964524 -23.58009)
		(end 85.014562 -23.630128)
		(stroke
			(width 0.10668)
			(type default)
		)
		(layer "B.Cu")
	)
	(gr_line
		(start 85.012784 -22.079966)
		(end 85.033612 -22.059138)
		(stroke
			(width 0.10668)
			(type default)
		)
		(layer "B.Cu")
	)
	(gr_line
		(start 86.388194 -24.269192)
		(end 86.581996 -24.462994)
		(stroke
			(width 0.10668)
			(type default)
		)
		(layer "B.Cu")
	)
	(gr_line
		(start 86.388194 -23.640796)
		(end 86.581996 -23.446994)
		(stroke
			(width 0.10668)
			(type default)
		)
		(layer "B.Cu")
	)
	(gr_line
		(start 86.52764 -18.375122)
		(end 86.568534 -18.38325)
		(stroke
			(width 0.10668)
			(type default)
		)
		(layer "B.Cu")
	)
	(gr_line
		(start 86.568534 -18.38325)
		(end 86.603078 -18.406872)
		(stroke
			(width 0.10668)
			(type default)
		)
		(layer "B.Cu")
	)
	(gr_line
		(start 86.93531 -22.017736)
		(end 87.129112 -22.211538)
		(stroke
			(width 0.10668)
			(type default)
		)
		(layer "B.Cu")
	)
	(gr_line
		(start 86.93531 -21.38934)
		(end 87.129112 -21.195538)
		(stroke
			(width 0.10668)
			(type default)
		)
		(layer "B.Cu")
	)
	(gr_line
		(start 88.78697 -19.889216)
		(end 88.821006 -19.91233)
		(stroke
			(width 0.10668)
			(type default)
		)
		(layer "B.Cu")
	)
	(gr_line
		(start 88.789256 -21.079714)
		(end 88.85301 -20.766024)
		(stroke
			(width 0.10668)
			(type default)
		)
		(layer "B.Cu")
	)
	(gr_line
		(start 88.789256 -21.079714)
		(end 89.14257 -21.613368)
		(stroke
			(width 0.10668)
			(type default)
		)
		(layer "B.Cu")
	)
	(gr_line
		(start 88.821006 -19.91233)
		(end 88.843866 -19.94662)
		(stroke
			(width 0.10668)
			(type default)
		)
		(layer "B.Cu")
	)
	(gr_line
		(start 89.14257 -21.613368)
		(end 89.456006 -21.677122)
		(stroke
			(width 0.10668)
			(type default)
		)
		(layer "B.Cu")
	)
	(gr_line
		(start 89.248742 -20.558506)
		(end 89.802208 -21.394928)
		(stroke
			(width 0.10668)
			(type default)
		)
		(layer "B.Cu")
	)
	(gr_line
		(start 89.748106 -22.52853)
		(end 89.81186 -22.21484)
		(stroke
			(width 0.10668)
			(type default)
		)
		(layer "B.Cu")
	)
	(gr_line
		(start 89.748106 -22.52853)
		(end 90.10142 -23.062184)
		(stroke
			(width 0.10668)
			(type default)
		)
		(layer "B.Cu")
	)
	(gr_line
		(start 90.10142 -23.062184)
		(end 90.41511 -23.126192)
		(stroke
			(width 0.10668)
			(type default)
		)
		(layer "B.Cu")
	)
	(gr_line
		(start 90.207846 -22.008084)
		(end 90.76182 -22.845014)
		(stroke
			(width 0.10668)
			(type default)
		)
		(layer "B.Cu")
	)
	(gr_line
		(start 90.706956 -23.977346)
		(end 90.77071 -23.663656)
		(stroke
			(width 0.10668)
			(type default)
		)
		(layer "B.Cu")
	)
	(gr_line
		(start 90.706956 -23.977346)
		(end 91.06027 -24.511)
		(stroke
			(width 0.10668)
			(type default)
		)
		(layer "B.Cu")
	)
	(gr_line
		(start 91.06027 -24.511)
		(end 91.37396 -24.575008)
		(stroke
			(width 0.10668)
			(type default)
		)
		(layer "B.Cu")
	)
	(gr_line
		(start 91.165426 -23.454614)
		(end 91.721686 -24.294846)
		(stroke
			(width 0.10668)
			(type default)
		)
		(layer "B.Cu")
	)
	(gr_line
		(start 91.665806 -25.426162)
		(end 91.72956 -25.112218)
		(stroke
			(width 0.10668)
			(type default)
		)
		(layer "B.Cu")
	)
	(gr_line
		(start 91.665806 -25.426162)
		(end 92.01912 -25.959816)
		(stroke
			(width 0.10668)
			(type default)
		)
		(layer "B.Cu")
	)
	(gr_line
		(start 92.01912 -25.959816)
		(end 92.33281 -26.02357)
		(stroke
			(width 0.10668)
			(type default)
		)
		(layer "B.Cu")
	)
	(gr_line
		(start 92.123768 -24.90216)
		(end 92.680028 -25.742646)
		(stroke
			(width 0.10668)
			(type default)
		)
		(layer "B.Cu")
	)
	(gr_line
		(start 93.39834 -27.629104)
		(end 93.422216 -27.665172)
		(stroke
			(width 0.10668)
			(type default)
		)
		(layer "B.Cu")
	)
	(gr_line
		(start 93.422216 -27.665172)
		(end 93.458792 -27.689556)
		(stroke
			(width 0.10668)
			(type default)
		)
		(layer "B.Cu")
	)
	(gr_line
		(start 94.738952 -47.863506)
		(end 94.762828 -47.899574)
		(stroke
			(width 0.10668)
			(type default)
		)
		(layer "B.Cu")
	)
	(gr_line
		(start 94.762828 -47.899574)
		(end 94.798896 -47.92345)
		(stroke
			(width 0.10668)
			(type default)
		)
		(layer "B.Cu")
	)
	(gr_line
		(start 96.43618 -49.007014)
		(end 96.468184 -49.028096)
		(stroke
			(width 0.10668)
			(type default)
		)
		(layer "B.Cu")
	)
	(gr_line
		(start 96.468184 -49.028096)
		(end 96.506538 -49.03597)
		(stroke
			(width 0.10668)
			(type default)
		)
		(layer "B.Cu")
	)
	(gr_line
		(start 97.870264 -49.315878)
		(end 98.047048 -49.582578)
		(stroke
			(width 0.10668)
			(type default)
		)
		(layer "B.Cu")
	)
	(gr_line
		(start 98.001328 -48.888904)
		(end 98.986594 -49.08931)
		(stroke
			(width 0.10668)
			(type default)
		)
		(layer "B.Cu")
	)
	(gr_line
		(start 98.047048 -49.582578)
		(end 98.674174 -49.710086)
		(stroke
			(width 0.10668)
			(type default)
		)
		(layer "B.Cu")
	)
	(gr_line
		(start 98.674174 -49.710086)
		(end 98.941128 -49.533556)
		(stroke
			(width 0.10668)
			(type default)
		)
		(layer "B.Cu")
	)
	(gr_line
		(start 99.57308 -49.66208)
		(end 99.74961 -49.929034)
		(stroke
			(width 0.10668)
			(type default)
		)
		(layer "B.Cu")
	)
	(gr_line
		(start 99.70516 -49.23536)
		(end 100.690934 -49.43602)
		(stroke
			(width 0.10668)
			(type default)
		)
		(layer "B.Cu")
	)
	(gr_line
		(start 99.74961 -49.929034)
		(end 100.376736 -50.056542)
		(stroke
			(width 0.10668)
			(type default)
		)
		(layer "B.Cu")
	)
	(gr_line
		(start 100.376736 -50.056542)
		(end 100.64369 -49.880012)
		(stroke
			(width 0.10668)
			(type default)
		)
		(layer "B.Cu")
	)
	(gr_line
		(start 101.406452 -49.581562)
		(end 101.541326 -49.608994)
		(stroke
			(width 0.10668)
			(type default)
		)
		(layer "B.Cu")
	)
	(gr_line
		(start 101.430074 -51.74996)
		(end 101.750876 -51.429158)
		(stroke
			(width 0.10668)
			(type default)
		)
		(layer "B.Cu")
	)
	(gr_line
		(start 101.430074 -35.049968)
		(end 101.750876 -34.729166)
		(stroke
			(width 0.10668)
			(type default)
		)
		(layer "B.Cu")
	)
	(gr_line
		(start 101.541326 -49.608994)
		(end 101.617526 -49.724056)
		(stroke
			(width 0.10668)
			(type default)
		)
		(layer "B.Cu")
	)
	(gr_line
		(start 101.542088 -32.509714)
		(end 101.578156 -32.53359)
		(stroke
			(width 0.10668)
			(type default)
		)
		(layer "B.Cu")
	)
	(gr_line
		(start 101.578156 -32.53359)
		(end 101.60254 -32.570166)
		(stroke
			(width 0.10668)
			(type default)
		)
		(layer "B.Cu")
	)
	(gr_line
		(start 102.071932 -33.279334)
		(end 102.093268 -33.311592)
		(stroke
			(width 0.10668)
			(type default)
		)
		(layer "B.Cu")
	)
	(gr_line
		(start 102.093268 -33.311592)
		(end 102.101142 -33.349946)
		(stroke
			(width 0.10668)
			(type default)
		)
		(layer "B.Cu")
	)
	(gr_line
		(start 102.238048 -50.66157)
		(end 102.286054 -50.734214)
		(stroke
			(width 0.10668)
			(type default)
		)
		(layer "B.Cu")
	)
	(gr_line
		(start 102.379272 -51.429158)
		(end 102.700074 -51.74996)
		(stroke
			(width 0.10668)
			(type default)
		)
		(layer "B.Cu")
	)
	(gr_line
		(start 102.379272 -34.729166)
		(end 102.700074 -35.049968)
		(stroke
			(width 0.10668)
			(type default)
		)
		(layer "B.Cu")
	)
	(gr_line
		(start 0 -22.200108)
		(end 0 -0.999998)
		(stroke
			(width 1.524)
			(type default)
		)
		(layer "In1.Cu")
	)
	(gr_arc
		(start 0 -22.200108)
		(mid 0.292895 -22.907209)
		(end 0.999998 -23.200106)
		(stroke
			(width 1.524)
			(type default)
		)
		(layer "In1.Cu")
	)
	(gr_arc
		(start 0.999998 0)
		(mid 0.292893 -0.292893)
		(end 0 -0.999998)
		(stroke
			(width 1.524)
			(type default)
		)
		(layer "In1.Cu")
	)
	(gr_line
		(start 0.999998 0)
		(end 94.499938 0)
		(stroke
			(width 1.524)
			(type default)
		)
		(layer "In1.Cu")
	)
	(gr_line
		(start 23.694898 -14.538452)
		(end 24.964898 -14.538452)
		(stroke
			(width 0.2)
			(type default)
		)
		(layer "In1.Cu")
	)
	(gr_arc
		(start 23.694898 -13.161772)
		(mid 23.006558 -13.850112)
		(end 23.694898 -14.538452)
		(stroke
			(width 0.2)
			(type default)
		)
		(layer "In1.Cu")
	)
	(gr_line
		(start 23.694898 -3.238246)
		(end 24.964898 -3.238246)
		(stroke
			(width 0.2)
			(type default)
		)
		(layer "In1.Cu")
	)
	(gr_arc
		(start 23.694898 -1.861566)
		(mid 23.006558 -2.549906)
		(end 23.694898 -3.238246)
		(stroke
			(width 0.2)
			(type default)
		)
		(layer "In1.Cu")
	)
	(gr_arc
		(start 24.964898 -14.538452)
		(mid 25.653238 -13.850112)
		(end 24.964898 -13.161772)
		(stroke
			(width 0.2)
			(type default)
		)
		(layer "In1.Cu")
	)
	(gr_line
		(start 24.964898 -13.161772)
		(end 23.694898 -13.161772)
		(stroke
			(width 0.2)
			(type default)
		)
		(layer "In1.Cu")
	)
	(gr_arc
		(start 24.964898 -3.238246)
		(mid 25.653238 -2.549906)
		(end 24.964898 -1.861566)
		(stroke
			(width 0.2)
			(type default)
		)
		(layer "In1.Cu")
	)
	(gr_line
		(start 24.964898 -1.861566)
		(end 23.694898 -1.861566)
		(stroke
			(width 0.2)
			(type default)
		)
		(layer "In1.Cu")
	)
	(gr_line
		(start 27.504898 -14.538452)
		(end 28.774898 -14.538452)
		(stroke
			(width 0.2)
			(type default)
		)
		(layer "In1.Cu")
	)
	(gr_arc
		(start 27.504898 -13.161772)
		(mid 26.816558 -13.850112)
		(end 27.504898 -14.538452)
		(stroke
			(width 0.2)
			(type default)
		)
		(layer "In1.Cu")
	)
	(gr_line
		(start 27.504898 -3.238246)
		(end 28.774898 -3.238246)
		(stroke
			(width 0.2)
			(type default)
		)
		(layer "In1.Cu")
	)
	(gr_arc
		(start 27.504898 -1.861566)
		(mid 26.816558 -2.549906)
		(end 27.504898 -3.238246)
		(stroke
			(width 0.2)
			(type default)
		)
		(layer "In1.Cu")
	)
	(gr_arc
		(start 28.774898 -14.538452)
		(mid 29.463238 -13.850112)
		(end 28.774898 -13.161772)
		(stroke
			(width 0.2)
			(type default)
		)
		(layer "In1.Cu")
	)
	(gr_line
		(start 28.774898 -13.161772)
		(end 27.504898 -13.161772)
		(stroke
			(width 0.2)
			(type default)
		)
		(layer "In1.Cu")
	)
	(gr_arc
		(start 28.774898 -3.238246)
		(mid 29.463238 -2.549906)
		(end 28.774898 -1.861566)
		(stroke
			(width 0.2)
			(type default)
		)
		(layer "In1.Cu")
	)
	(gr_line
		(start 28.774898 -1.861566)
		(end 27.504898 -1.861566)
		(stroke
			(width 0.2)
			(type default)
		)
		(layer "In1.Cu")
	)
	(gr_line
		(start 48.999902 -23.200106)
		(end 0.999998 -23.200106)
		(stroke
			(width 1.524)
			(type default)
		)
		(layer "In1.Cu")
	)
	(gr_line
		(start 49.500028 -24.200104)
		(end 49.500028 -23.699978)
		(stroke
			(width 1.524)
			(type default)
		)
		(layer "In1.Cu")
	)
	(gr_arc
		(start 49.500028 -24.200104)
		(mid 49.646439 -24.553564)
		(end 49.9999 -24.699976)
		(stroke
			(width 1.524)
			(type default)
		)
		(layer "In1.Cu")
	)
	(gr_arc
		(start 49.500028 -23.699978)
		(mid 49.353439 -23.34659)
		(end 48.999902 -23.200106)
		(stroke
			(width 1.524)
			(type default)
		)
		(layer "In1.Cu")
	)
	(gr_line
		(start 68.49999 -24.699976)
		(end 49.9999 -24.699976)
		(stroke
			(width 1.524)
			(type default)
		)
		(layer "In1.Cu")
	)
	(gr_line
		(start 69.499988 -64.200024)
		(end 69.499988 -25.699974)
		(stroke
			(width 1.524)
			(type default)
		)
		(layer "In1.Cu")
	)
	(gr_arc
		(start 69.499988 -64.200024)
		(mid 69.792888 -64.907119)
		(end 70.499986 -65.200022)
		(stroke
			(width 1.524)
			(type default)
		)
		(layer "In1.Cu")
	)
	(gr_arc
		(start 69.499988 -25.699974)
		(mid 69.207095 -24.992869)
		(end 68.49999 -24.699976)
		(stroke
			(width 1.524)
			(type default)
		)
		(layer "In1.Cu")
	)
	(gr_arc
		(start 82.576416 -22.182582)
		(mid 83.086829 -22.693376)
		(end 83.597496 -22.182836)
		(stroke
			(width 0.2)
			(type default)
		)
		(layer "In1.Cu")
	)
	(gr_line
		(start 82.576416 -21.166836)
		(end 82.576416 -22.182582)
		(stroke
			(width 0.2)
			(type default)
		)
		(layer "In1.Cu")
	)
	(gr_line
		(start 82.652616 -26.21915)
		(end 83.668616 -26.21915)
		(stroke
			(width 0.2)
			(type default)
		)
		(layer "In1.Cu")
	)
	(gr_arc
		(start 82.65287 -25.19807)
		(mid 82.142076 -25.708483)
		(end 82.652616 -26.21915)
		(stroke
			(width 0.2)
			(type default)
		)
		(layer "In1.Cu")
	)
	(gr_line
		(start 83.597496 -22.182836)
		(end 83.597496 -21.166836)
		(stroke
			(width 0.2)
			(type default)
		)
		(layer "In1.Cu")
	)
	(gr_arc
		(start 83.597496 -21.166836)
		(mid 83.086956 -20.656296)
		(end 82.576416 -21.166836)
		(stroke
			(width 0.2)
			(type default)
		)
		(layer "In1.Cu")
	)
	(gr_arc
		(start 83.668616 -26.21915)
		(mid 84.179156 -25.70861)
		(end 83.668616 -25.19807)
		(stroke
			(width 0.2)
			(type default)
		)
		(layer "In1.Cu")
	)
	(gr_line
		(start 83.668616 -25.19807)
		(end 82.65287 -25.19807)
		(stroke
			(width 0.2)
			(type default)
		)
		(layer "In1.Cu")
	)
	(gr_arc
		(start 86.071456 -24.46274)
		(mid 86.581869 -24.973534)
		(end 87.092536 -24.462994)
		(stroke
			(width 0.2)
			(type default)
		)
		(layer "In1.Cu")
	)
	(gr_line
		(start 86.071456 -23.446994)
		(end 86.071456 -24.46274)
		(stroke
			(width 0.2)
			(type default)
		)
		(layer "In1.Cu")
	)
	(gr_arc
		(start 86.618572 -22.211284)
		(mid 87.128985 -22.722078)
		(end 87.639652 -22.211538)
		(stroke
			(width 0.2)
			(type default)
		)
		(layer "In1.Cu")
	)
	(gr_line
		(start 86.618572 -21.195538)
		(end 86.618572 -22.211284)
		(stroke
			(width 0.2)
			(type default)
		)
		(layer "In1.Cu")
	)
	(gr_line
		(start 87.092536 -24.462994)
		(end 87.092536 -23.446994)
		(stroke
			(width 0.2)
			(type default)
		)
		(layer "In1.Cu")
	)
	(gr_arc
		(start 87.092536 -23.446994)
		(mid 86.581996 -22.936454)
		(end 86.071456 -23.446994)
		(stroke
			(width 0.2)
			(type default)
		)
		(layer "In1.Cu")
	)
	(gr_line
		(start 87.639652 -22.211538)
		(end 87.639652 -21.195538)
		(stroke
			(width 0.2)
			(type default)
		)
		(layer "In1.Cu")
	)
	(gr_arc
		(start 87.639652 -21.195538)
		(mid 87.129112 -20.684998)
		(end 86.618572 -21.195538)
		(stroke
			(width 0.2)
			(type default)
		)
		(layer "In1.Cu")
	)
	(gr_arc
		(start 95.499936 -23.999952)
		(mid 95.792829 -24.707057)
		(end 96.499934 -24.99995)
		(stroke
			(width 1.524)
			(type default)
		)
		(layer "In1.Cu")
	)
	(gr_arc
		(start 95.499936 -0.999998)
		(mid 95.207045 -0.29288)
		(end 94.499938 0)
		(stroke
			(width 1.524)
			(type default)
		)
		(layer "In1.Cu")
	)
	(gr_line
		(start 95.499936 -0.999998)
		(end 95.499936 -23.999952)
		(stroke
			(width 1.524)
			(type default)
		)
		(layer "In1.Cu")
	)
	(gr_line
		(start 96.499934 -24.99995)
		(end 117.350032 -24.99995)
		(stroke
			(width 1.524)
			(type default)
		)
		(layer "In1.Cu")
	)
	(gr_line
		(start 97.620074 -52.4383)
		(end 98.890074 -52.4383)
		(stroke
			(width 0.2)
			(type default)
		)
		(layer "In1.Cu")
	)
	(gr_arc
		(start 97.620074 -51.06162)
		(mid 96.931734 -51.74996)
		(end 97.620074 -52.4383)
		(stroke
			(width 0.2)
			(type default)
		)
		(layer "In1.Cu")
	)
	(gr_line
		(start 97.620074 -35.738308)
		(end 98.890074 -35.738308)
		(stroke
			(width 0.2)
			(type default)
		)
		(layer "In1.Cu")
	)
	(gr_arc
		(start 97.620074 -34.361628)
		(mid 96.931734 -35.049968)
		(end 97.620074 -35.738308)
		(stroke
			(width 0.2)
			(type default)
		)
		(layer "In1.Cu")
	)
	(gr_arc
		(start 98.890074 -52.4383)
		(mid 99.578414 -51.74996)
		(end 98.890074 -51.06162)
		(stroke
			(width 0.2)
			(type default)
		)
		(layer "In1.Cu")
	)
	(gr_line
		(start 98.890074 -51.06162)
		(end 97.620074 -51.06162)
		(stroke
			(width 0.2)
			(type default)
		)
		(layer "In1.Cu")
	)
	(gr_arc
		(start 98.890074 -35.738308)
		(mid 99.578414 -35.049968)
		(end 98.890074 -34.361628)
		(stroke
			(width 0.2)
			(type default)
		)
		(layer "In1.Cu")
	)
	(gr_line
		(start 98.890074 -34.361628)
		(end 97.620074 -34.361628)
		(stroke
			(width 0.2)
			(type default)
		)
		(layer "In1.Cu")
	)
	(gr_line
		(start 101.430074 -52.4383)
		(end 102.700074 -52.4383)
		(stroke
			(width 0.2)
			(type default)
		)
		(layer "In1.Cu")
	)
	(gr_arc
		(start 101.430074 -51.06162)
		(mid 100.741734 -51.74996)
		(end 101.430074 -52.4383)
		(stroke
			(width 0.2)
			(type default)
		)
		(layer "In1.Cu")
	)
	(gr_line
		(start 101.430074 -35.738308)
		(end 102.700074 -35.738308)
		(stroke
			(width 0.2)
			(type default)
		)
		(layer "In1.Cu")
	)
	(gr_arc
		(start 101.430074 -34.361628)
		(mid 100.741734 -35.049968)
		(end 101.430074 -35.738308)
		(stroke
			(width 0.2)
			(type default)
		)
		(layer "In1.Cu")
	)
	(gr_arc
		(start 102.700074 -52.4383)
		(mid 103.388414 -51.74996)
		(end 102.700074 -51.06162)
		(stroke
			(width 0.2)
			(type default)
		)
		(layer "In1.Cu")
	)
	(gr_line
		(start 102.700074 -51.06162)
		(end 101.430074 -51.06162)
		(stroke
			(width 0.2)
			(type default)
		)
		(layer "In1.Cu")
	)
	(gr_arc
		(start 102.700074 -35.738308)
		(mid 103.388414 -35.049968)
		(end 102.700074 -34.361628)
		(stroke
			(width 0.2)
			(type default)
		)
		(layer "In1.Cu")
	)
	(gr_line
		(start 102.700074 -34.361628)
		(end 101.430074 -34.361628)
		(stroke
			(width 0.2)
			(type default)
		)
		(layer "In1.Cu")
	)
	(gr_arc
		(start 117.350032 -24.99995)
		(mid 118.057137 -24.707057)
		(end 118.35003 -23.999952)
		(stroke
			(width 1.524)
			(type default)
		)
		(layer "In1.Cu")
	)
	(gr_line
		(start 118.35003 -23.999952)
		(end 118.35003 -20.049998)
		(stroke
			(width 1.524)
			(type default)
		)
		(layer "In1.Cu")
	)
	(gr_arc
		(start 119.350028 -19.05)
		(mid 118.642904 -19.342883)
		(end 118.35003 -20.049998)
		(stroke
			(width 1.524)
			(type default)
		)
		(layer "In1.Cu")
	)
	(gr_line
		(start 119.350028 -19.05)
		(end 134.500112 -19.05)
		(stroke
			(width 1.524)
			(type default)
		)
		(layer "In1.Cu")
	)
	(gr_arc
		(start 134.500112 -19.05)
		(mid 135.207217 -18.757107)
		(end 135.50011 -18.050002)
		(stroke
			(width 1.524)
			(type default)
		)
		(layer "In1.Cu")
	)
	(gr_line
		(start 135.50011 -18.050002)
		(end 135.50011 -0.999998)
		(stroke
			(width 1.524)
			(type default)
		)
		(layer "In1.Cu")
	)
	(gr_arc
		(start 136.500108 0)
		(mid 135.792997 -0.29289)
		(end 135.50011 -0.999998)
		(stroke
			(width 1.524)
			(type default)
		)
		(layer "In1.Cu")
	)
	(gr_line
		(start 136.500108 0)
		(end 142.500096 0)
		(stroke
			(width 1.524)
			(type default)
		)
		(layer "In1.Cu")
	)
	(gr_line
		(start 142.500096 -65.200022)
		(end 70.499986 -65.200022)
		(stroke
			(width 1.524)
			(type default)
		)
		(layer "In1.Cu")
	)
	(gr_arc
		(start 142.500096 -65.200022)
		(mid 143.207212 -64.907132)
		(end 143.500094 -64.200024)
		(stroke
			(width 1.524)
			(type default)
		)
		(layer "In1.Cu")
	)
	(gr_arc
		(start 143.500094 -0.999998)
		(mid 143.2072 -0.292895)
		(end 142.500096 0)
		(stroke
			(width 1.524)
			(type default)
		)
		(layer "In1.Cu")
	)
	(gr_line
		(start 143.500094 -0.999998)
		(end 143.500094 -64.200024)
		(stroke
			(width 1.524)
			(type default)
		)
		(layer "In1.Cu")
	)
	(gr_line
		(start 19.00682 -11.23823)
		(end 19.011646 -11.214354)
		(stroke
			(width 0.07112)
			(type default)
		)
		(layer "In2.Cu")
	)
	(gr_line
		(start 19.00682 -11.23823)
		(end 19.0119 -11.262614)
		(stroke
			(width 0.07112)
			(type default)
		)
		(layer "In2.Cu")
	)
	(gr_line
		(start 19.165062 -10.45591)
		(end 19.169888 -10.432796)
		(stroke
			(width 0.07112)
			(type default)
		)
		(layer "In2.Cu")
	)
	(gr_line
		(start 19.169888 -10.432796)
		(end 19.182842 -10.412984)
		(stroke
			(width 0.07112)
			(type default)
		)
		(layer "In2.Cu")
	)
	(gr_line
		(start 19.181826 -12.096242)
		(end 19.186398 -12.11834)
		(stroke
			(width 0.07112)
			(type default)
		)
		(layer "In2.Cu")
	)
	(gr_line
		(start 19.186398 -12.11834)
		(end 19.19859 -12.136882)
		(stroke
			(width 0.07112)
			(type default)
		)
		(layer "In2.Cu")
	)
	(gr_line
		(start 20.30476 -13.80871)
		(end 20.319746 -13.831316)
		(stroke
			(width 0.07112)
			(type default)
		)
		(layer "In2.Cu")
	)
	(gr_line
		(start 20.319746 -13.831316)
		(end 20.342352 -13.846302)
		(stroke
			(width 0.07112)
			(type default)
		)
		(layer "In2.Cu")
	)
	(gr_line
		(start 23.361904 -15.845028)
		(end 23.38197 -15.858236)
		(stroke
			(width 0.07112)
			(type default)
		)
		(layer "In2.Cu")
	)
	(gr_line
		(start 23.38197 -15.858236)
		(end 23.405338 -15.862808)
		(stroke
			(width 0.07112)
			(type default)
		)
		(layer "In2.Cu")
	)
	(gr_line
		(start 23.694898 -13.850112)
		(end 24.101806 -14.25702)
		(stroke
			(width 0.07112)
			(type default)
		)
		(layer "In2.Cu")
	)
	(gr_line
		(start 23.694898 -2.549906)
		(end 24.101806 -2.956814)
		(stroke
			(width 0.07112)
			(type default)
		)
		(layer "In2.Cu")
	)
	(gr_line
		(start 24.20747 -14.717014)
		(end 24.254714 -14.774926)
		(stroke
			(width 0.07112)
			(type default)
		)
		(layer "In2.Cu")
	)
	(gr_line
		(start 24.436578 -14.997684)
		(end 24.484584 -15.056358)
		(stroke
			(width 0.07112)
			(type default)
		)
		(layer "In2.Cu")
	)
	(gr_line
		(start 24.484584 -15.056358)
		(end 24.55799 -15.07109)
		(stroke
			(width 0.07112)
			(type default)
		)
		(layer "In2.Cu")
	)
	(gr_line
		(start 24.55799 -14.25702)
		(end 24.964898 -13.850112)
		(stroke
			(width 0.07112)
			(type default)
		)
		(layer "In2.Cu")
	)
	(gr_line
		(start 24.55799 -2.956814)
		(end 24.964898 -2.549906)
		(stroke
			(width 0.07112)
			(type default)
		)
		(layer "In2.Cu")
	)
	(gr_line
		(start 28.007564 -15.771622)
		(end 28.031694 -15.776702)
		(stroke
			(width 0.07112)
			(type default)
		)
		(layer "In2.Cu")
	)
	(gr_line
		(start 28.031694 -15.776702)
		(end 28.055824 -15.771622)
		(stroke
			(width 0.07112)
			(type default)
		)
		(layer "In2.Cu")
	)
	(gr_line
		(start 28.177744 -16.833342)
		(end 28.201874 -16.838422)
		(stroke
			(width 0.07112)
			(type default)
		)
		(layer "In2.Cu")
	)
	(gr_line
		(start 28.201874 -16.838422)
		(end 28.226004 -16.833342)
		(stroke
			(width 0.07112)
			(type default)
		)
		(layer "In2.Cu")
	)
	(gr_line
		(start 31.438596 -14.756892)
		(end 31.462726 -14.751812)
		(stroke
			(width 0.07112)
			(type default)
		)
		(layer "In2.Cu")
	)
	(gr_line
		(start 31.462726 -14.751812)
		(end 31.486856 -14.756892)
		(stroke
			(width 0.07112)
			(type default)
		)
		(layer "In2.Cu")
	)
	(gr_line
		(start 31.682944 -15.803626)
		(end 31.707074 -15.798546)
		(stroke
			(width 0.07112)
			(type default)
		)
		(layer "In2.Cu")
	)
	(gr_line
		(start 31.707074 -15.798546)
		(end 31.731204 -15.803626)
		(stroke
			(width 0.07112)
			(type default)
		)
		(layer "In2.Cu")
	)
	(gr_line
		(start 33.199324 -15.431516)
		(end 33.223454 -15.436596)
		(stroke
			(width 0.07112)
			(type default)
		)
		(layer "In2.Cu")
	)
	(gr_line
		(start 33.223454 -15.436596)
		(end 33.247584 -15.431516)
		(stroke
			(width 0.07112)
			(type default)
		)
		(layer "In2.Cu")
	)
	(gr_line
		(start 33.40862 -16.471392)
		(end 33.43275 -16.476472)
		(stroke
			(width 0.07112)
			(type default)
		)
		(layer "In2.Cu")
	)
	(gr_line
		(start 33.43275 -16.476472)
		(end 33.45688 -16.471392)
		(stroke
			(width 0.07112)
			(type default)
		)
		(layer "In2.Cu")
	)
	(gr_line
		(start 35.71875 -15.684754)
		(end 35.74288 -15.679674)
		(stroke
			(width 0.07112)
			(type default)
		)
		(layer "In2.Cu")
	)
	(gr_line
		(start 35.74288 -15.679674)
		(end 35.76701 -15.684754)
		(stroke
			(width 0.07112)
			(type default)
		)
		(layer "In2.Cu")
	)
	(gr_line
		(start 35.771328 -14.592046)
		(end 35.795458 -14.586966)
		(stroke
			(width 0.07112)
			(type default)
		)
		(layer "In2.Cu")
	)
	(gr_line
		(start 35.795458 -14.586966)
		(end 35.819588 -14.592046)
		(stroke
			(width 0.07112)
			(type default)
		)
		(layer "In2.Cu")
	)
	(gr_line
		(start 54.302406 -18.67789)
		(end 54.326536 -18.68297)
		(stroke
			(width 0.07112)
			(type default)
		)
		(layer "In2.Cu")
	)
	(gr_line
		(start 54.326536 -18.68297)
		(end 54.350666 -18.67789)
		(stroke
			(width 0.07112)
			(type default)
		)
		(layer "In2.Cu")
	)
	(gr_line
		(start 55.593234 -19.718528)
		(end 55.614062 -19.722592)
		(stroke
			(width 0.07112)
			(type default)
		)
		(layer "In2.Cu")
	)
	(gr_line
		(start 55.614062 -19.722592)
		(end 55.631842 -19.73453)
		(stroke
			(width 0.07112)
			(type default)
		)
		(layer "In2.Cu")
	)
	(gr_line
		(start 56.110632 -20.434808)
		(end 56.128412 -20.446746)
		(stroke
			(width 0.07112)
			(type default)
		)
		(layer "In2.Cu")
	)
	(gr_line
		(start 56.128412 -20.446746)
		(end 56.14924 -20.45081)
		(stroke
			(width 0.07112)
			(type default)
		)
		(layer "In2.Cu")
	)
	(gr_line
		(start 57.567068 -20.739354)
		(end 58.25744 -20.879816)
		(stroke
			(width 0.07112)
			(type default)
		)
		(layer "In2.Cu")
	)
	(gr_line
		(start 57.595262 -20.416012)
		(end 57.802272 -20.279106)
		(stroke
			(width 0.07112)
			(type default)
		)
		(layer "In2.Cu")
	)
	(gr_line
		(start 57.802272 -20.279106)
		(end 58.220356 -20.364196)
		(stroke
			(width 0.07112)
			(type default)
		)
		(layer "In2.Cu")
	)
	(gr_line
		(start 58.220356 -20.364196)
		(end 58.357516 -20.571206)
		(stroke
			(width 0.07112)
			(type default)
		)
		(layer "In2.Cu")
	)
	(gr_line
		(start 58.751978 -20.9804)
		(end 59.440826 -21.120354)
		(stroke
			(width 0.07112)
			(type default)
		)
		(layer "In2.Cu")
	)
	(gr_line
		(start 58.780172 -20.657058)
		(end 58.986928 -20.520152)
		(stroke
			(width 0.07112)
			(type default)
		)
		(layer "In2.Cu")
	)
	(gr_line
		(start 58.986928 -20.520152)
		(end 59.405012 -20.605242)
		(stroke
			(width 0.07112)
			(type default)
		)
		(layer "In2.Cu")
	)
	(gr_line
		(start 59.405012 -20.605242)
		(end 59.542172 -20.811998)
		(stroke
			(width 0.07112)
			(type default)
		)
		(layer "In2.Cu")
	)
	(gr_line
		(start 59.937142 -21.221446)
		(end 60.62472 -21.361146)
		(stroke
			(width 0.07112)
			(type default)
		)
		(layer "In2.Cu")
	)
	(gr_line
		(start 59.964828 -20.898104)
		(end 60.171584 -20.761198)
		(stroke
			(width 0.07112)
			(type default)
		)
		(layer "In2.Cu")
	)
	(gr_line
		(start 60.171584 -20.761198)
		(end 60.589668 -20.846288)
		(stroke
			(width 0.07112)
			(type default)
		)
		(layer "In2.Cu")
	)
	(gr_line
		(start 60.589668 -20.846288)
		(end 60.726828 -21.053044)
		(stroke
			(width 0.07112)
			(type default)
		)
		(layer "In2.Cu")
	)
	(gr_line
		(start 61.122814 -21.462746)
		(end 61.810646 -21.6027)
		(stroke
			(width 0.07112)
			(type default)
		)
		(layer "In2.Cu")
	)
	(gr_line
		(start 61.149484 -21.13915)
		(end 61.356494 -21.00199)
		(stroke
			(width 0.07112)
			(type default)
		)
		(layer "In2.Cu")
	)
	(gr_line
		(start 61.356494 -21.00199)
		(end 61.774578 -21.08708)
		(stroke
			(width 0.07112)
			(type default)
		)
		(layer "In2.Cu")
	)
	(gr_line
		(start 61.774578 -21.08708)
		(end 61.911484 -21.29409)
		(stroke
			(width 0.07112)
			(type default)
		)
		(layer "In2.Cu")
	)
	(gr_line
		(start 64.34455 -16.31823)
		(end 64.36995 -16.31315)
		(stroke
			(width 0.07112)
			(type default)
		)
		(layer "In2.Cu")
	)
	(gr_line
		(start 64.36995 -16.31315)
		(end 64.39535 -16.31823)
		(stroke
			(width 0.07112)
			(type default)
		)
		(layer "In2.Cu")
	)
	(gr_line
		(start 65.730374 -22.40026)
		(end 66.424048 -22.541484)
		(stroke
			(width 0.07112)
			(type default)
		)
		(layer "In2.Cu")
	)
	(gr_line
		(start 65.759838 -22.077172)
		(end 65.966848 -21.940012)
		(stroke
			(width 0.07112)
			(type default)
		)
		(layer "In2.Cu")
	)
	(gr_line
		(start 65.966848 -21.940012)
		(end 66.384932 -22.025102)
		(stroke
			(width 0.07112)
			(type default)
		)
		(layer "In2.Cu")
	)
	(gr_line
		(start 66.384932 -22.025102)
		(end 66.522346 -22.232112)
		(stroke
			(width 0.07112)
			(type default)
		)
		(layer "In2.Cu")
	)
	(gr_line
		(start 66.915792 -22.641306)
		(end 67.607434 -22.782022)
		(stroke
			(width 0.07112)
			(type default)
		)
		(layer "In2.Cu")
	)
	(gr_line
		(start 66.944494 -22.318218)
		(end 67.151504 -22.181058)
		(stroke
			(width 0.07112)
			(type default)
		)
		(layer "In2.Cu")
	)
	(gr_line
		(start 67.151504 -22.181058)
		(end 67.569588 -22.266148)
		(stroke
			(width 0.07112)
			(type default)
		)
		(layer "In2.Cu")
	)
	(gr_line
		(start 67.569588 -22.266148)
		(end 67.707002 -22.473158)
		(stroke
			(width 0.07112)
			(type default)
		)
		(layer "In2.Cu")
	)
	(gr_line
		(start 68.100448 -22.882352)
		(end 68.79209 -23.023068)
		(stroke
			(width 0.07112)
			(type default)
		)
		(layer "In2.Cu")
	)
	(gr_line
		(start 68.12915 -22.559264)
		(end 68.33616 -22.422104)
		(stroke
			(width 0.07112)
			(type default)
		)
		(layer "In2.Cu")
	)
	(gr_line
		(start 68.33616 -22.422104)
		(end 68.754244 -22.507194)
		(stroke
			(width 0.07112)
			(type default)
		)
		(layer "In2.Cu")
	)
	(gr_line
		(start 68.754244 -22.507194)
		(end 68.891658 -22.714204)
		(stroke
			(width 0.07112)
			(type default)
		)
		(layer "In2.Cu")
	)
	(gr_line
		(start 69.285104 -23.123398)
		(end 69.976746 -23.264114)
		(stroke
			(width 0.07112)
			(type default)
		)
		(layer "In2.Cu")
	)
	(gr_line
		(start 69.313806 -22.800056)
		(end 69.52107 -22.66315)
		(stroke
			(width 0.07112)
			(type default)
		)
		(layer "In2.Cu")
	)
	(gr_line
		(start 69.52107 -22.66315)
		(end 69.939154 -22.74824)
		(stroke
			(width 0.07112)
			(type default)
		)
		(layer "In2.Cu")
	)
	(gr_line
		(start 69.939154 -22.74824)
		(end 70.07606 -22.95525)
		(stroke
			(width 0.07112)
			(type default)
		)
		(layer "In2.Cu")
	)
	(gr_line
		(start 73.67905 -24.017478)
		(end 74.371962 -24.158448)
		(stroke
			(width 0.07112)
			(type default)
		)
		(layer "In2.Cu")
	)
	(gr_line
		(start 73.70826 -23.694136)
		(end 73.91527 -23.55723)
		(stroke
			(width 0.07112)
			(type default)
		)
		(layer "In2.Cu")
	)
	(gr_line
		(start 73.91527 -23.55723)
		(end 74.333354 -23.64232)
		(stroke
			(width 0.07112)
			(type default)
		)
		(layer "In2.Cu")
	)
	(gr_line
		(start 74.333354 -23.64232)
		(end 74.470514 -23.84933)
		(stroke
			(width 0.07112)
			(type default)
		)
		(layer "In2.Cu")
	)
	(gr_line
		(start 74.86396 -24.258524)
		(end 75.556364 -24.399494)
		(stroke
			(width 0.07112)
			(type default)
		)
		(layer "In2.Cu")
	)
	(gr_line
		(start 74.892916 -23.935182)
		(end 75.099926 -23.798276)
		(stroke
			(width 0.07112)
			(type default)
		)
		(layer "In2.Cu")
	)
	(gr_line
		(start 75.099926 -23.798276)
		(end 75.51801 -23.883366)
		(stroke
			(width 0.07112)
			(type default)
		)
		(layer "In2.Cu")
	)
	(gr_line
		(start 75.51801 -23.883366)
		(end 75.65517 -24.090376)
		(stroke
			(width 0.07112)
			(type default)
		)
		(layer "In2.Cu")
	)
	(gr_line
		(start 76.0476 -24.499316)
		(end 76.740004 -24.640032)
		(stroke
			(width 0.07112)
			(type default)
		)
		(layer "In2.Cu")
	)
	(gr_line
		(start 76.077572 -24.176228)
		(end 76.284582 -24.039322)
		(stroke
			(width 0.07112)
			(type default)
		)
		(layer "In2.Cu")
	)
	(gr_line
		(start 76.284582 -24.039322)
		(end 76.702666 -24.124412)
		(stroke
			(width 0.07112)
			(type default)
		)
		(layer "In2.Cu")
	)
	(gr_line
		(start 76.702666 -24.124412)
		(end 76.839826 -24.331422)
		(stroke
			(width 0.07112)
			(type default)
		)
		(layer "In2.Cu")
	)
	(gr_line
		(start 77.233018 -24.740616)
		(end 77.925676 -24.881586)
		(stroke
			(width 0.07112)
			(type default)
		)
		(layer "In2.Cu")
	)
	(gr_line
		(start 77.262228 -24.417274)
		(end 77.469238 -24.280368)
		(stroke
			(width 0.07112)
			(type default)
		)
		(layer "In2.Cu")
	)
	(gr_line
		(start 77.469238 -24.280368)
		(end 77.887322 -24.365458)
		(stroke
			(width 0.07112)
			(type default)
		)
		(layer "In2.Cu")
	)
	(gr_line
		(start 77.562964 -19.323558)
		(end 77.587094 -19.328638)
		(stroke
			(width 0.07112)
			(type default)
		)
		(layer "In2.Cu")
	)
	(gr_line
		(start 77.587094 -19.328638)
		(end 77.611224 -19.323558)
		(stroke
			(width 0.07112)
			(type default)
		)
		(layer "In2.Cu")
	)
	(gr_line
		(start 77.887322 -24.365458)
		(end 78.024482 -24.572468)
		(stroke
			(width 0.07112)
			(type default)
		)
		(layer "In2.Cu")
	)
	(gr_line
		(start 78.420976 -24.655526)
		(end 78.444344 -24.660098)
		(stroke
			(width 0.07112)
			(type default)
		)
		(layer "In2.Cu")
	)
	(gr_line
		(start 78.44409 -24.660352)
		(end 78.444344 -24.660098)
		(stroke
			(width 0.07112)
			(type default)
		)
		(layer "In2.Cu")
	)
	(gr_line
		(start 78.44409 -24.660352)
		(end 78.462378 -24.67229)
		(stroke
			(width 0.07112)
			(type default)
		)
		(layer "In2.Cu")
	)
	(gr_line
		(start 81.316322 -26.945336)
		(end 81.335626 -26.958036)
		(stroke
			(width 0.07112)
			(type default)
		)
		(layer "In2.Cu")
	)
	(gr_line
		(start 81.335626 -26.958036)
		(end 81.358994 -26.962862)
		(stroke
			(width 0.07112)
			(type default)
		)
		(layer "In2.Cu")
	)
	(gr_line
		(start 81.854548 -18.134076)
		(end 81.878678 -18.128996)
		(stroke
			(width 0.07112)
			(type default)
		)
		(layer "In2.Cu")
	)
	(gr_line
		(start 81.878678 -18.128996)
		(end 81.902808 -18.134076)
		(stroke
			(width 0.07112)
			(type default)
		)
		(layer "In2.Cu")
	)
	(gr_line
		(start 81.979262 -27.088338)
		(end 82.003392 -27.093418)
		(stroke
			(width 0.07112)
			(type default)
		)
		(layer "In2.Cu")
	)
	(gr_line
		(start 82.003392 -27.093418)
		(end 82.027776 -27.088338)
		(stroke
			(width 0.07112)
			(type default)
		)
		(layer "In2.Cu")
	)
	(gr_line
		(start 82.527394 -26.9875)
		(end 82.550762 -26.982674)
		(stroke
			(width 0.07112)
			(type default)
		)
		(layer "In2.Cu")
	)
	(gr_line
		(start 82.550762 -26.982674)
		(end 82.570066 -26.969974)
		(stroke
			(width 0.07112)
			(type default)
		)
		(layer "In2.Cu")
	)
	(gr_line
		(start 82.652616 -25.70861)
		(end 82.858356 -25.70861)
		(stroke
			(width 0.07112)
			(type default)
		)
		(layer "In2.Cu")
	)
	(gr_line
		(start 82.858356 -25.70861)
		(end 82.932524 -25.782778)
		(stroke
			(width 0.07112)
			(type default)
		)
		(layer "In2.Cu")
	)
	(gr_line
		(start 82.942938 -18.674588)
		(end 83.080098 -18.881344)
		(stroke
			(width 0.07112)
			(type default)
		)
		(layer "In2.Cu")
	)
	(gr_line
		(start 83.037426 -26.660602)
		(end 83.060032 -26.645616)
		(stroke
			(width 0.07112)
			(type default)
		)
		(layer "In2.Cu")
	)
	(gr_line
		(start 83.043522 -18.365978)
		(end 83.7311 -18.505678)
		(stroke
			(width 0.07112)
			(type default)
		)
		(layer "In2.Cu")
	)
	(gr_line
		(start 83.060032 -26.645616)
		(end 83.075018 -26.62301)
		(stroke
			(width 0.07112)
			(type default)
		)
		(layer "In2.Cu")
	)
	(gr_line
		(start 83.080098 -18.881344)
		(end 83.498182 -18.966434)
		(stroke
			(width 0.07112)
			(type default)
		)
		(layer "In2.Cu")
	)
	(gr_line
		(start 83.259168 -26.344626)
		(end 83.27136 -26.326084)
		(stroke
			(width 0.07112)
			(type default)
		)
		(layer "In2.Cu")
	)
	(gr_line
		(start 83.27136 -26.326084)
		(end 83.275932 -26.303986)
		(stroke
			(width 0.07112)
			(type default)
		)
		(layer "In2.Cu")
	)
	(gr_line
		(start 83.388708 -25.782778)
		(end 83.462876 -25.70861)
		(stroke
			(width 0.07112)
			(type default)
		)
		(layer "In2.Cu")
	)
	(gr_line
		(start 83.462876 -25.70861)
		(end 83.668616 -25.70861)
		(stroke
			(width 0.07112)
			(type default)
		)
		(layer "In2.Cu")
	)
	(gr_line
		(start 83.498182 -18.966434)
		(end 83.704938 -18.829528)
		(stroke
			(width 0.07112)
			(type default)
		)
		(layer "In2.Cu")
	)
	(gr_line
		(start 84.128102 -18.915634)
		(end 84.265008 -19.12239)
		(stroke
			(width 0.07112)
			(type default)
		)
		(layer "In2.Cu")
	)
	(gr_line
		(start 84.229956 -18.607278)
		(end 84.916518 -18.746724)
		(stroke
			(width 0.07112)
			(type default)
		)
		(layer "In2.Cu")
	)
	(gr_line
		(start 84.265008 -19.12239)
		(end 84.683092 -19.20748)
		(stroke
			(width 0.07112)
			(type default)
		)
		(layer "In2.Cu")
	)
	(gr_line
		(start 84.683092 -19.20748)
		(end 84.890102 -19.070574)
		(stroke
			(width 0.07112)
			(type default)
		)
		(layer "In2.Cu")
	)
	(gr_line
		(start 85.312758 -19.156426)
		(end 85.449664 -19.363436)
		(stroke
			(width 0.07112)
			(type default)
		)
		(layer "In2.Cu")
	)
	(gr_line
		(start 85.414358 -18.84807)
		(end 86.103206 -18.988024)
		(stroke
			(width 0.07112)
			(type default)
		)
		(layer "In2.Cu")
	)
	(gr_line
		(start 85.449664 -19.363436)
		(end 85.867748 -19.448526)
		(stroke
			(width 0.07112)
			(type default)
		)
		(layer "In2.Cu")
	)
	(gr_line
		(start 85.867748 -19.448526)
		(end 86.074758 -19.311366)
		(stroke
			(width 0.07112)
			(type default)
		)
		(layer "In2.Cu")
	)
	(gr_line
		(start 86.581996 -24.462994)
		(end 86.861904 -24.183086)
		(stroke
			(width 0.07112)
			(type default)
		)
		(layer "In2.Cu")
	)
	(gr_line
		(start 86.581996 -23.446994)
		(end 86.861904 -23.726902)
		(stroke
			(width 0.07112)
			(type default)
		)
		(layer "In2.Cu")
	)
	(gr_line
		(start 86.597236 -19.088608)
		(end 86.620604 -19.09318)
		(stroke
			(width 0.07112)
			(type default)
		)
		(layer "In2.Cu")
	)
	(gr_line
		(start 86.620604 -19.09318)
		(end 86.64067 -19.106388)
		(stroke
			(width 0.07112)
			(type default)
		)
		(layer "In2.Cu")
	)
	(gr_line
		(start 87.698834 -24.144732)
		(end 87.745316 -24.113998)
		(stroke
			(width 0.07112)
			(type default)
		)
		(layer "In2.Cu")
	)
	(gr_line
		(start 87.720932 -19.821652)
		(end 87.743538 -19.836638)
		(stroke
			(width 0.07112)
			(type default)
		)
		(layer "In2.Cu")
	)
	(gr_line
		(start 87.743538 -19.836638)
		(end 87.758524 -19.859244)
		(stroke
			(width 0.07112)
			(type default)
		)
		(layer "In2.Cu")
	)
	(gr_line
		(start 88.460072 -23.640542)
		(end 88.537542 -23.589234)
		(stroke
			(width 0.07112)
			(type default)
		)
		(layer "In2.Cu")
	)
	(gr_line
		(start 88.504776 -20.986496)
		(end 88.517984 -21.006562)
		(stroke
			(width 0.07112)
			(type default)
		)
		(layer "In2.Cu")
	)
	(gr_line
		(start 88.517984 -21.006562)
		(end 88.522556 -21.02993)
		(stroke
			(width 0.07112)
			(type default)
		)
		(layer "In2.Cu")
	)
	(gr_line
		(start 88.537542 -23.589234)
		(end 88.55583 -23.498556)
		(stroke
			(width 0.07112)
			(type default)
		)
		(layer "In2.Cu")
	)
	(gr_line
		(start 88.7857 -22.371558)
		(end 88.79078 -22.347174)
		(stroke
			(width 0.07112)
			(type default)
		)
		(layer "In2.Cu")
	)
	(gr_line
		(start 88.7857 -22.323044)
		(end 88.79078 -22.347174)
		(stroke
			(width 0.07112)
			(type default)
		)
		(layer "In2.Cu")
	)
	(gr_line
		(start 0 -22.200108)
		(end 0 -0.999998)
		(stroke
			(width 1.524)
			(type default)
		)
		(layer "In4.Cu")
	)
	(gr_arc
		(start 0 -22.200108)
		(mid 0.292895 -22.907209)
		(end 0.999998 -23.200106)
		(stroke
			(width 1.524)
			(type default)
		)
		(layer "In4.Cu")
	)
	(gr_arc
		(start 0.999998 0)
		(mid 0.292893 -0.292893)
		(end 0 -0.999998)
		(stroke
			(width 1.524)
			(type default)
		)
		(layer "In4.Cu")
	)
	(gr_line
		(start 0.999998 0)
		(end 94.499938 0)
		(stroke
			(width 1.524)
			(type default)
		)
		(layer "In4.Cu")
	)
	(gr_line
		(start 23.694898 -14.538452)
		(end 24.964898 -14.538452)
		(stroke
			(width 0.2)
			(type default)
		)
		(layer "In4.Cu")
	)
	(gr_arc
		(start 23.694898 -13.161772)
		(mid 23.006558 -13.850112)
		(end 23.694898 -14.538452)
		(stroke
			(width 0.2)
			(type default)
		)
		(layer "In4.Cu")
	)
	(gr_line
		(start 23.694898 -3.238246)
		(end 24.964898 -3.238246)
		(stroke
			(width 0.2)
			(type default)
		)
		(layer "In4.Cu")
	)
	(gr_arc
		(start 23.694898 -1.861566)
		(mid 23.006558 -2.549906)
		(end 23.694898 -3.238246)
		(stroke
			(width 0.2)
			(type default)
		)
		(layer "In4.Cu")
	)
	(gr_arc
		(start 24.964898 -14.538452)
		(mid 25.653238 -13.850112)
		(end 24.964898 -13.161772)
		(stroke
			(width 0.2)
			(type default)
		)
		(layer "In4.Cu")
	)
	(gr_line
		(start 24.964898 -13.161772)
		(end 23.694898 -13.161772)
		(stroke
			(width 0.2)
			(type default)
		)
		(layer "In4.Cu")
	)
	(gr_arc
		(start 24.964898 -3.238246)
		(mid 25.653238 -2.549906)
		(end 24.964898 -1.861566)
		(stroke
			(width 0.2)
			(type default)
		)
		(layer "In4.Cu")
	)
	(gr_line
		(start 24.964898 -1.861566)
		(end 23.694898 -1.861566)
		(stroke
			(width 0.2)
			(type default)
		)
		(layer "In4.Cu")
	)
	(gr_line
		(start 27.504898 -14.538452)
		(end 28.774898 -14.538452)
		(stroke
			(width 0.2)
			(type default)
		)
		(layer "In4.Cu")
	)
	(gr_arc
		(start 27.504898 -13.161772)
		(mid 26.816558 -13.850112)
		(end 27.504898 -14.538452)
		(stroke
			(width 0.2)
			(type default)
		)
		(layer "In4.Cu")
	)
	(gr_line
		(start 27.504898 -3.238246)
		(end 28.774898 -3.238246)
		(stroke
			(width 0.2)
			(type default)
		)
		(layer "In4.Cu")
	)
	(gr_arc
		(start 27.504898 -1.861566)
		(mid 26.816558 -2.549906)
		(end 27.504898 -3.238246)
		(stroke
			(width 0.2)
			(type default)
		)
		(layer "In4.Cu")
	)
	(gr_arc
		(start 28.774898 -14.538452)
		(mid 29.463238 -13.850112)
		(end 28.774898 -13.161772)
		(stroke
			(width 0.2)
			(type default)
		)
		(layer "In4.Cu")
	)
	(gr_line
		(start 28.774898 -13.161772)
		(end 27.504898 -13.161772)
		(stroke
			(width 0.2)
			(type default)
		)
		(layer "In4.Cu")
	)
	(gr_arc
		(start 28.774898 -3.238246)
		(mid 29.463238 -2.549906)
		(end 28.774898 -1.861566)
		(stroke
			(width 0.2)
			(type default)
		)
		(layer "In4.Cu")
	)
	(gr_line
		(start 28.774898 -1.861566)
		(end 27.504898 -1.861566)
		(stroke
			(width 0.2)
			(type default)
		)
		(layer "In4.Cu")
	)
	(gr_line
		(start 48.999902 -23.200106)
		(end 0.999998 -23.200106)
		(stroke
			(width 1.524)
			(type default)
		)
		(layer "In4.Cu")
	)
	(gr_line
		(start 49.500028 -24.200104)
		(end 49.500028 -23.699978)
		(stroke
			(width 1.524)
			(type default)
		)
		(layer "In4.Cu")
	)
	(gr_arc
		(start 49.500028 -24.200104)
		(mid 49.646439 -24.553564)
		(end 49.9999 -24.699976)
		(stroke
			(width 1.524)
			(type default)
		)
		(layer "In4.Cu")
	)
	(gr_arc
		(start 49.500028 -23.699978)
		(mid 49.353439 -23.34659)
		(end 48.999902 -23.200106)
		(stroke
			(width 1.524)
			(type default)
		)
		(layer "In4.Cu")
	)
	(gr_line
		(start 68.49999 -24.699976)
		(end 49.9999 -24.699976)
		(stroke
			(width 1.524)
			(type default)
		)
		(layer "In4.Cu")
	)
	(gr_line
		(start 69.499988 -64.200024)
		(end 69.499988 -25.699974)
		(stroke
			(width 1.524)
			(type default)
		)
		(layer "In4.Cu")
	)
	(gr_arc
		(start 69.499988 -64.200024)
		(mid 69.792888 -64.907119)
		(end 70.499986 -65.200022)
		(stroke
			(width 1.524)
			(type default)
		)
		(layer "In4.Cu")
	)
	(gr_arc
		(start 69.499988 -25.699974)
		(mid 69.207095 -24.992869)
		(end 68.49999 -24.699976)
		(stroke
			(width 1.524)
			(type default)
		)
		(layer "In4.Cu")
	)
	(gr_rect
		(start 74.987912 -23.40229)
		(end 76.181712 -24.507698)
		(stroke
			(width 0)
			(type default)
		)
		(fill no)
		(layer "In4.Cu")
	)
	(gr_rect
		(start 74.987912 -21.152104)
		(end 76.181712 -22.257766)
		(stroke
			(width 0)
			(type default)
		)
		(fill no)
		(layer "In4.Cu")
	)
	(gr_rect
		(start 77.687932 -23.40229)
		(end 78.881732 -24.507698)
		(stroke
			(width 0)
			(type default)
		)
		(fill no)
		(layer "In4.Cu")
	)
	(gr_rect
		(start 77.687932 -21.152104)
		(end 78.881732 -22.257766)
		(stroke
			(width 0)
			(type default)
		)
		(fill no)
		(layer "In4.Cu")
	)
	(gr_rect
		(start 81.218024 -23.40229)
		(end 82.411824 -24.507698)
		(stroke
			(width 0)
			(type default)
		)
		(fill no)
		(layer "In4.Cu")
	)
	(gr_rect
		(start 81.218024 -21.152104)
		(end 82.411824 -22.257766)
		(stroke
			(width 0)
			(type default)
		)
		(fill no)
		(layer "In4.Cu")
	)
	(gr_arc
		(start 82.576416 -22.182582)
		(mid 83.086829 -22.693376)
		(end 83.597496 -22.182836)
		(stroke
			(width 0.2)
			(type default)
		)
		(layer "In4.Cu")
	)
	(gr_line
		(start 82.576416 -21.166836)
		(end 82.576416 -22.182582)
		(stroke
			(width 0.2)
			(type default)
		)
		(layer "In4.Cu")
	)
	(gr_line
		(start 82.652616 -26.21915)
		(end 83.668616 -26.21915)
		(stroke
			(width 0.2)
			(type default)
		)
		(layer "In4.Cu")
	)
	(gr_arc
		(start 82.65287 -25.19807)
		(mid 82.142076 -25.708483)
		(end 82.652616 -26.21915)
		(stroke
			(width 0.2)
			(type default)
		)
		(layer "In4.Cu")
	)
	(gr_line
		(start 83.597496 -22.182836)
		(end 83.597496 -21.166836)
		(stroke
			(width 0.2)
			(type default)
		)
		(layer "In4.Cu")
	)
	(gr_arc
		(start 83.597496 -21.166836)
		(mid 83.086956 -20.656296)
		(end 82.576416 -21.166836)
		(stroke
			(width 0.2)
			(type default)
		)
		(layer "In4.Cu")
	)
	(gr_arc
		(start 83.668616 -26.21915)
		(mid 84.179156 -25.70861)
		(end 83.668616 -25.19807)
		(stroke
			(width 0.2)
			(type default)
		)
		(layer "In4.Cu")
	)
	(gr_line
		(start 83.668616 -25.19807)
		(end 82.65287 -25.19807)
		(stroke
			(width 0.2)
			(type default)
		)
		(layer "In4.Cu")
	)
	(gr_rect
		(start 83.918044 -23.40229)
		(end 85.111844 -24.507698)
		(stroke
			(width 0)
			(type default)
		)
		(fill no)
		(layer "In4.Cu")
	)
	(gr_rect
		(start 83.918044 -21.152104)
		(end 85.111844 -22.257766)
		(stroke
			(width 0)
			(type default)
		)
		(fill no)
		(layer "In4.Cu")
	)
	(gr_arc
		(start 86.071456 -24.46274)
		(mid 86.581869 -24.973534)
		(end 87.092536 -24.462994)
		(stroke
			(width 0.2)
			(type default)
		)
		(layer "In4.Cu")
	)
	(gr_line
		(start 86.071456 -23.446994)
		(end 86.071456 -24.46274)
		(stroke
			(width 0.2)
			(type default)
		)
		(layer "In4.Cu")
	)
	(gr_arc
		(start 86.618572 -22.211284)
		(mid 87.128985 -22.722078)
		(end 87.639652 -22.211538)
		(stroke
			(width 0.2)
			(type default)
		)
		(layer "In4.Cu")
	)
	(gr_line
		(start 86.618572 -21.195538)
		(end 86.618572 -22.211284)
		(stroke
			(width 0.2)
			(type default)
		)
		(layer "In4.Cu")
	)
	(gr_line
		(start 87.092536 -24.462994)
		(end 87.092536 -23.446994)
		(stroke
			(width 0.2)
			(type default)
		)
		(layer "In4.Cu")
	)
	(gr_arc
		(start 87.092536 -23.446994)
		(mid 86.581996 -22.936454)
		(end 86.071456 -23.446994)
		(stroke
			(width 0.2)
			(type default)
		)
		(layer "In4.Cu")
	)
	(gr_line
		(start 87.639652 -22.211538)
		(end 87.639652 -21.195538)
		(stroke
			(width 0.2)
			(type default)
		)
		(layer "In4.Cu")
	)
	(gr_arc
		(start 87.639652 -21.195538)
		(mid 87.129112 -20.684998)
		(end 86.618572 -21.195538)
		(stroke
			(width 0.2)
			(type default)
		)
		(layer "In4.Cu")
	)
	(gr_arc
		(start 95.499936 -23.999952)
		(mid 95.792829 -24.707057)
		(end 96.499934 -24.99995)
		(stroke
			(width 1.524)
			(type default)
		)
		(layer "In4.Cu")
	)
	(gr_arc
		(start 95.499936 -0.999998)
		(mid 95.207045 -0.29288)
		(end 94.499938 0)
		(stroke
			(width 1.524)
			(type default)
		)
		(layer "In4.Cu")
	)
	(gr_line
		(start 95.499936 -0.999998)
		(end 95.499936 -23.999952)
		(stroke
			(width 1.524)
			(type default)
		)
		(layer "In4.Cu")
	)
	(gr_line
		(start 96.499934 -24.99995)
		(end 117.350032 -24.99995)
		(stroke
			(width 1.524)
			(type default)
		)
		(layer "In4.Cu")
	)
	(gr_line
		(start 97.620074 -52.4383)
		(end 98.890074 -52.4383)
		(stroke
			(width 0.2)
			(type default)
		)
		(layer "In4.Cu")
	)
	(gr_arc
		(start 97.620074 -51.06162)
		(mid 96.931734 -51.74996)
		(end 97.620074 -52.4383)
		(stroke
			(width 0.2)
			(type default)
		)
		(layer "In4.Cu")
	)
	(gr_line
		(start 97.620074 -35.738308)
		(end 98.890074 -35.738308)
		(stroke
			(width 0.2)
			(type default)
		)
		(layer "In4.Cu")
	)
	(gr_arc
		(start 97.620074 -34.361628)
		(mid 96.931734 -35.049968)
		(end 97.620074 -35.738308)
		(stroke
			(width 0.2)
			(type default)
		)
		(layer "In4.Cu")
	)
	(gr_arc
		(start 98.890074 -52.4383)
		(mid 99.578414 -51.74996)
		(end 98.890074 -51.06162)
		(stroke
			(width 0.2)
			(type default)
		)
		(layer "In4.Cu")
	)
	(gr_line
		(start 98.890074 -51.06162)
		(end 97.620074 -51.06162)
		(stroke
			(width 0.2)
			(type default)
		)
		(layer "In4.Cu")
	)
	(gr_arc
		(start 98.890074 -35.738308)
		(mid 99.578414 -35.049968)
		(end 98.890074 -34.361628)
		(stroke
			(width 0.2)
			(type default)
		)
		(layer "In4.Cu")
	)
	(gr_line
		(start 98.890074 -34.361628)
		(end 97.620074 -34.361628)
		(stroke
			(width 0.2)
			(type default)
		)
		(layer "In4.Cu")
	)
	(gr_line
		(start 101.430074 -52.4383)
		(end 102.700074 -52.4383)
		(stroke
			(width 0.2)
			(type default)
		)
		(layer "In4.Cu")
	)
	(gr_arc
		(start 101.430074 -51.06162)
		(mid 100.741734 -51.74996)
		(end 101.430074 -52.4383)
		(stroke
			(width 0.2)
			(type default)
		)
		(layer "In4.Cu")
	)
	(gr_line
		(start 101.430074 -35.738308)
		(end 102.700074 -35.738308)
		(stroke
			(width 0.2)
			(type default)
		)
		(layer "In4.Cu")
	)
	(gr_arc
		(start 101.430074 -34.361628)
		(mid 100.741734 -35.049968)
		(end 101.430074 -35.738308)
		(stroke
			(width 0.2)
			(type default)
		)
		(layer "In4.Cu")
	)
	(gr_arc
		(start 102.700074 -52.4383)
		(mid 103.388414 -51.74996)
		(end 102.700074 -51.06162)
		(stroke
			(width 0.2)
			(type default)
		)
		(layer "In4.Cu")
	)
	(gr_line
		(start 102.700074 -51.06162)
		(end 101.430074 -51.06162)
		(stroke
			(width 0.2)
			(type default)
		)
		(layer "In4.Cu")
	)
	(gr_arc
		(start 102.700074 -35.738308)
		(mid 103.388414 -35.049968)
		(end 102.700074 -34.361628)
		(stroke
			(width 0.2)
			(type default)
		)
		(layer "In4.Cu")
	)
	(gr_line
		(start 102.700074 -34.361628)
		(end 101.430074 -34.361628)
		(stroke
			(width 0.2)
			(type default)
		)
		(layer "In4.Cu")
	)
	(gr_arc
		(start 117.350032 -24.99995)
		(mid 118.057137 -24.707057)
		(end 118.35003 -23.999952)
		(stroke
			(width 1.524)
			(type default)
		)
		(layer "In4.Cu")
	)
	(gr_line
		(start 118.35003 -23.999952)
		(end 118.35003 -20.049998)
		(stroke
			(width 1.524)
			(type default)
		)
		(layer "In4.Cu")
	)
	(gr_arc
		(start 119.350028 -19.05)
		(mid 118.642904 -19.342883)
		(end 118.35003 -20.049998)
		(stroke
			(width 1.524)
			(type default)
		)
		(layer "In4.Cu")
	)
	(gr_line
		(start 119.350028 -19.05)
		(end 134.500112 -19.05)
		(stroke
			(width 1.524)
			(type default)
		)
		(layer "In4.Cu")
	)
	(gr_arc
		(start 134.500112 -19.05)
		(mid 135.207217 -18.757107)
		(end 135.50011 -18.050002)
		(stroke
			(width 1.524)
			(type default)
		)
		(layer "In4.Cu")
	)
	(gr_line
		(start 135.50011 -18.050002)
		(end 135.50011 -0.999998)
		(stroke
			(width 1.524)
			(type default)
		)
		(layer "In4.Cu")
	)
	(gr_arc
		(start 136.500108 0)
		(mid 135.792997 -0.29289)
		(end 135.50011 -0.999998)
		(stroke
			(width 1.524)
			(type default)
		)
		(layer "In4.Cu")
	)
	(gr_line
		(start 136.500108 0)
		(end 142.500096 0)
		(stroke
			(width 1.524)
			(type default)
		)
		(layer "In4.Cu")
	)
	(gr_line
		(start 142.500096 -65.200022)
		(end 70.499986 -65.200022)
		(stroke
			(width 1.524)
			(type default)
		)
		(layer "In4.Cu")
	)
	(gr_arc
		(start 142.500096 -65.200022)
		(mid 143.207212 -64.907132)
		(end 143.500094 -64.200024)
		(stroke
			(width 1.524)
			(type default)
		)
		(layer "In4.Cu")
	)
	(gr_arc
		(start 143.500094 -0.999998)
		(mid 143.2072 -0.292895)
		(end 142.500096 0)
		(stroke
			(width 1.524)
			(type default)
		)
		(layer "In4.Cu")
	)
	(gr_line
		(start 143.500094 -0.999998)
		(end 143.500094 -64.200024)
		(stroke
			(width 1.524)
			(type default)
		)
		(layer "In4.Cu")
	)
	(gr_line
		(start 0 -22.200108)
		(end 0 -0.999998)
		(stroke
			(width 0.05)
			(type default)
		)
		(layer "Edge.Cuts")
	)
	(gr_arc
		(start 0 -22.200108)
		(mid 0.292895 -22.907209)
		(end 0.999998 -23.200106)
		(stroke
			(width 0.05)
			(type default)
		)
		(layer "Edge.Cuts")
	)
	(gr_arc
		(start 0.999998 0)
		(mid 0.292893 -0.292893)
		(end 0 -0.999998)
		(stroke
			(width 0.05)
			(type default)
		)
		(layer "Edge.Cuts")
	)
	(gr_line
		(start 0.999998 0)
		(end 94.499938 0)
		(stroke
			(width 0.05)
			(type default)
		)
		(layer "Edge.Cuts")
	)
	(gr_arc
		(start 1.89992 -4.020058)
		(mid 3.999992 -6.12013)
		(end 6.100064 -4.020058)
		(stroke
			(width 0.05)
			(type default)
		)
		(layer "Edge.Cuts")
	)
	(gr_arc
		(start 2.350008 -17.020032)
		(mid 3.999992 -18.670016)
		(end 5.649976 -17.020032)
		(stroke
			(width 0.05)
			(type default)
		)
		(layer "Edge.Cuts")
	)
	(gr_arc
		(start 3.40995 -11.199876)
		(mid 4.500118 -12.290044)
		(end 5.590032 -11.199876)
		(stroke
			(width 0.05)
			(type default)
		)
		(layer "Edge.Cuts")
	)
	(gr_arc
		(start 5.590032 -11.199876)
		(mid 4.500118 -10.109962)
		(end 3.40995 -11.199876)
		(stroke
			(width 0.05)
			(type default)
		)
		(layer "Edge.Cuts")
	)
	(gr_arc
		(start 5.649976 -17.020032)
		(mid 3.999992 -15.370048)
		(end 2.350008 -17.020032)
		(stroke
			(width 0.05)
			(type default)
		)
		(layer "Edge.Cuts")
	)
	(gr_arc
		(start 6.100064 -4.020058)
		(mid 3.999992 -1.919986)
		(end 1.89992 -4.020058)
		(stroke
			(width 0.05)
			(type default)
		)
		(layer "Edge.Cuts")
	)
	(gr_arc
		(start 20.500086 -11.500104)
		(mid 20.646495 -11.853567)
		(end 20.999958 -11.999976)
		(stroke
			(width 0.05)
			(type default)
		)
		(layer "Edge.Cuts")
	)
	(gr_line
		(start 20.500086 -10.999978)
		(end 20.500086 -11.500104)
		(stroke
			(width 0.05)
			(type default)
		)
		(layer "Edge.Cuts")
	)
	(gr_line
		(start 20.999958 -11.999976)
		(end 47.999904 -11.999976)
		(stroke
			(width 0.05)
			(type default)
		)
		(layer "Edge.Cuts")
	)
	(gr_arc
		(start 20.999958 -10.500106)
		(mid 20.646495 -10.646515)
		(end 20.500086 -10.999978)
		(stroke
			(width 0.05)
			(type default)
		)
		(layer "Edge.Cuts")
	)
	(gr_arc
		(start 47.999904 -11.999976)
		(mid 48.353531 -11.853657)
		(end 48.50003 -11.500104)
		(stroke
			(width 0.05)
			(type default)
		)
		(layer "Edge.Cuts")
	)
	(gr_line
		(start 47.999904 -10.500106)
		(end 20.999958 -10.500106)
		(stroke
			(width 0.05)
			(type default)
		)
		(layer "Edge.Cuts")
	)
	(gr_line
		(start 48.50003 -11.500104)
		(end 48.50003 -10.999978)
		(stroke
			(width 0.05)
			(type default)
		)
		(layer "Edge.Cuts")
	)
	(gr_arc
		(start 48.50003 -10.999978)
		(mid 48.353441 -10.64659)
		(end 47.999904 -10.500106)
		(stroke
			(width 0.05)
			(type default)
		)
		(layer "Edge.Cuts")
	)
	(gr_line
		(start 48.999902 -23.200106)
		(end 0.999998 -23.200106)
		(stroke
			(width 0.05)
			(type default)
		)
		(layer "Edge.Cuts")
	)
	(gr_line
		(start 49.500028 -24.200104)
		(end 49.500028 -23.699978)
		(stroke
			(width 0.05)
			(type default)
		)
		(layer "Edge.Cuts")
	)
	(gr_arc
		(start 49.500028 -24.200104)
		(mid 49.646439 -24.553564)
		(end 49.9999 -24.699976)
		(stroke
			(width 0.05)
			(type default)
		)
		(layer "Edge.Cuts")
	)
	(gr_arc
		(start 49.500028 -23.699978)
		(mid 49.353439 -23.34659)
		(end 48.999902 -23.200106)
		(stroke
			(width 0.05)
			(type default)
		)
		(layer "Edge.Cuts")
	)
	(gr_line
		(start 68.49999 -24.699976)
		(end 49.9999 -24.699976)
		(stroke
			(width 0.05)
			(type default)
		)
		(layer "Edge.Cuts")
	)
	(gr_line
		(start 69.499988 -64.200024)
		(end 69.499988 -25.699974)
		(stroke
			(width 0.05)
			(type default)
		)
		(layer "Edge.Cuts")
	)
	(gr_arc
		(start 69.499988 -64.200024)
		(mid 69.792888 -64.907119)
		(end 70.499986 -65.200022)
		(stroke
			(width 0.05)
			(type default)
		)
		(layer "Edge.Cuts")
	)
	(gr_arc
		(start 69.499988 -25.699974)
		(mid 69.207095 -24.992869)
		(end 68.49999 -24.699976)
		(stroke
			(width 0.05)
			(type default)
		)
		(layer "Edge.Cuts")
	)
	(gr_arc
		(start 75.350116 -61.699902)
		(mid 77.0001 -63.349886)
		(end 78.650084 -61.699902)
		(stroke
			(width 0.05)
			(type default)
		)
		(layer "Edge.Cuts")
	)
	(gr_arc
		(start 75.350116 -3.50012)
		(mid 77.0001 -5.150104)
		(end 78.650084 -3.50012)
		(stroke
			(width 0.05)
			(type default)
		)
		(layer "Edge.Cuts")
	)
	(gr_arc
		(start 78.650084 -61.699902)
		(mid 77.0001 -60.049918)
		(end 75.350116 -61.699902)
		(stroke
			(width 0.05)
			(type default)
		)
		(layer "Edge.Cuts")
	)
	(gr_arc
		(start 78.650084 -3.50012)
		(mid 77.0001 -1.850136)
		(end 75.350116 -3.50012)
		(stroke
			(width 0.05)
			(type default)
		)
		(layer "Edge.Cuts")
	)
	(gr_arc
		(start 95.499936 -45.748702)
		(mid 95.64642 -46.102344)
		(end 96.000062 -46.248828)
		(stroke
			(width 0.05)
			(type default)
		)
		(layer "Edge.Cuts")
	)
	(gr_line
		(start 95.499936 -42.248836)
		(end 95.499936 -45.748702)
		(stroke
			(width 0.05)
			(type default)
		)
		(layer "Edge.Cuts")
	)
	(gr_arc
		(start 95.499936 -23.999952)
		(mid 95.792829 -24.707057)
		(end 96.499934 -24.99995)
		(stroke
			(width 0.05)
			(type default)
		)
		(layer "Edge.Cuts")
	)
	(gr_arc
		(start 95.499936 -0.999998)
		(mid 95.207045 -0.29288)
		(end 94.499938 0)
		(stroke
			(width 0.05)
			(type default)
		)
		(layer "Edge.Cuts")
	)
	(gr_line
		(start 95.499936 -0.999998)
		(end 95.499936 -23.999952)
		(stroke
			(width 0.05)
			(type default)
		)
		(layer "Edge.Cuts")
	)
	(gr_line
		(start 96.000062 -46.248828)
		(end 123.000008 -46.248828)
		(stroke
			(width 0.05)
			(type default)
		)
		(layer "Edge.Cuts")
	)
	(gr_arc
		(start 96.000062 -41.74871)
		(mid 95.64642 -41.895194)
		(end 95.499936 -42.248836)
		(stroke
			(width 0.05)
			(type default)
		)
		(layer "Edge.Cuts")
	)
	(gr_line
		(start 96.499934 -24.99995)
		(end 117.350032 -24.99995)
		(stroke
			(width 0.05)
			(type default)
		)
		(layer "Edge.Cuts")
	)
	(gr_arc
		(start 117.350032 -24.99995)
		(mid 118.057137 -24.707057)
		(end 118.35003 -23.999952)
		(stroke
			(width 0.05)
			(type default)
		)
		(layer "Edge.Cuts")
	)
	(gr_line
		(start 118.35003 -23.999952)
		(end 118.35003 -20.049998)
		(stroke
			(width 0.05)
			(type default)
		)
		(layer "Edge.Cuts")
	)
	(gr_arc
		(start 119.350028 -19.05)
		(mid 118.642904 -19.342883)
		(end 118.35003 -20.049998)
		(stroke
			(width 0.05)
			(type default)
		)
		(layer "Edge.Cuts")
	)
	(gr_line
		(start 119.350028 -19.05)
		(end 134.500112 -19.05)
		(stroke
			(width 0.05)
			(type default)
		)
		(layer "Edge.Cuts")
	)
	(gr_arc
		(start 123.000008 -46.248828)
		(mid 123.353561 -46.102329)
		(end 123.49988 -45.748702)
		(stroke
			(width 0.05)
			(type default)
		)
		(layer "Edge.Cuts")
	)
	(gr_line
		(start 123.000008 -41.74871)
		(end 96.000062 -41.74871)
		(stroke
			(width 0.05)
			(type default)
		)
		(layer "Edge.Cuts")
	)
	(gr_line
		(start 123.49988 -45.748702)
		(end 123.49988 -42.248836)
		(stroke
			(width 0.05)
			(type default)
		)
		(layer "Edge.Cuts")
	)
	(gr_arc
		(start 123.49988 -42.248836)
		(mid 123.353471 -41.895373)
		(end 123.000008 -41.74871)
		(stroke
			(width 0.05)
			(type default)
		)
		(layer "Edge.Cuts")
	)
	(gr_arc
		(start 132.409946 -61.20003)
		(mid 133.500114 -62.290198)
		(end 134.590028 -61.20003)
		(stroke
			(width 0.05)
			(type default)
		)
		(layer "Edge.Cuts")
	)
	(gr_arc
		(start 134.500112 -19.05)
		(mid 135.207217 -18.757107)
		(end 135.50011 -18.050002)
		(stroke
			(width 0.05)
			(type default)
		)
		(layer "Edge.Cuts")
	)
	(gr_arc
		(start 134.590028 -61.20003)
		(mid 133.500114 -60.110116)
		(end 132.409946 -61.20003)
		(stroke
			(width 0.05)
			(type default)
		)
		(layer "Edge.Cuts")
	)
	(gr_line
		(start 135.50011 -18.050002)
		(end 135.50011 -0.999998)
		(stroke
			(width 0.05)
			(type default)
		)
		(layer "Edge.Cuts")
	)
	(gr_arc
		(start 136.500108 0)
		(mid 135.792997 -0.29289)
		(end 135.50011 -0.999998)
		(stroke
			(width 0.05)
			(type default)
		)
		(layer "Edge.Cuts")
	)
	(gr_line
		(start 136.500108 0)
		(end 142.500096 0)
		(stroke
			(width 0.05)
			(type default)
		)
		(layer "Edge.Cuts")
	)
	(gr_arc
		(start 137.899902 -61.699902)
		(mid 139.999974 -63.799974)
		(end 142.100046 -61.699902)
		(stroke
			(width 0.05)
			(type default)
		)
		(layer "Edge.Cuts")
	)
	(gr_arc
		(start 138.34999 -3.50012)
		(mid 139.999974 -5.150104)
		(end 141.649958 -3.50012)
		(stroke
			(width 0.05)
			(type default)
		)
		(layer "Edge.Cuts")
	)
	(gr_arc
		(start 139.320016 -10.199878)
		(mid 140.410184 -11.290046)
		(end 141.500098 -10.199878)
		(stroke
			(width 0.05)
			(type default)
		)
		(layer "Edge.Cuts")
	)
	(gr_arc
		(start 141.500098 -10.199878)
		(mid 140.410184 -9.109964)
		(end 139.320016 -10.199878)
		(stroke
			(width 0.05)
			(type default)
		)
		(layer "Edge.Cuts")
	)
	(gr_arc
		(start 141.649958 -3.50012)
		(mid 139.999974 -1.850136)
		(end 138.34999 -3.50012)
		(stroke
			(width 0.05)
			(type default)
		)
		(layer "Edge.Cuts")
	)
	(gr_arc
		(start 142.100046 -61.699902)
		(mid 139.999974 -59.59983)
		(end 137.899902 -61.699902)
		(stroke
			(width 0.05)
			(type default)
		)
		(layer "Edge.Cuts")
	)
	(gr_line
		(start 142.500096 -65.200022)
		(end 70.499986 -65.200022)
		(stroke
			(width 0.05)
			(type default)
		)
		(layer "Edge.Cuts")
	)
	(gr_arc
		(start 142.500096 -65.200022)
		(mid 143.207212 -64.907132)
		(end 143.500094 -64.200024)
		(stroke
			(width 0.05)
			(type default)
		)
		(layer "Edge.Cuts")
	)
	(gr_arc
		(start 143.500094 -0.999998)
		(mid 143.2072 -0.292895)
		(end 142.500096 0)
		(stroke
			(width 0.05)
			(type default)
		)
		(layer "Edge.Cuts")
	)
	(gr_line
		(start 143.500094 -0.999998)
		(end 143.500094 -64.200024)
		(stroke
			(width 0.05)
			(type default)
		)
		(layer "Edge.Cuts")
	)
	(via
		(at 85.723476 -45.07738)
		(size 0.7112)
		(drill 0.3556)
		(layers "F.Cu" "B.Cu")
		(net "PWR_EN_R_P5V")
	)
	(segment
		(start 85.326474 -47.892716)
		(end 85.723476 -47.495714)
		(width 0.254)
		(layer "B.Cu")
		(net "PWR_EN_R_P5V")
	)
	(segment
		(start 83.329272 -44.7675)
		(end 84.328 -44.7675)
		(width 0.254)
		(layer "B.Cu")
		(net "PWR_EN_R_P5V")
	)
	(segment
		(start 83.599274 -47.892716)
		(end 85.326474 -47.892716)
		(width 0.254)
		(layer "B.Cu")
		(net "PWR_EN_R_P5V")
	)
	(segment
		(start 85.413596 -44.7675)
		(end 85.723476 -45.07738)
		(width 0.254)
		(layer "B.Cu")
		(net "PWR_EN_R_P5V")
	)
	(segment
		(start 85.723476 -47.495714)
		(end 85.723476 -45.07738)
		(width 0.254)
		(layer "B.Cu")
		(net "PWR_EN_R_P5V")
	)
	(segment
		(start 84.328 -44.7675)
		(end 85.413596 -44.7675)
		(width 0.254)
		(layer "B.Cu")
		(net "PWR_EN_R_P5V")
	)
	(segment
		(start 83.320636 -44.776136)
		(end 83.329272 -44.7675)
		(width 0.254)
		(layer "B.Cu")
		(net "PWR_EN_R_P5V")
	)
	(segment
		(start 81.084166 -43.927776)
		(end 81.932526 -44.776136)
		(width 0.254)
		(layer "B.Cu")
		(net "PWR_EN_R_P5V")
	)
	(segment
		(start 81.932526 -44.776136)
		(end 83.320636 -44.776136)
		(width 0.254)
		(layer "B.Cu")
		(net "PWR_EN_R_P5V")
	)
	(segment
		(start 69.916294 -5.669026)
		(end 69.144134 -5.669026)
		(width 0.254)
		(layer "B.Cu")
		(net "PWR_EN_L_P5V")
	)
	(segment
		(start 72.411082 -6.725412)
		(end 71.395082 -6.725412)
		(width 0.254)
		(layer "B.Cu")
		(net "PWR_EN_L_P5V")
	)
	(segment
		(start 70.97268 -6.725412)
		(end 69.916294 -5.669026)
		(width 0.254)
		(layer "B.Cu")
		(net "PWR_EN_L_P5V")
	)
	(segment
		(start 71.395082 -6.725412)
		(end 70.97268 -6.725412)
		(width 0.254)
		(layer "B.Cu")
		(net "PWR_EN_L_P5V")
	)
	(segment
		(start 69.144134 -5.669026)
		(end 69.144134 -7.964678)
		(width 0.254)
		(layer "B.Cu")
		(net "PWR_EN_L_P5V")
	)
	(segment
		(start 70.704456 -9.525)
		(end 73.025 -9.525)
		(width 0.254)
		(layer "B.Cu")
		(net "PWR_EN_L_P5V")
	)
	(segment
		(start 69.144134 -7.964678)
		(end 70.704456 -9.525)
		(width 0.254)
		(layer "B.Cu")
		(net "PWR_EN_L_P5V")
	)
	(segment
		(start 79.5655 -7.0739)
		(end 79.7306 -6.9088)
		(width 0.18288)
		(layer "F.Cu")
		(net "VIN_P3")
	)
	(segment
		(start 79.5655 -8.128)
		(end 79.5655 -7.0739)
		(width 0.18288)
		(layer "F.Cu")
		(net "VIN_P3")
	)
	(segment
		(start 78.4225 -8.128)
		(end 79.5655 -8.128)
		(width 0.18288)
		(layer "F.Cu")
		(net "VIN_P3")
	)
	(via
		(at 79.7306 -6.9088)
		(size 0.508)
		(drill 0.254)
		(layers "F.Cu" "B.Cu")
		(net "VIN_P3")
	)
	(segment
		(start 79.71536 -6.92404)
		(end 79.71536 -8.382)
		(width 0.18288)
		(layer "B.Cu")
		(net "VIN_P3")
	)
	(segment
		(start 79.7306 -6.9088)
		(end 79.71536 -6.92404)
		(width 0.18288)
		(layer "B.Cu")
		(net "VIN_P3")
	)
	(segment
		(start 83.5025 -36.82492)
		(end 83.5025 -36.068)
		(width 0.254)
		(layer "F.Cu")
		(net "SW_SW_R_N_0")
	)
	(segment
		(start 85.115146 -38.12286)
		(end 84.112354 -38.12286)
		(width 0.254)
		(layer "F.Cu")
		(net "SW_SW_R_N_0")
	)
	(segment
		(start 84.112354 -38.12286)
		(end 83.096354 -38.12286)
		(width 0.254)
		(layer "F.Cu")
		(net "SW_SW_R_N_0")
	)
	(segment
		(start 83.096354 -38.12286)
		(end 83.096354 -37.231066)
		(width 0.254)
		(layer "F.Cu")
		(net "SW_SW_R_N_0")
	)
	(segment
		(start 83.096354 -37.231066)
		(end 83.5025 -36.82492)
		(width 0.254)
		(layer "F.Cu")
		(net "SW_SW_R_N_0")
	)
	(segment
		(start 85.404452 -37.833554)
		(end 85.115146 -38.12286)
		(width 0.254)
		(layer "F.Cu")
		(net "SW_SW_R_N_0")
	)
	(via
		(at 85.404452 -37.833554)
		(size 0.508)
		(drill 0.254)
		(layers "F.Cu" "B.Cu")
		(net "SW_SW_R_N_0")
	)
	(segment
		(start 83.4136 -35.941)
		(end 83.4136 -36.911534)
		(width 0.254)
		(layer "B.Cu")
		(net "SW_SW_R_N_0")
	)
	(segment
		(start 85.404452 -37.833554)
		(end 85.265006 -37.973)
		(width 0.254)
		(layer "B.Cu")
		(net "SW_SW_R_N_0")
	)
	(segment
		(start 83.566 -37.063934)
		(end 83.566 -37.973)
		(width 0.254)
		(layer "B.Cu")
		(net "SW_SW_R_N_0")
	)
	(segment
		(start 83.4136 -36.911534)
		(end 83.566 -37.063934)
		(width 0.254)
		(layer "B.Cu")
		(net "SW_SW_R_N_0")
	)
	(segment
		(start 85.265006 -37.973)
		(end 83.566 -37.973)
		(width 0.254)
		(layer "B.Cu")
		(net "SW_SW_R_N_0")
	)
	(segment
		(start 81.5975 -36.068)
		(end 81.5975 -37.186616)
		(width 0.254)
		(layer "F.Cu")
		(net "SW_SW_R_0")
	)
	(segment
		(start 82.6135 -36.068)
		(end 81.5975 -36.068)
		(width 0.254)
		(layer "F.Cu")
		(net "SW_SW_R_0")
	)
	(segment
		(start 81.5975 -37.186616)
		(end 81.798668 -37.387784)
		(width 0.254)
		(layer "F.Cu")
		(net "SW_SW_R_0")
	)
	(via
		(at 81.798668 -37.387784)
		(size 0.7112)
		(drill 0.254)
		(layers "F.Cu" "B.Cu")
		(net "SW_SW_R_0")
	)
	(segment
		(start 81.798668 -37.387784)
		(end 81.1276 -36.716716)
		(width 0.254)
		(layer "B.Cu")
		(net "SW_SW_R_0")
	)
	(segment
		(start 81.1276 -36.716716)
		(end 81.1276 -35.941)
		(width 0.254)
		(layer "B.Cu")
		(net "SW_SW_R_0")
	)
	(segment
		(start 80.005936 -35.7378)
		(end 80.209136 -35.941)
		(width 0.254)
		(layer "B.Cu")
		(net "SW_SW_R_0")
	)
	(segment
		(start 79.26324 -35.7378)
		(end 80.005936 -35.7378)
		(width 0.254)
		(layer "B.Cu")
		(net "SW_SW_R_0")
	)
	(segment
		(start 80.209136 -35.941)
		(end 81.1276 -35.941)
		(width 0.254)
		(layer "B.Cu")
		(net "SW_SW_R_0")
	)
	(segment
		(start 90.678 -8.801608)
		(end 91.5035 -7.976108)
		(width 0.254)
		(layer "F.Cu")
		(net "SW_SW_L_N_0")
	)
	(segment
		(start 91.694 -9.5885)
		(end 90.678 -9.5885)
		(width 0.254)
		(layer "F.Cu")
		(net "SW_SW_L_N_0")
	)
	(segment
		(start 92.6465 -9.5885)
		(end 91.694 -9.5885)
		(width 0.254)
		(layer "F.Cu")
		(net "SW_SW_L_N_0")
	)
	(segment
		(start 90.678 -9.5885)
		(end 90.678 -8.801608)
		(width 0.254)
		(layer "F.Cu")
		(net "SW_SW_L_N_0")
	)
	(segment
		(start 91.5035 -7.493)
		(end 91.5035 -6.420612)
		(width 0.254)
		(layer "F.Cu")
		(net "SW_SW_L_N_0")
	)
	(segment
		(start 91.5035 -6.420612)
		(end 91.1606 -6.077712)
		(width 0.254)
		(layer "F.Cu")
		(net "SW_SW_L_N_0")
	)
	(segment
		(start 91.5035 -7.976108)
		(end 91.5035 -7.493)
		(width 0.254)
		(layer "F.Cu")
		(net "SW_SW_L_N_0")
	)
	(via
		(at 91.1606 -6.077712)
		(size 0.7112)
		(drill 0.254)
		(layers "F.Cu" "B.Cu")
		(net "SW_SW_L_N_0")
	)
	(via
		(at 92.6465 -9.5885)
		(size 0.5588)
		(drill 0.3048)
		(layers "F.Cu" "B.Cu")
		(net "SW_SW_L_N_0")
	)
	(segment
		(start 91.1606 -7.4676)
		(end 91.1606 -6.077712)
		(width 0.254)
		(layer "B.Cu")
		(net "SW_SW_L_N_0")
	)
	(segment
		(start 92.469716 -9.411716)
		(end 91.092274 -9.411716)
		(width 0.254)
		(layer "B.Cu")
		(net "SW_SW_L_N_0")
	)
	(segment
		(start 92.6465 -9.5885)
		(end 92.469716 -9.411716)
		(width 0.254)
		(layer "B.Cu")
		(net "SW_SW_L_N_0")
	)
	(segment
		(start 89.4715 -8.519922)
		(end 89.16416 -8.827262)
		(width 0.254)
		(layer "F.Cu")
		(net "SW_SW_L_0")
	)
	(segment
		(start 90.6145 -7.493)
		(end 89.4715 -7.493)
		(width 0.254)
		(layer "F.Cu")
		(net "SW_SW_L_0")
	)
	(segment
		(start 89.4715 -7.493)
		(end 89.4715 -8.519922)
		(width 0.254)
		(layer "F.Cu")
		(net "SW_SW_L_0")
	)
	(via
		(at 89.16416 -8.827262)
		(size 0.7112)
		(drill 0.254)
		(layers "F.Cu" "B.Cu")
		(net "SW_SW_L_0")
	)
	(segment
		(start 87.01024 -7.0358)
		(end 87.4268 -7.0358)
		(width 0.254)
		(layer "B.Cu")
		(net "SW_SW_L_0")
	)
	(segment
		(start 87.8586 -7.4676)
		(end 88.8746 -7.4676)
		(width 0.254)
		(layer "B.Cu")
		(net "SW_SW_L_0")
	)
	(segment
		(start 88.8746 -8.537702)
		(end 88.8746 -7.4676)
		(width 0.254)
		(layer "B.Cu")
		(net "SW_SW_L_0")
	)
	(segment
		(start 87.4268 -7.0358)
		(end 87.8586 -7.4676)
		(width 0.254)
		(layer "B.Cu")
		(net "SW_SW_L_0")
	)
	(segment
		(start 89.16416 -8.827262)
		(end 88.8746 -8.537702)
		(width 0.254)
		(layer "B.Cu")
		(net "SW_SW_L_0")
	)
	(via
		(at 78.613 -36.83)
		(size 0.5588)
		(drill 0.3048)
		(layers "F.Cu" "B.Cu")
		(net "PWR_EN_R_N")
	)
	(via
		(at 78.867 -46.819312)
		(size 0.7112)
		(drill 0.254)
		(layers "F.Cu" "B.Cu")
		(net "PWR_EN_R_N")
	)
	(segment
		(start 78.613 -35.7378)
		(end 78.613 -36.83)
		(width 0.254)
		(layer "B.Cu")
		(net "PWR_EN_R_N")
	)
	(segment
		(start 78.867 -46.819312)
		(end 77.534262 -46.819312)
		(width 0.254)
		(layer "B.Cu")
		(net "PWR_EN_R_N")
	)
	(segment
		(start 76.781914 -47.57166)
		(end 76.781914 -51.85283)
		(width 0.254)
		(layer "B.Cu")
		(net "PWR_EN_R_N")
	)
	(segment
		(start 77.414882 -52.485798)
		(end 81.077816 -52.485798)
		(width 0.254)
		(layer "B.Cu")
		(net "PWR_EN_R_N")
	)
	(segment
		(start 81.077816 -52.485798)
		(end 81.93024 -53.338222)
		(width 0.254)
		(layer "B.Cu")
		(net "PWR_EN_R_N")
	)
	(segment
		(start 79.853536 -45.832776)
		(end 78.867 -46.819312)
		(width 0.254)
		(layer "B.Cu")
		(net "PWR_EN_R_N")
	)
	(segment
		(start 81.93024 -53.338222)
		(end 81.93024 -54.1655)
		(width 0.254)
		(layer "B.Cu")
		(net "PWR_EN_R_N")
	)
	(segment
		(start 76.781914 -51.85283)
		(end 77.414882 -52.485798)
		(width 0.254)
		(layer "B.Cu")
		(net "PWR_EN_R_N")
	)
	(segment
		(start 80.099916 -45.832776)
		(end 79.853536 -45.832776)
		(width 0.254)
		(layer "B.Cu")
		(net "PWR_EN_R_N")
	)
	(segment
		(start 77.534262 -46.819312)
		(end 76.781914 -47.57166)
		(width 0.254)
		(layer "B.Cu")
		(net "PWR_EN_R_N")
	)
	(segment
		(start 78.191106 -37.251894)
		(end 78.191106 -46.143418)
		(width 0.254)
		(layer "In2.Cu")
		(net "PWR_EN_R_N")
	)
	(segment
		(start 78.191106 -46.143418)
		(end 78.867 -46.819312)
		(width 0.254)
		(layer "In2.Cu")
		(net "PWR_EN_R_N")
	)
	(segment
		(start 78.613 -36.83)
		(end 78.191106 -37.251894)
		(width 0.254)
		(layer "In2.Cu")
		(net "PWR_EN_R_N")
	)
	(segment
		(start 84.98586 -7.652512)
		(end 85.165692 -7.47268)
		(width 0.254)
		(layer "F.Cu")
		(net "PWR_EN_L_DELAY")
	)
	(segment
		(start 72.306434 -6.601968)
		(end 69.481954 -9.426448)
		(width 0.254)
		(layer "F.Cu")
		(net "PWR_EN_L_DELAY")
	)
	(segment
		(start 82.647028 -4.1402)
		(end 82.4738 -4.1402)
		(width 0.254)
		(layer "F.Cu")
		(net "PWR_EN_L_DELAY")
	)
	(segment
		(start 85.165692 -7.47268)
		(end 85.165692 -6.658864)
		(width 0.254)
		(layer "F.Cu")
		(net "PWR_EN_L_DELAY")
	)
	(segment
		(start 81.102454 -4.1402)
		(end 78.640686 -6.601968)
		(width 0.254)
		(layer "F.Cu")
		(net "PWR_EN_L_DELAY")
	)
	(segment
		(start 78.640686 -6.601968)
		(end 72.306434 -6.601968)
		(width 0.254)
		(layer "F.Cu")
		(net "PWR_EN_L_DELAY")
	)
	(segment
		(start 82.588608 -8.13943)
		(end 83.075526 -7.652512)
		(width 0.254)
		(layer "F.Cu")
		(net "PWR_EN_L_DELAY")
	)
	(segment
		(start 82.4738 -4.1402)
		(end 81.102454 -4.1402)
		(width 0.254)
		(layer "F.Cu")
		(net "PWR_EN_L_DELAY")
	)
	(segment
		(start 83.075526 -7.652512)
		(end 84.98586 -7.652512)
		(width 0.254)
		(layer "F.Cu")
		(net "PWR_EN_L_DELAY")
	)
	(segment
		(start 85.165692 -6.658864)
		(end 82.647028 -4.1402)
		(width 0.254)
		(layer "F.Cu")
		(net "PWR_EN_L_DELAY")
	)
	(via
		(at 82.4738 -4.1402)
		(size 0.508)
		(drill 0.254)
		(layers "F.Cu" "B.Cu")
		(net "PWR_EN_L_DELAY")
	)
	(via
		(at 83.361784 -8.188198)
		(size 0.7112)
		(drill 0.3556)
		(layers "F.Cu" "B.Cu")
		(net "PWR_EN_L_DELAY")
	)
	(via
		(at 69.481954 -9.426448)
		(size 0.508)
		(drill 0.254)
		(layers "F.Cu" "B.Cu")
		(net "PWR_EN_L_DELAY")
	)
	(segment
		(start 79.96936 -9.190228)
		(end 82.359754 -9.190228)
		(width 0.254)
		(layer "B.Cu")
		(net "PWR_EN_L_DELAY")
	)
	(segment
		(start 86.159848 -6.073394)
		(end 86.36 -6.273546)
		(width 0.254)
		(layer "B.Cu")
		(net "PWR_EN_L_DELAY")
	)
	(segment
		(start 79.71536 -9.444228)
		(end 79.96936 -9.190228)
		(width 0.254)
		(layer "B.Cu")
		(net "PWR_EN_L_DELAY")
	)
	(segment
		(start 82.4738 -4.1402)
		(end 84.406994 -6.073394)
		(width 0.254)
		(layer "B.Cu")
		(net "PWR_EN_L_DELAY")
	)
	(segment
		(start 79.71536 -10.2616)
		(end 79.71536 -9.444228)
		(width 0.254)
		(layer "B.Cu")
		(net "PWR_EN_L_DELAY")
	)
	(segment
		(start 86.106 -8.188198)
		(end 86.36 -7.934198)
		(width 0.254)
		(layer "B.Cu")
		(net "PWR_EN_L_DELAY")
	)
	(segment
		(start 68.159884 -8.104378)
		(end 69.481954 -9.426448)
		(width 0.254)
		(layer "B.Cu")
		(net "PWR_EN_L_DELAY")
	)
	(segment
		(start 86.36 -7.934198)
		(end 86.36 -7.0358)
		(width 0.254)
		(layer "B.Cu")
		(net "PWR_EN_L_DELAY")
	)
	(segment
		(start 86.36 -6.273546)
		(end 86.36 -7.0358)
		(width 0.254)
		(layer "B.Cu")
		(net "PWR_EN_L_DELAY")
	)
	(segment
		(start 68.159884 -7.574026)
		(end 68.159884 -8.104378)
		(width 0.254)
		(layer "B.Cu")
		(net "PWR_EN_L_DELAY")
	)
	(segment
		(start 82.359754 -9.190228)
		(end 83.361784 -8.188198)
		(width 0.254)
		(layer "B.Cu")
		(net "PWR_EN_L_DELAY")
	)
	(segment
		(start 84.406994 -6.073394)
		(end 86.159848 -6.073394)
		(width 0.254)
		(layer "B.Cu")
		(net "PWR_EN_L_DELAY")
	)
	(segment
		(start 83.361784 -8.188198)
		(end 86.106 -8.188198)
		(width 0.254)
		(layer "B.Cu")
		(net "PWR_EN_L_DELAY")
	)
	(segment
		(start 77.5335 -7.6835)
		(end 77.1906 -7.3406)
		(width 0.18288)
		(layer "F.Cu")
		(net "PWR_EN_L")
	)
	(segment
		(start 77.5335 -8.128)
		(end 77.5335 -7.6835)
		(width 0.18288)
		(layer "F.Cu")
		(net "PWR_EN_L")
	)
	(via
		(at 77.1906 -7.3406)
		(size 0.508)
		(drill 0.254)
		(layers "F.Cu" "B.Cu")
		(net "PWR_EN_L")
	)
	(segment
		(start 77.1906 -7.3406)
		(end 77.84084 -7.99084)
		(width 0.18288)
		(layer "B.Cu")
		(net "PWR_EN_L")
	)
	(segment
		(start 77.84084 -7.99084)
		(end 77.84084 -8.3693)
		(width 0.18288)
		(layer "B.Cu")
		(net "PWR_EN_L")
	)
	(segment
		(start 86.2965 -5.08)
		(end 86.36 -5.0165)
		(width 0.254)
		(layer "F.Cu")
		(net "PWR_EN_D_2")
	)
	(segment
		(start 86.36 -5.0165)
		(end 86.36 -3.725418)
		(width 0.254)
		(layer "F.Cu")
		(net "PWR_EN_D_2")
	)
	(via
		(at 86.36 -3.725418)
		(size 0.7112)
		(drill 0.254)
		(layers "F.Cu" "B.Cu")
		(net "PWR_EN_D_2")
	)
	(segment
		(start 85.70976 -3.979418)
		(end 85.70976 -5.1562)
		(width 0.254)
		(layer "B.Cu")
		(net "PWR_EN_D_2")
	)
	(segment
		(start 85.96376 -3.725418)
		(end 85.70976 -3.979418)
		(width 0.254)
		(layer "B.Cu")
		(net "PWR_EN_D_2")
	)
	(segment
		(start 86.36 -3.725418)
		(end 85.96376 -3.725418)
		(width 0.254)
		(layer "B.Cu")
		(net "PWR_EN_D_2")
	)
	(segment
		(start 86.36 -5.1562)
		(end 86.36 -3.725418)
		(width 0.254)
		(layer "B.Cu")
		(net "PWR_EN_D_2")
	)
	(segment
		(start 78.5495 -33.909)
		(end 78.5495 -32.369506)
		(width 0.254)
		(layer "F.Cu")
		(net "PWR_EN_D_0")
	)
	(via
		(at 78.5495 -32.369506)
		(size 0.7112)
		(drill 0.254)
		(layers "F.Cu" "B.Cu")
		(net "PWR_EN_D_0")
	)
	(segment
		(start 78.21676 -32.369506)
		(end 77.96276 -32.623506)
		(width 0.254)
		(layer "B.Cu")
		(net "PWR_EN_D_0")
	)
	(segment
		(start 78.5495 -32.385)
		(end 78.5495 -32.369506)
		(width 0.254)
		(layer "B.Cu")
		(net "PWR_EN_D_0")
	)
	(segment
		(start 78.5495 -32.369506)
		(end 78.21676 -32.369506)
		(width 0.254)
		(layer "B.Cu")
		(net "PWR_EN_D_0")
	)
	(segment
		(start 78.613 -33.8582)
		(end 78.613 -32.4485)
		(width 0.254)
		(layer "B.Cu")
		(net "PWR_EN_D_0")
	)
	(segment
		(start 78.613 -32.4485)
		(end 78.5495 -32.385)
		(width 0.254)
		(layer "B.Cu")
		(net "PWR_EN_D_0")
	)
	(segment
		(start 77.96276 -32.623506)
		(end 77.96276 -33.8582)
		(width 0.254)
		(layer "B.Cu")
		(net "PWR_EN_D_0")
	)
	(segment
		(start 119.210074 -50.949352)
		(end 119.210074 -51.74996)
		(width 0.508)
		(layer "F.Cu")
		(net "P5V_SW_R")
	)
	(segment
		(start 119.210074 -35.049968)
		(end 119.83974 -35.679634)
		(width 0.508)
		(layer "F.Cu")
		(net "P5V_SW_R")
	)
	(segment
		(start 120.480074 -51.74996)
		(end 120.480074 -52.550568)
		(width 0.508)
		(layer "F.Cu")
		(net "P5V_SW_R")
	)
	(segment
		(start 119.210074 -35.049968)
		(end 119.210074 -35.850576)
		(width 0.508)
		(layer "F.Cu")
		(net "P5V_SW_R")
	)
	(segment
		(start 120.480074 -50.949352)
		(end 120.480074 -51.74996)
		(width 0.508)
		(layer "F.Cu")
		(net "P5V_SW_R")
	)
	(segment
		(start 119.210074 -51.74996)
		(end 119.210074 -52.550568)
		(width 0.508)
		(layer "F.Cu")
		(net "P5V_SW_R")
	)
	(segment
		(start 120.480074 -35.049968)
		(end 120.480074 -35.850576)
		(width 0.508)
		(layer "F.Cu")
		(net "P5V_SW_R")
	)
	(segment
		(start 119.850408 -35.679634)
		(end 120.480074 -35.049968)
		(width 0.508)
		(layer "F.Cu")
		(net "P5V_SW_R")
	)
	(via
		(at 79.883 -47.879)
		(size 0.5588)
		(drill 0.3048)
		(layers "F.Cu" "B.Cu")
		(net "P5V_SW_R")
	)
	(via
		(at 80.899 -49.149)
		(size 0.5588)
		(drill 0.3048)
		(layers "F.Cu" "B.Cu")
		(net "P5V_SW_R")
	)
	(via
		(at 80.899 -51.689)
		(size 0.5588)
		(drill 0.3048)
		(layers "F.Cu" "B.Cu")
		(net "P5V_SW_R")
	)
	(via
		(at 79.883 -51.689)
		(size 0.5588)
		(drill 0.3048)
		(layers "F.Cu" "B.Cu")
		(net "P5V_SW_R")
	)
	(via
		(at 80.899 -47.879)
		(size 0.5588)
		(drill 0.3048)
		(layers "F.Cu" "B.Cu")
		(net "P5V_SW_R")
	)
	(via
		(at 79.883 -49.149)
		(size 0.5588)
		(drill 0.3048)
		(layers "F.Cu" "B.Cu")
		(net "P5V_SW_R")
	)
	(via
		(at 80.899 -50.419)
		(size 0.5588)
		(drill 0.3048)
		(layers "F.Cu" "B.Cu")
		(net "P5V_SW_R")
	)
	(via
		(at 79.883 -50.419)
		(size 0.5588)
		(drill 0.3048)
		(layers "F.Cu" "B.Cu")
		(net "P5V_SW_R")
	)
	(via
		(at 81.731358 -48.588422)
		(size 0.7112)
		(drill 0.3556)
		(layers "F.Cu" "B.Cu")
		(net "P5V_SW_R")
	)
	(segment
		(start 119.210074 -35.049968)
		(end 119.210074 -35.850576)
		(width 0.508)
		(layer "In2.Cu")
		(net "P5V_SW_R")
	)
	(segment
		(start 120.480074 -34.24936)
		(end 120.480074 -35.049968)
		(width 0.508)
		(layer "In2.Cu")
		(net "P5V_SW_R")
	)
	(segment
		(start 120.480074 -50.949352)
		(end 120.480074 -51.74996)
		(width 0.508)
		(layer "In2.Cu")
		(net "P5V_SW_R")
	)
	(segment
		(start 119.210074 -50.949352)
		(end 119.210074 -51.74996)
		(width 0.508)
		(layer "In2.Cu")
		(net "P5V_SW_R")
	)
	(segment
		(start 120.480074 -51.74996)
		(end 120.480074 -52.550568)
		(width 0.508)
		(layer "In2.Cu")
		(net "P5V_SW_R")
	)
	(segment
		(start 119.210074 -34.24936)
		(end 119.210074 -35.049968)
		(width 0.508)
		(layer "In2.Cu")
		(net "P5V_SW_R")
	)
	(segment
		(start 119.210074 -51.74996)
		(end 119.210074 -52.550568)
		(width 0.508)
		(layer "In2.Cu")
		(net "P5V_SW_R")
	)
	(segment
		(start 120.480074 -35.049968)
		(end 120.480074 -35.850576)
		(width 0.508)
		(layer "In2.Cu")
		(net "P5V_SW_R")
	)
	(segment
		(start 46.554898 -2.549906)
		(end 46.554898 -3.350514)
		(width 0.508)
		(layer "F.Cu")
		(net "P5V_SW_L")
	)
	(segment
		(start 45.284898 -13.850112)
		(end 45.284898 -14.65072)
		(width 0.508)
		(layer "F.Cu")
		(net "P5V_SW_L")
	)
	(segment
		(start 46.554898 -2.549906)
		(end 47.184564 -3.179572)
		(width 0.508)
		(layer "F.Cu")
		(net "P5V_SW_L")
	)
	(segment
		(start 46.554898 -13.850112)
		(end 47.184564 -14.479778)
		(width 0.508)
		(layer "F.Cu")
		(net "P5V_SW_L")
	)
	(segment
		(start 45.284898 -13.850112)
		(end 45.914564 -14.479778)
		(width 0.508)
		(layer "F.Cu")
		(net "P5V_SW_L")
	)
	(segment
		(start 45.284898 -2.549906)
		(end 45.914564 -3.179572)
		(width 0.508)
		(layer "F.Cu")
		(net "P5V_SW_L")
	)
	(segment
		(start 46.554898 -13.850112)
		(end 46.554898 -14.65072)
		(width 0.508)
		(layer "F.Cu")
		(net "P5V_SW_L")
	)
	(segment
		(start 45.284898 -2.549906)
		(end 45.284898 -3.350514)
		(width 0.508)
		(layer "F.Cu")
		(net "P5V_SW_L")
	)
	(via
		(at 67.855592 -10.00633)
		(size 0.7112)
		(drill 0.3556)
		(layers "F.Cu" "B.Cu")
		(net "P5V_SW_L")
	)
	(via
		(at 65.562226 -13.287756)
		(size 0.5588)
		(drill 0.3048)
		(layers "F.Cu" "B.Cu")
		(net "P5V_SW_L")
	)
	(via
		(at 66.476626 -13.287756)
		(size 0.5588)
		(drill 0.3048)
		(layers "F.Cu" "B.Cu")
		(net "P5V_SW_L")
	)
	(via
		(at 66.528696 -9.77392)
		(size 0.5588)
		(drill 0.3048)
		(layers "F.Cu" "B.Cu")
		(net "P5V_SW_L")
	)
	(via
		(at 66.490596 -12.320524)
		(size 0.5588)
		(drill 0.3048)
		(layers "F.Cu" "B.Cu")
		(net "P5V_SW_L")
	)
	(via
		(at 66.50736 -10.733786)
		(size 0.5588)
		(drill 0.3048)
		(layers "F.Cu" "B.Cu")
		(net "P5V_SW_L")
	)
	(via
		(at 65.576196 -12.320524)
		(size 0.5588)
		(drill 0.3048)
		(layers "F.Cu" "B.Cu")
		(net "P5V_SW_L")
	)
	(via
		(at 65.614296 -9.77392)
		(size 0.5588)
		(drill 0.3048)
		(layers "F.Cu" "B.Cu")
		(net "P5V_SW_L")
	)
	(via
		(at 65.59296 -10.733786)
		(size 0.5588)
		(drill 0.3048)
		(layers "F.Cu" "B.Cu")
		(net "P5V_SW_L")
	)
	(segment
		(start 45.284898 -13.049504)
		(end 45.284898 -13.850112)
		(width 0.508)
		(layer "In2.Cu")
		(net "P5V_SW_L")
	)
	(segment
		(start 46.554898 -2.549906)
		(end 46.554898 -3.350514)
		(width 0.508)
		(layer "In2.Cu")
		(net "P5V_SW_L")
	)
	(segment
		(start 45.284898 -13.850112)
		(end 45.284898 -14.65072)
		(width 0.508)
		(layer "In2.Cu")
		(net "P5V_SW_L")
	)
	(segment
		(start 46.554898 -13.049504)
		(end 46.554898 -13.850112)
		(width 0.508)
		(layer "In2.Cu")
		(net "P5V_SW_L")
	)
	(segment
		(start 45.284898 -2.549906)
		(end 45.284898 -3.350514)
		(width 0.508)
		(layer "In2.Cu")
		(net "P5V_SW_L")
	)
	(segment
		(start 46.554898 -2.549906)
		(end 47.184564 -3.179572)
		(width 0.508)
		(layer "In2.Cu")
		(net "P5V_SW_L")
	)
	(segment
		(start 45.284898 -2.549906)
		(end 45.914564 -3.179572)
		(width 0.508)
		(layer "In2.Cu")
		(net "P5V_SW_L")
	)
	(segment
		(start 46.554898 -13.850112)
		(end 46.554898 -14.65072)
		(width 0.508)
		(layer "In2.Cu")
		(net "P5V_SW_L")
	)
	(segment
		(start 126.830074 -51.74996)
		(end 126.830074 -52.550568)
		(width 0.508)
		(layer "F.Cu")
		(net "P12V_SW_R")
	)
	(segment
		(start 128.100074 -50.949352)
		(end 128.100074 -51.74996)
		(width 0.508)
		(layer "F.Cu")
		(net "P12V_SW_R")
	)
	(segment
		(start 128.100074 -35.049968)
		(end 128.72974 -35.679634)
		(width 0.508)
		(layer "F.Cu")
		(net "P12V_SW_R")
	)
	(segment
		(start 128.100074 -35.049968)
		(end 128.100074 -35.850576)
		(width 0.508)
		(layer "F.Cu")
		(net "P12V_SW_R")
	)
	(segment
		(start 128.100074 -51.74996)
		(end 128.900682 -51.74996)
		(width 0.508)
		(layer "F.Cu")
		(net "P12V_SW_R")
	)
	(segment
		(start 126.830074 -35.049968)
		(end 127.45974 -35.679634)
		(width 0.508)
		(layer "F.Cu")
		(net "P12V_SW_R")
	)
	(segment
		(start 126.830074 -50.949352)
		(end 126.830074 -51.74996)
		(width 0.508)
		(layer "F.Cu")
		(net "P12V_SW_R")
	)
	(segment
		(start 126.830074 -35.049968)
		(end 127.188976 -35.865054)
		(width 0.508)
		(layer "F.Cu")
		(net "P12V_SW_R")
	)
	(segment
		(start 128.100074 -51.74996)
		(end 128.100074 -52.550568)
		(width 0.508)
		(layer "F.Cu")
		(net "P12V_SW_R")
	)
	(via
		(at 81.364328 -40.645588)
		(size 0.5588)
		(drill 0.3048)
		(layers "F.Cu" "B.Cu")
		(net "P12V_SW_R")
	)
	(via
		(at 76.2 -41.8846)
		(size 0.5588)
		(drill 0.3048)
		(layers "F.Cu" "B.Cu")
		(net "P12V_SW_R")
	)
	(via
		(at 80.348328 -40.645588)
		(size 0.5588)
		(drill 0.3048)
		(layers "F.Cu" "B.Cu")
		(net "P12V_SW_R")
	)
	(via
		(at 76.962 -36.6776)
		(size 0.5588)
		(drill 0.3048)
		(layers "F.Cu" "B.Cu")
		(net "P12V_SW_R")
	)
	(via
		(at 77.1144 -41.8592)
		(size 0.5588)
		(drill 0.3048)
		(layers "F.Cu" "B.Cu")
		(net "P12V_SW_R")
	)
	(via
		(at 81.364328 -39.539672)
		(size 0.5588)
		(drill 0.3048)
		(layers "F.Cu" "B.Cu")
		(net "P12V_SW_R")
	)
	(via
		(at 80.348328 -41.788588)
		(size 0.5588)
		(drill 0.3048)
		(layers "F.Cu" "B.Cu")
		(net "P12V_SW_R")
	)
	(via
		(at 80.348328 -39.539672)
		(size 0.5588)
		(drill 0.3048)
		(layers "F.Cu" "B.Cu")
		(net "P12V_SW_R")
	)
	(via
		(at 76.0222 -36.703)
		(size 0.5588)
		(drill 0.3048)
		(layers "F.Cu" "B.Cu")
		(net "P12V_SW_R")
	)
	(via
		(at 78.867 -38.608)
		(size 0.7112)
		(drill 0.3556)
		(layers "F.Cu" "B.Cu")
		(net "P12V_SW_R")
	)
	(via
		(at 81.391252 -38.464744)
		(size 0.5588)
		(drill 0.3048)
		(layers "F.Cu" "B.Cu")
		(net "P12V_SW_R")
	)
	(via
		(at 81.364328 -41.788588)
		(size 0.5588)
		(drill 0.3048)
		(layers "F.Cu" "B.Cu")
		(net "P12V_SW_R")
	)
	(via
		(at 80.375252 -38.464744)
		(size 0.5588)
		(drill 0.3048)
		(layers "F.Cu" "B.Cu")
		(net "P12V_SW_R")
	)
	(segment
		(start 128.100074 -51.74996)
		(end 128.100074 -52.550568)
		(width 0.508)
		(layer "In3.Cu")
		(net "P12V_SW_R")
	)
	(segment
		(start 126.830074 -50.949352)
		(end 126.830074 -51.74996)
		(width 0.508)
		(layer "In3.Cu")
		(net "P12V_SW_R")
	)
	(segment
		(start 128.100074 -50.949352)
		(end 128.100074 -51.74996)
		(width 0.508)
		(layer "In3.Cu")
		(net "P12V_SW_R")
	)
	(segment
		(start 128.100074 -51.74996)
		(end 128.900682 -51.74996)
		(width 0.508)
		(layer "In3.Cu")
		(net "P12V_SW_R")
	)
	(segment
		(start 128.100074 -35.049968)
		(end 128.100074 -35.850576)
		(width 0.508)
		(layer "In3.Cu")
		(net "P12V_SW_R")
	)
	(segment
		(start 126.830074 -51.74996)
		(end 126.830074 -52.550568)
		(width 0.508)
		(layer "In3.Cu")
		(net "P12V_SW_R")
	)
	(segment
		(start 126.830074 -35.049968)
		(end 126.830074 -35.850576)
		(width 0.508)
		(layer "In3.Cu")
		(net "P12V_SW_R")
	)
	(segment
		(start 126.830074 -35.049968)
		(end 127.45974 -35.679634)
		(width 0.508)
		(layer "In3.Cu")
		(net "P12V_SW_R")
	)
	(segment
		(start 128.100074 -35.049968)
		(end 128.900682 -35.049968)
		(width 0.508)
		(layer "In3.Cu")
		(net "P12V_SW_R")
	)
	(segment
		(start 54.174898 -13.850112)
		(end 54.975506 -13.850112)
		(width 0.508)
		(layer "F.Cu")
		(net "P12V_SW_L")
	)
	(segment
		(start 54.174898 -13.049504)
		(end 54.174898 -13.850112)
		(width 0.508)
		(layer "F.Cu")
		(net "P12V_SW_L")
	)
	(segment
		(start 52.904898 -2.549906)
		(end 52.904898 -3.350514)
		(width 0.508)
		(layer "F.Cu")
		(net "P12V_SW_L")
	)
	(segment
		(start 54.174898 -13.850112)
		(end 54.174898 -14.65072)
		(width 0.508)
		(layer "F.Cu")
		(net "P12V_SW_L")
	)
	(segment
		(start 54.174898 -2.549906)
		(end 54.975506 -2.549906)
		(width 0.508)
		(layer "F.Cu")
		(net "P12V_SW_L")
	)
	(segment
		(start 54.174898 -2.549906)
		(end 54.174898 -3.350514)
		(width 0.508)
		(layer "F.Cu")
		(net "P12V_SW_L")
	)
	(segment
		(start 52.904898 -13.850112)
		(end 52.904898 -14.65072)
		(width 0.508)
		(layer "F.Cu")
		(net "P12V_SW_L")
	)
	(segment
		(start 52.904898 -13.049504)
		(end 52.904898 -13.850112)
		(width 0.508)
		(layer "F.Cu")
		(net "P12V_SW_L")
	)
	(segment
		(start 52.904898 -2.549906)
		(end 53.534564 -3.179572)
		(width 0.508)
		(layer "F.Cu")
		(net "P12V_SW_L")
	)
	(via
		(at 84.47151 -12.453112)
		(size 0.5588)
		(drill 0.3048)
		(layers "F.Cu" "B.Cu")
		(net "P12V_SW_L")
	)
	(via
		(at 83.419696 -11.533632)
		(size 0.5588)
		(drill 0.3048)
		(layers "F.Cu" "B.Cu")
		(net "P12V_SW_L")
	)
	(via
		(at 83.45551 -12.453112)
		(size 0.5588)
		(drill 0.3048)
		(layers "F.Cu" "B.Cu")
		(net "P12V_SW_L")
	)
	(via
		(at 84.483956 -13.376402)
		(size 0.5588)
		(drill 0.3048)
		(layers "F.Cu" "B.Cu")
		(net "P12V_SW_L")
	)
	(via
		(at 83.467956 -13.376402)
		(size 0.5588)
		(drill 0.3048)
		(layers "F.Cu" "B.Cu")
		(net "P12V_SW_L")
	)
	(via
		(at 85.577934 -13.178536)
		(size 0.7112)
		(drill 0.3556)
		(layers "F.Cu" "B.Cu")
		(net "P12V_SW_L")
	)
	(via
		(at 84.457032 -10.573766)
		(size 0.5588)
		(drill 0.3048)
		(layers "F.Cu" "B.Cu")
		(net "P12V_SW_L")
	)
	(via
		(at 84.435696 -11.533632)
		(size 0.5588)
		(drill 0.3048)
		(layers "F.Cu" "B.Cu")
		(net "P12V_SW_L")
	)
	(via
		(at 83.441032 -10.573766)
		(size 0.5588)
		(drill 0.3048)
		(layers "F.Cu" "B.Cu")
		(net "P12V_SW_L")
	)
	(segment
		(start 54.174898 -13.850112)
		(end 54.174898 -14.65072)
		(width 0.508)
		(layer "In3.Cu")
		(net "P12V_SW_L")
	)
	(segment
		(start 54.174898 -13.850112)
		(end 54.975506 -13.850112)
		(width 0.508)
		(layer "In3.Cu")
		(net "P12V_SW_L")
	)
	(segment
		(start 54.174898 -2.549906)
		(end 54.975506 -2.549906)
		(width 0.508)
		(layer "In3.Cu")
		(net "P12V_SW_L")
	)
	(segment
		(start 54.174898 -13.049504)
		(end 54.174898 -13.850112)
		(width 0.508)
		(layer "In3.Cu")
		(net "P12V_SW_L")
	)
	(segment
		(start 52.904898 -13.049504)
		(end 52.904898 -13.850112)
		(width 0.508)
		(layer "In3.Cu")
		(net "P12V_SW_L")
	)
	(segment
		(start 52.904898 -2.549906)
		(end 52.904898 -3.350514)
		(width 0.508)
		(layer "In3.Cu")
		(net "P12V_SW_L")
	)
	(segment
		(start 52.275232 -1.92024)
		(end 52.904898 -2.549906)
		(width 0.508)
		(layer "In3.Cu")
		(net "P12V_SW_L")
	)
	(segment
		(start 52.904898 -13.850112)
		(end 52.904898 -14.65072)
		(width 0.508)
		(layer "In3.Cu")
		(net "P12V_SW_L")
	)
	(segment
		(start 54.174898 -2.549906)
		(end 54.174898 -3.350514)
		(width 0.508)
		(layer "In3.Cu")
		(net "P12V_SW_L")
	)
	(via
		(at 83.668616 -25.70861)
		(size 0.508)
		(drill 0.254)
		(layers "F.Cu" "B.Cu")
		(net "HBA_MB_TX_P3")
	)
	(segment
		(start 83.381596 -24.234648)
		(end 82.90941 -23.762462)
		(width 0.21336)
		(layer "B.Cu")
		(net "HBA_MB_TX_P3")
	)
	(segment
		(start 83.381596 -25.42159)
		(end 83.381596 -24.234648)
		(width 0.21336)
		(layer "B.Cu")
		(net "HBA_MB_TX_P3")
	)
	(segment
		(start 82.90941 -23.762462)
		(end 82.418936 -23.762462)
		(width 0.21336)
		(layer "B.Cu")
		(net "HBA_MB_TX_P3")
	)
	(segment
		(start 82.236564 -23.58009)
		(end 81.814924 -23.58009)
		(width 0.21336)
		(layer "B.Cu")
		(net "HBA_MB_TX_P3")
	)
	(segment
		(start 83.668616 -25.70861)
		(end 83.381596 -25.42159)
		(width 0.21336)
		(layer "B.Cu")
		(net "HBA_MB_TX_P3")
	)
	(segment
		(start 82.418936 -23.762462)
		(end 82.236564 -23.58009)
		(width 0.21336)
		(layer "B.Cu")
		(net "HBA_MB_TX_P3")
	)
	(segment
		(start 20.319746 -13.831316)
		(end 23.38197 -15.858236)
		(width 0.14224)
		(layer "In2.Cu")
		(net "HBA_MB_TX_P3")
	)
	(segment
		(start 19.00682 -11.23823)
		(end 19.186398 -12.11834)
		(width 0.14224)
		(layer "In2.Cu")
		(net "HBA_MB_TX_P3")
	)
	(segment
		(start 56.128412 -20.446746)
		(end 78.319376 -24.961596)
		(width 0.14224)
		(layer "In2.Cu")
		(net "HBA_MB_TX_P3")
	)
	(segment
		(start 83.462876 -25.70861)
		(end 83.668616 -25.70861)
		(width 0.14224)
		(layer "In2.Cu")
		(net "HBA_MB_TX_P3")
	)
	(segment
		(start 19.186398 -12.11834)
		(end 20.319746 -13.831316)
		(width 0.14224)
		(layer "In2.Cu")
		(net "HBA_MB_TX_P3")
	)
	(segment
		(start 35.74288 -16.006318)
		(end 55.489348 -20.023836)
		(width 0.14224)
		(layer "In2.Cu")
		(net "HBA_MB_TX_P3")
	)
	(segment
		(start 33.43275 -16.476472)
		(end 35.74288 -16.006318)
		(width 0.14224)
		(layer "In2.Cu")
		(net "HBA_MB_TX_P3")
	)
	(segment
		(start 82.550762 -26.982674)
		(end 83.060032 -26.645616)
		(width 0.14224)
		(layer "In2.Cu")
		(net "HBA_MB_TX_P3")
	)
	(segment
		(start 23.38197 -15.858236)
		(end 28.201874 -16.838422)
		(width 0.14224)
		(layer "In2.Cu")
		(net "HBA_MB_TX_P3")
	)
	(segment
		(start 83.060032 -26.645616)
		(end 83.27136 -26.326084)
		(width 0.14224)
		(layer "In2.Cu")
		(net "HBA_MB_TX_P3")
	)
	(segment
		(start 23.694898 -2.549906)
		(end 24.16429 -3.019298)
		(width 0.14224)
		(layer "In2.Cu")
		(net "HBA_MB_TX_P3")
	)
	(segment
		(start 83.27136 -26.326084)
		(end 83.320636 -26.084276)
		(width 0.14224)
		(layer "In2.Cu")
		(net "HBA_MB_TX_P3")
	)
	(segment
		(start 83.320636 -26.084276)
		(end 83.320636 -25.85085)
		(width 0.14224)
		(layer "In2.Cu")
		(net "HBA_MB_TX_P3")
	)
	(segment
		(start 28.201874 -16.838422)
		(end 31.707074 -16.12519)
		(width 0.14224)
		(layer "In2.Cu")
		(net "HBA_MB_TX_P3")
	)
	(segment
		(start 24.16429 -3.019298)
		(end 24.16429 -3.29946)
		(width 0.14224)
		(layer "In2.Cu")
		(net "HBA_MB_TX_P3")
	)
	(segment
		(start 55.489348 -20.023836)
		(end 56.128412 -20.446746)
		(width 0.14224)
		(layer "In2.Cu")
		(net "HBA_MB_TX_P3")
	)
	(segment
		(start 83.320636 -25.85085)
		(end 83.462876 -25.70861)
		(width 0.14224)
		(layer "In2.Cu")
		(net "HBA_MB_TX_P3")
	)
	(segment
		(start 31.707074 -16.12519)
		(end 33.43275 -16.476472)
		(width 0.14224)
		(layer "In2.Cu")
		(net "HBA_MB_TX_P3")
	)
	(segment
		(start 24.16429 -3.29946)
		(end 23.361396 -4.102354)
		(width 0.14224)
		(layer "In2.Cu")
		(net "HBA_MB_TX_P3")
	)
	(segment
		(start 78.319376 -24.961596)
		(end 81.335626 -26.958036)
		(width 0.14224)
		(layer "In2.Cu")
		(net "HBA_MB_TX_P3")
	)
	(segment
		(start 23.361396 -4.102354)
		(end 19.169888 -10.432796)
		(width 0.14224)
		(layer "In2.Cu")
		(net "HBA_MB_TX_P3")
	)
	(segment
		(start 82.003392 -27.093418)
		(end 82.550762 -26.982674)
		(width 0.14224)
		(layer "In2.Cu")
		(net "HBA_MB_TX_P3")
	)
	(segment
		(start 19.169888 -10.432796)
		(end 19.00682 -11.23823)
		(width 0.14224)
		(layer "In2.Cu")
		(net "HBA_MB_TX_P3")
	)
	(segment
		(start 81.335626 -26.958036)
		(end 82.003392 -27.093418)
		(width 0.14224)
		(layer "In2.Cu")
		(net "HBA_MB_TX_P3")
	)
	(via
		(at 86.581996 -23.446994)
		(size 0.508)
		(drill 0.254)
		(layers "F.Cu" "B.Cu")
		(net "HBA_MB_TX_P2")
	)
	(segment
		(start 85.118448 -23.734014)
		(end 84.964524 -23.58009)
		(width 0.21336)
		(layer "B.Cu")
		(net "HBA_MB_TX_P2")
	)
	(segment
		(start 86.581996 -23.446994)
		(end 86.294976 -23.734014)
		(width 0.21336)
		(layer "B.Cu")
		(net "HBA_MB_TX_P2")
	)
	(segment
		(start 86.294976 -23.734014)
		(end 85.118448 -23.734014)
		(width 0.21336)
		(layer "B.Cu")
		(net "HBA_MB_TX_P2")
	)
	(segment
		(start 84.964524 -23.58009)
		(end 84.514944 -23.58009)
		(width 0.21336)
		(layer "B.Cu")
		(net "HBA_MB_TX_P2")
	)
	(segment
		(start 86.495636 -19.394678)
		(end 87.512398 -20.067778)
		(width 0.14224)
		(layer "In2.Cu")
		(net "HBA_MB_TX_P2")
	)
	(segment
		(start 77.587094 -19.328638)
		(end 81.878678 -18.45564)
		(width 0.14224)
		(layer "In2.Cu")
		(net "HBA_MB_TX_P2")
	)
	(segment
		(start 24.20747 -14.717014)
		(end 24.484584 -15.056358)
		(width 0.14224)
		(layer "In2.Cu")
		(net "HBA_MB_TX_P2")
	)
	(segment
		(start 31.462726 -15.078456)
		(end 33.223454 -15.436596)
		(width 0.14224)
		(layer "In2.Cu")
		(net "HBA_MB_TX_P2")
	)
	(segment
		(start 35.795458 -14.91361)
		(end 54.326536 -18.68297)
		(width 0.14224)
		(layer "In2.Cu")
		(net "HBA_MB_TX_P2")
	)
	(segment
		(start 23.694898 -13.850112)
		(end 24.20747 -14.362684)
		(width 0.14224)
		(layer "In2.Cu")
		(net "HBA_MB_TX_P2")
	)
	(segment
		(start 85.449664 -19.363436)
		(end 85.867748 -19.448526)
		(width 0.14224)
		(layer "In2.Cu")
		(net "HBA_MB_TX_P2")
	)
	(segment
		(start 85.31098 -19.153632)
		(end 85.449664 -19.363436)
		(width 0.14224)
		(layer "In2.Cu")
		(net "HBA_MB_TX_P2")
	)
	(segment
		(start 24.20747 -14.362684)
		(end 24.20747 -14.717014)
		(width 0.14224)
		(layer "In2.Cu")
		(net "HBA_MB_TX_P2")
	)
	(segment
		(start 86.077552 -19.309588)
		(end 86.495636 -19.394678)
		(width 0.14224)
		(layer "In2.Cu")
		(net "HBA_MB_TX_P2")
	)
	(segment
		(start 33.223454 -15.436596)
		(end 35.795458 -14.91361)
		(width 0.14224)
		(layer "In2.Cu")
		(net "HBA_MB_TX_P2")
	)
	(segment
		(start 84.12607 -18.912586)
		(end 84.265008 -19.12239)
		(width 0.14224)
		(layer "In2.Cu")
		(net "HBA_MB_TX_P2")
	)
	(segment
		(start 54.326536 -18.68297)
		(end 64.36995 -16.640048)
		(width 0.14224)
		(layer "In2.Cu")
		(net "HBA_MB_TX_P2")
	)
	(segment
		(start 84.265008 -19.12239)
		(end 84.683092 -19.20748)
		(width 0.14224)
		(layer "In2.Cu")
		(net "HBA_MB_TX_P2")
	)
	(segment
		(start 28.031694 -15.776702)
		(end 31.462726 -15.078456)
		(width 0.14224)
		(layer "In2.Cu")
		(net "HBA_MB_TX_P2")
	)
	(segment
		(start 83.498182 -18.966434)
		(end 83.707986 -18.827496)
		(width 0.14224)
		(layer "In2.Cu")
		(net "HBA_MB_TX_P2")
	)
	(segment
		(start 87.512398 -20.067778)
		(end 88.216486 -21.13153)
		(width 0.14224)
		(layer "In2.Cu")
		(net "HBA_MB_TX_P2")
	)
	(segment
		(start 83.080098 -18.881344)
		(end 83.498182 -18.966434)
		(width 0.14224)
		(layer "In2.Cu")
		(net "HBA_MB_TX_P2")
	)
	(segment
		(start 81.878678 -18.45564)
		(end 82.94116 -18.671794)
		(width 0.14224)
		(layer "In2.Cu")
		(net "HBA_MB_TX_P2")
	)
	(segment
		(start 64.36995 -16.640048)
		(end 64.36995 -16.639794)
		(width 0.14224)
		(layer "In2.Cu")
		(net "HBA_MB_TX_P2")
	)
	(segment
		(start 83.707986 -18.827496)
		(end 84.12607 -18.912586)
		(width 0.14224)
		(layer "In2.Cu")
		(net "HBA_MB_TX_P2")
	)
	(segment
		(start 88.250268 -23.395432)
		(end 87.602314 -23.824692)
		(width 0.14224)
		(layer "In2.Cu")
		(net "HBA_MB_TX_P2")
	)
	(segment
		(start 82.94116 -18.671794)
		(end 83.080098 -18.881344)
		(width 0.14224)
		(layer "In2.Cu")
		(net "HBA_MB_TX_P2")
	)
	(segment
		(start 64.36995 -16.639794)
		(end 77.587094 -19.328638)
		(width 0.14224)
		(layer "In2.Cu")
		(net "HBA_MB_TX_P2")
	)
	(segment
		(start 24.484584 -15.056358)
		(end 28.031694 -15.776702)
		(width 0.14224)
		(layer "In2.Cu")
		(net "HBA_MB_TX_P2")
	)
	(segment
		(start 84.683092 -19.20748)
		(end 84.892896 -19.068542)
		(width 0.14224)
		(layer "In2.Cu")
		(net "HBA_MB_TX_P2")
	)
	(segment
		(start 88.464136 -22.347174)
		(end 88.250268 -23.395432)
		(width 0.14224)
		(layer "In2.Cu")
		(net "HBA_MB_TX_P2")
	)
	(segment
		(start 86.959694 -23.824692)
		(end 86.581996 -23.446994)
		(width 0.14224)
		(layer "In2.Cu")
		(net "HBA_MB_TX_P2")
	)
	(segment
		(start 85.867748 -19.448526)
		(end 86.077552 -19.309588)
		(width 0.14224)
		(layer "In2.Cu")
		(net "HBA_MB_TX_P2")
	)
	(segment
		(start 87.602314 -23.824692)
		(end 86.959694 -23.824692)
		(width 0.14224)
		(layer "In2.Cu")
		(net "HBA_MB_TX_P2")
	)
	(segment
		(start 88.216486 -21.13153)
		(end 88.464136 -22.347174)
		(width 0.14224)
		(layer "In2.Cu")
		(net "HBA_MB_TX_P2")
	)
	(segment
		(start 84.892896 -19.068542)
		(end 85.31098 -19.153632)
		(width 0.14224)
		(layer "In2.Cu")
		(net "HBA_MB_TX_P2")
	)
	(segment
		(start 88.51265 -20.857464)
		(end 88.195658 -20.92198)
		(width 0.21336)
		(layer "F.Cu")
		(net "HBA_MB_TX_P1")
	)
	(segment
		(start 89.961466 -21.816314)
		(end 89.644474 -21.88083)
		(width 0.21336)
		(layer "F.Cu")
		(net "HBA_MB_TX_P1")
	)
	(segment
		(start 83.845654 -19.214338)
		(end 83.218528 -19.08683)
		(width 0.21336)
		(layer "F.Cu")
		(net "HBA_MB_TX_P1")
	)
	(segment
		(start 83.086956 -21.324062)
		(end 83.086956 -21.166836)
		(width 0.21336)
		(layer "F.Cu")
		(net "HBA_MB_TX_P1")
	)
	(segment
		(start 95.956374 -30.420564)
		(end 94.330774 -27.964892)
		(width 0.21336)
		(layer "F.Cu")
		(net "HBA_MB_TX_P1")
	)
	(segment
		(start 82.41284 -18.689574)
		(end 81.694274 -19.165316)
		(width 0.21336)
		(layer "F.Cu")
		(net "HBA_MB_TX_P1")
	)
	(segment
		(start 96.245426 -31.27121)
		(end 95.892112 -30.737556)
		(width 0.21336)
		(layer "F.Cu")
		(net "HBA_MB_TX_P1")
	)
	(segment
		(start 86.49081 -19.519138)
		(end 85.817964 -19.382232)
		(width 0.21336)
		(layer "F.Cu")
		(net "HBA_MB_TX_P1")
	)
	(segment
		(start 89.046304 -21.210778)
		(end 88.51265 -20.857464)
		(width 0.21336)
		(layer "F.Cu")
		(net "HBA_MB_TX_P1")
	)
	(segment
		(start 98.175318 -34.088832)
		(end 98.082608 -33.632648)
		(width 0.21336)
		(layer "F.Cu")
		(net "HBA_MB_TX_P1")
	)
	(segment
		(start 92.096082 -25.002744)
		(end 91.742768 -24.46909)
		(width 0.21336)
		(layer "F.Cu")
		(net "HBA_MB_TX_P1")
	)
	(segment
		(start 96.850962 -32.186372)
		(end 96.915478 -31.86938)
		(width 0.21336)
		(layer "F.Cu")
		(net "HBA_MB_TX_P1")
	)
	(segment
		(start 93.37167 -26.516076)
		(end 93.054932 -26.45156)
		(width 0.21336)
		(layer "F.Cu")
		(net "HBA_MB_TX_P1")
	)
	(segment
		(start 85.548216 -19.560794)
		(end 84.92109 -19.433286)
		(width 0.21336)
		(layer "F.Cu")
		(net "HBA_MB_TX_P1")
	)
	(segment
		(start 87.597488 -20.251674)
		(end 86.49081 -19.519138)
		(width 0.21336)
		(layer "F.Cu")
		(net "HBA_MB_TX_P1")
	)
	(segment
		(start 89.11082 -21.527516)
		(end 89.046304 -21.210778)
		(width 0.21336)
		(layer "F.Cu")
		(net "HBA_MB_TX_P1")
	)
	(segment
		(start 93.724984 -27.04973)
		(end 93.37167 -26.516076)
		(width 0.21336)
		(layer "F.Cu")
		(net "HBA_MB_TX_P1")
	)
	(segment
		(start 92.41282 -25.06726)
		(end 92.096082 -25.002744)
		(width 0.21336)
		(layer "F.Cu")
		(net "HBA_MB_TX_P1")
	)
	(segment
		(start 98.175318 -34.494724)
		(end 98.175318 -34.088832)
		(width 0.21336)
		(layer "F.Cu")
		(net "HBA_MB_TX_P1")
	)
	(segment
		(start 81.390236 -20.657312)
		(end 81.885536 -21.405088)
		(width 0.21336)
		(layer "F.Cu")
		(net "HBA_MB_TX_P1")
	)
	(segment
		(start 85.817964 -19.382232)
		(end 85.548216 -19.560794)
		(width 0.21336)
		(layer "F.Cu")
		(net "HBA_MB_TX_P1")
	)
	(segment
		(start 91.45397 -23.618444)
		(end 91.137232 -23.553928)
		(width 0.21336)
		(layer "F.Cu")
		(net "HBA_MB_TX_P1")
	)
	(segment
		(start 88.195658 -20.92198)
		(end 87.662004 -20.568666)
		(width 0.21336)
		(layer "F.Cu")
		(net "HBA_MB_TX_P1")
	)
	(segment
		(start 94.330774 -27.964892)
		(end 94.013782 -27.900376)
		(width 0.21336)
		(layer "F.Cu")
		(net "HBA_MB_TX_P1")
	)
	(segment
		(start 82.535268 -21.537422)
		(end 82.873596 -21.537422)
		(width 0.21336)
		(layer "F.Cu")
		(net "HBA_MB_TX_P1")
	)
	(segment
		(start 96.915478 -31.86938)
		(end 96.562164 -31.335726)
		(width 0.21336)
		(layer "F.Cu")
		(net "HBA_MB_TX_P1")
	)
	(segment
		(start 97.620074 -35.049968)
		(end 98.175318 -34.494724)
		(width 0.21336)
		(layer "F.Cu")
		(net "HBA_MB_TX_P1")
	)
	(segment
		(start 93.660468 -27.366722)
		(end 93.724984 -27.04973)
		(width 0.21336)
		(layer "F.Cu")
		(net "HBA_MB_TX_P1")
	)
	(segment
		(start 91.742768 -24.46909)
		(end 91.807284 -24.152098)
		(width 0.21336)
		(layer "F.Cu")
		(net "HBA_MB_TX_P1")
	)
	(segment
		(start 84.742528 -19.163538)
		(end 84.115402 -19.03603)
		(width 0.21336)
		(layer "F.Cu")
		(net "HBA_MB_TX_P1")
	)
	(segment
		(start 87.662004 -20.568666)
		(end 87.597488 -20.251674)
		(width 0.21336)
		(layer "F.Cu")
		(net "HBA_MB_TX_P1")
	)
	(segment
		(start 81.885536 -21.405088)
		(end 82.535268 -21.537422)
		(width 0.21336)
		(layer "F.Cu")
		(net "HBA_MB_TX_P1")
	)
	(segment
		(start 94.013782 -27.900376)
		(end 93.660468 -27.366722)
		(width 0.21336)
		(layer "F.Cu")
		(net "HBA_MB_TX_P1")
	)
	(segment
		(start 90.783918 -23.020274)
		(end 90.848434 -22.703282)
		(width 0.21336)
		(layer "F.Cu")
		(net "HBA_MB_TX_P1")
	)
	(segment
		(start 81.694274 -19.165316)
		(end 81.390236 -20.657312)
		(width 0.21336)
		(layer "F.Cu")
		(net "HBA_MB_TX_P1")
	)
	(segment
		(start 92.701618 -25.917906)
		(end 92.766134 -25.600914)
		(width 0.21336)
		(layer "F.Cu")
		(net "HBA_MB_TX_P1")
	)
	(segment
		(start 98.082608 -33.632648)
		(end 97.521268 -32.784542)
		(width 0.21336)
		(layer "F.Cu")
		(net "HBA_MB_TX_P1")
	)
	(segment
		(start 96.562164 -31.335726)
		(end 96.245426 -31.27121)
		(width 0.21336)
		(layer "F.Cu")
		(net "HBA_MB_TX_P1")
	)
	(segment
		(start 84.115402 -19.03603)
		(end 83.845654 -19.214338)
		(width 0.21336)
		(layer "F.Cu")
		(net "HBA_MB_TX_P1")
	)
	(segment
		(start 91.807284 -24.152098)
		(end 91.45397 -23.618444)
		(width 0.21336)
		(layer "F.Cu")
		(net "HBA_MB_TX_P1")
	)
	(segment
		(start 89.644474 -21.88083)
		(end 89.11082 -21.527516)
		(width 0.21336)
		(layer "F.Cu")
		(net "HBA_MB_TX_P1")
	)
	(segment
		(start 82.873596 -21.537422)
		(end 83.086956 -21.324062)
		(width 0.21336)
		(layer "F.Cu")
		(net "HBA_MB_TX_P1")
	)
	(segment
		(start 90.49512 -22.169628)
		(end 89.961466 -21.816314)
		(width 0.21336)
		(layer "F.Cu")
		(net "HBA_MB_TX_P1")
	)
	(segment
		(start 95.892112 -30.737556)
		(end 95.956374 -30.420564)
		(width 0.21336)
		(layer "F.Cu")
		(net "HBA_MB_TX_P1")
	)
	(segment
		(start 97.521268 -32.784542)
		(end 97.521014 -32.784542)
		(width 0.21336)
		(layer "F.Cu")
		(net "HBA_MB_TX_P1")
	)
	(segment
		(start 91.137232 -23.553928)
		(end 90.783918 -23.020274)
		(width 0.21336)
		(layer "F.Cu")
		(net "HBA_MB_TX_P1")
	)
	(segment
		(start 83.218528 -19.08683)
		(end 83.039966 -18.817082)
		(width 0.21336)
		(layer "F.Cu")
		(net "HBA_MB_TX_P1")
	)
	(segment
		(start 92.766134 -25.600914)
		(end 92.41282 -25.06726)
		(width 0.21336)
		(layer "F.Cu")
		(net "HBA_MB_TX_P1")
	)
	(segment
		(start 97.204276 -32.720026)
		(end 96.850962 -32.186372)
		(width 0.21336)
		(layer "F.Cu")
		(net "HBA_MB_TX_P1")
	)
	(segment
		(start 93.054932 -26.45156)
		(end 92.701618 -25.917906)
		(width 0.21336)
		(layer "F.Cu")
		(net "HBA_MB_TX_P1")
	)
	(segment
		(start 97.521014 -32.784542)
		(end 97.204276 -32.720026)
		(width 0.21336)
		(layer "F.Cu")
		(net "HBA_MB_TX_P1")
	)
	(segment
		(start 83.039966 -18.817082)
		(end 82.41284 -18.689574)
		(width 0.21336)
		(layer "F.Cu")
		(net "HBA_MB_TX_P1")
	)
	(segment
		(start 84.92109 -19.433286)
		(end 84.742528 -19.163538)
		(width 0.21336)
		(layer "F.Cu")
		(net "HBA_MB_TX_P1")
	)
	(segment
		(start 90.848434 -22.703282)
		(end 90.49512 -22.169628)
		(width 0.21336)
		(layer "F.Cu")
		(net "HBA_MB_TX_P1")
	)
	(via
		(at 83.086956 -21.166836)
		(size 0.508)
		(drill 0.254)
		(layers "F.Cu" "B.Cu")
		(net "HBA_MB_TX_P1")
	)
	(segment
		(start 82.26933 -21.329904)
		(end 81.814924 -21.329904)
		(width 0.21336)
		(layer "B.Cu")
		(net "HBA_MB_TX_P1")
	)
	(segment
		(start 83.086956 -21.166836)
		(end 82.799936 -21.453856)
		(width 0.21336)
		(layer "B.Cu")
		(net "HBA_MB_TX_P1")
	)
	(segment
		(start 82.393282 -21.453856)
		(end 82.26933 -21.329904)
		(width 0.21336)
		(layer "B.Cu")
		(net "HBA_MB_TX_P1")
	)
	(segment
		(start 82.799936 -21.453856)
		(end 82.393282 -21.453856)
		(width 0.21336)
		(layer "B.Cu")
		(net "HBA_MB_TX_P1")
	)
	(segment
		(start 86.335108 -21.482558)
		(end 86.842092 -21.482558)
		(width 0.21336)
		(layer "F.Cu")
		(net "HBA_MB_TX_P0")
	)
	(segment
		(start 84.450936 -23.889462)
		(end 84.723224 -22.549358)
		(width 0.21336)
		(layer "F.Cu")
		(net "HBA_MB_TX_P0")
	)
	(segment
		(start 86.842092 -21.482558)
		(end 87.129112 -21.195538)
		(width 0.21336)
		(layer "F.Cu")
		(net "HBA_MB_TX_P0")
	)
	(segment
		(start 97.597214 -49.940972)
		(end 92.49283 -46.562518)
		(width 0.21336)
		(layer "F.Cu")
		(net "HBA_MB_TX_P0")
	)
	(segment
		(start 89.038684 -41.34358)
		(end 86.208616 -27.433016)
		(width 0.21336)
		(layer "F.Cu")
		(net "HBA_MB_TX_P0")
	)
	(segment
		(start 84.712048 -25.172162)
		(end 84.450936 -23.889462)
		(width 0.21336)
		(layer "F.Cu")
		(net "HBA_MB_TX_P0")
	)
	(segment
		(start 98.086418 -51.283616)
		(end 98.086418 -50.680366)
		(width 0.21336)
		(layer "F.Cu")
		(net "HBA_MB_TX_P0")
	)
	(segment
		(start 86.208616 -27.433016)
		(end 84.712048 -25.172162)
		(width 0.21336)
		(layer "F.Cu")
		(net "HBA_MB_TX_P0")
	)
	(segment
		(start 92.49283 -46.562518)
		(end 89.038684 -41.34358)
		(width 0.21336)
		(layer "F.Cu")
		(net "HBA_MB_TX_P0")
	)
	(segment
		(start 97.620074 -51.74996)
		(end 98.086418 -51.283616)
		(width 0.21336)
		(layer "F.Cu")
		(net "HBA_MB_TX_P0")
	)
	(segment
		(start 98.086418 -50.680366)
		(end 97.597214 -49.940972)
		(width 0.21336)
		(layer "F.Cu")
		(net "HBA_MB_TX_P0")
	)
	(segment
		(start 84.723224 -22.549358)
		(end 86.335108 -21.482558)
		(width 0.21336)
		(layer "F.Cu")
		(net "HBA_MB_TX_P0")
	)
	(via
		(at 87.129112 -21.195538)
		(size 0.508)
		(drill 0.254)
		(layers "F.Cu" "B.Cu")
		(net "HBA_MB_TX_P0")
	)
	(segment
		(start 85.085682 -21.482558)
		(end 84.933028 -21.329904)
		(width 0.21336)
		(layer "B.Cu")
		(net "HBA_MB_TX_P0")
	)
	(segment
		(start 84.933028 -21.329904)
		(end 84.514944 -21.329904)
		(width 0.21336)
		(layer "B.Cu")
		(net "HBA_MB_TX_P0")
	)
	(segment
		(start 87.129112 -21.195538)
		(end 86.842092 -21.482558)
		(width 0.21336)
		(layer "B.Cu")
		(net "HBA_MB_TX_P0")
	)
	(segment
		(start 86.842092 -21.482558)
		(end 85.085682 -21.482558)
		(width 0.21336)
		(layer "B.Cu")
		(net "HBA_MB_TX_P0")
	)
	(via
		(at 82.652616 -25.70861)
		(size 0.508)
		(drill 0.254)
		(layers "F.Cu" "B.Cu")
		(net "HBA_MB_TX_N3")
	)
	(segment
		(start 82.939636 -24.417782)
		(end 82.726276 -24.204422)
		(width 0.21336)
		(layer "B.Cu")
		(net "HBA_MB_TX_N3")
	)
	(segment
		(start 82.299048 -24.329898)
		(end 81.814924 -24.329898)
		(width 0.21336)
		(layer "B.Cu")
		(net "HBA_MB_TX_N3")
	)
	(segment
		(start 82.652616 -25.70861)
		(end 82.939636 -25.42159)
		(width 0.21336)
		(layer "B.Cu")
		(net "HBA_MB_TX_N3")
	)
	(segment
		(start 82.726276 -24.204422)
		(end 82.424524 -24.204422)
		(width 0.21336)
		(layer "B.Cu")
		(net "HBA_MB_TX_N3")
	)
	(segment
		(start 82.939636 -25.42159)
		(end 82.939636 -24.417782)
		(width 0.21336)
		(layer "B.Cu")
		(net "HBA_MB_TX_N3")
	)
	(segment
		(start 82.424524 -24.204422)
		(end 82.299048 -24.329898)
		(width 0.21336)
		(layer "B.Cu")
		(net "HBA_MB_TX_N3")
	)
	(segment
		(start 24.964898 -2.549906)
		(end 24.48433 -3.030474)
		(width 0.14224)
		(layer "In2.Cu")
		(net "HBA_MB_TX_N3")
	)
	(segment
		(start 76.075032 -24.178006)
		(end 76.284582 -24.039322)
		(width 0.14224)
		(layer "In2.Cu")
		(net "HBA_MB_TX_N3")
	)
	(segment
		(start 33.43275 -16.149828)
		(end 35.74288 -15.679674)
		(width 0.14224)
		(layer "In2.Cu")
		(net "HBA_MB_TX_N3")
	)
	(segment
		(start 75.51801 -23.883366)
		(end 75.656948 -24.092916)
		(width 0.14224)
		(layer "In2.Cu")
		(net "HBA_MB_TX_N3")
	)
	(segment
		(start 82.828892 -26.414476)
		(end 82.970116 -26.201116)
		(width 0.14224)
		(layer "In2.Cu")
		(net "HBA_MB_TX_N3")
	)
	(segment
		(start 68.893182 -22.716744)
		(end 69.311266 -22.801834)
		(width 0.14224)
		(layer "In2.Cu")
		(net "HBA_MB_TX_N3")
	)
	(segment
		(start 69.52107 -22.66315)
		(end 69.939154 -22.74824)
		(width 0.14224)
		(layer "In2.Cu")
		(net "HBA_MB_TX_N3")
	)
	(segment
		(start 58.986928 -20.520152)
		(end 59.405012 -20.605242)
		(width 0.14224)
		(layer "In2.Cu")
		(net "HBA_MB_TX_N3")
	)
	(segment
		(start 24.48433 -3.432048)
		(end 23.61057 -4.305808)
		(width 0.14224)
		(layer "In2.Cu")
		(net "HBA_MB_TX_N3")
	)
	(segment
		(start 60.171584 -20.761198)
		(end 60.589668 -20.846288)
		(width 0.14224)
		(layer "In2.Cu")
		(net "HBA_MB_TX_N3")
	)
	(segment
		(start 57.592468 -20.41779)
		(end 57.802272 -20.279106)
		(width 0.14224)
		(layer "In2.Cu")
		(net "HBA_MB_TX_N3")
	)
	(segment
		(start 82.426048 -26.681176)
		(end 82.828892 -26.414476)
		(width 0.14224)
		(layer "In2.Cu")
		(net "HBA_MB_TX_N3")
	)
	(segment
		(start 59.405012 -20.605242)
		(end 59.54395 -20.814792)
		(width 0.14224)
		(layer "In2.Cu")
		(net "HBA_MB_TX_N3")
	)
	(segment
		(start 59.54395 -20.814792)
		(end 59.962034 -20.899882)
		(width 0.14224)
		(layer "In2.Cu")
		(net "HBA_MB_TX_N3")
	)
	(segment
		(start 24.48433 -3.030474)
		(end 24.48433 -3.432048)
		(width 0.14224)
		(layer "In2.Cu")
		(net "HBA_MB_TX_N3")
	)
	(segment
		(start 77.887322 -24.365458)
		(end 78.02626 -24.575008)
		(width 0.14224)
		(layer "In2.Cu")
		(net "HBA_MB_TX_N3")
	)
	(segment
		(start 19.471386 -10.55751)
		(end 19.333464 -11.237976)
		(width 0.14224)
		(layer "In2.Cu")
		(net "HBA_MB_TX_N3")
	)
	(segment
		(start 75.656948 -24.092916)
		(end 76.075032 -24.178006)
		(width 0.14224)
		(layer "In2.Cu")
		(net "HBA_MB_TX_N3")
	)
	(segment
		(start 61.774578 -21.08708)
		(end 61.913262 -21.296884)
		(width 0.14224)
		(layer "In2.Cu")
		(net "HBA_MB_TX_N3")
	)
	(segment
		(start 73.70572 -23.695914)
		(end 73.91527 -23.55723)
		(width 0.14224)
		(layer "In2.Cu")
		(net "HBA_MB_TX_N3")
	)
	(segment
		(start 78.44409 -24.660352)
		(end 81.46034 -26.656538)
		(width 0.14224)
		(layer "In2.Cu")
		(net "HBA_MB_TX_N3")
	)
	(segment
		(start 58.777378 -20.658836)
		(end 58.986928 -20.520152)
		(width 0.14224)
		(layer "In2.Cu")
		(net "HBA_MB_TX_N3")
	)
	(segment
		(start 74.333354 -23.64232)
		(end 74.472292 -23.85187)
		(width 0.14224)
		(layer "In2.Cu")
		(net "HBA_MB_TX_N3")
	)
	(segment
		(start 58.220356 -20.364196)
		(end 58.359294 -20.573746)
		(width 0.14224)
		(layer "In2.Cu")
		(net "HBA_MB_TX_N3")
	)
	(segment
		(start 78.02626 -24.575008)
		(end 78.444344 -24.660098)
		(width 0.14224)
		(layer "In2.Cu")
		(net "HBA_MB_TX_N3")
	)
	(segment
		(start 56.253126 -20.145502)
		(end 57.592468 -20.41779)
		(width 0.14224)
		(layer "In2.Cu")
		(net "HBA_MB_TX_N3")
	)
	(segment
		(start 75.099926 -23.798276)
		(end 75.51801 -23.883366)
		(width 0.14224)
		(layer "In2.Cu")
		(net "HBA_MB_TX_N3")
	)
	(segment
		(start 67.708526 -22.475698)
		(end 68.12661 -22.560788)
		(width 0.14224)
		(layer "In2.Cu")
		(net "HBA_MB_TX_N3")
	)
	(segment
		(start 55.614062 -19.722592)
		(end 56.253126 -20.145502)
		(width 0.14224)
		(layer "In2.Cu")
		(net "HBA_MB_TX_N3")
	)
	(segment
		(start 82.970116 -26.201116)
		(end 83.000596 -26.052018)
		(width 0.14224)
		(layer "In2.Cu")
		(net "HBA_MB_TX_N3")
	)
	(segment
		(start 61.913262 -21.296884)
		(end 65.757298 -22.078696)
		(width 0.14224)
		(layer "In2.Cu")
		(net "HBA_MB_TX_N3")
	)
	(segment
		(start 76.841604 -24.333962)
		(end 77.259688 -24.419052)
		(width 0.14224)
		(layer "In2.Cu")
		(net "HBA_MB_TX_N3")
	)
	(segment
		(start 60.589668 -20.846288)
		(end 60.728606 -21.055838)
		(width 0.14224)
		(layer "In2.Cu")
		(net "HBA_MB_TX_N3")
	)
	(segment
		(start 76.702666 -24.124412)
		(end 76.841604 -24.333962)
		(width 0.14224)
		(layer "In2.Cu")
		(net "HBA_MB_TX_N3")
	)
	(segment
		(start 70.077838 -22.95779)
		(end 73.70572 -23.695914)
		(width 0.14224)
		(layer "In2.Cu")
		(net "HBA_MB_TX_N3")
	)
	(segment
		(start 83.000596 -26.052018)
		(end 83.000596 -25.85085)
		(width 0.14224)
		(layer "In2.Cu")
		(net "HBA_MB_TX_N3")
	)
	(segment
		(start 82.003392 -26.766774)
		(end 82.426048 -26.681176)
		(width 0.14224)
		(layer "In2.Cu")
		(net "HBA_MB_TX_N3")
	)
	(segment
		(start 58.359294 -20.573746)
		(end 58.777378 -20.658836)
		(width 0.14224)
		(layer "In2.Cu")
		(net "HBA_MB_TX_N3")
	)
	(segment
		(start 67.151504 -22.181058)
		(end 67.569588 -22.266148)
		(width 0.14224)
		(layer "In2.Cu")
		(net "HBA_MB_TX_N3")
	)
	(segment
		(start 61.14669 -21.140928)
		(end 61.356494 -21.00199)
		(width 0.14224)
		(layer "In2.Cu")
		(net "HBA_MB_TX_N3")
	)
	(segment
		(start 74.890376 -23.93696)
		(end 75.099926 -23.798276)
		(width 0.14224)
		(layer "In2.Cu")
		(net "HBA_MB_TX_N3")
	)
	(segment
		(start 66.52387 -22.234652)
		(end 66.941954 -22.319742)
		(width 0.14224)
		(layer "In2.Cu")
		(net "HBA_MB_TX_N3")
	)
	(segment
		(start 65.966848 -21.940012)
		(end 66.384932 -22.025102)
		(width 0.14224)
		(layer "In2.Cu")
		(net "HBA_MB_TX_N3")
	)
	(segment
		(start 20.550886 -13.600176)
		(end 23.506938 -15.556738)
		(width 0.14224)
		(layer "In2.Cu")
		(net "HBA_MB_TX_N3")
	)
	(segment
		(start 69.939154 -22.74824)
		(end 70.077838 -22.95779)
		(width 0.14224)
		(layer "In2.Cu")
		(net "HBA_MB_TX_N3")
	)
	(segment
		(start 19.333464 -11.237976)
		(end 19.487642 -11.993372)
		(width 0.14224)
		(layer "In2.Cu")
		(net "HBA_MB_TX_N3")
	)
	(segment
		(start 81.46034 -26.656538)
		(end 82.003392 -26.766774)
		(width 0.14224)
		(layer "In2.Cu")
		(net "HBA_MB_TX_N3")
	)
	(segment
		(start 83.000596 -25.85085)
		(end 82.858356 -25.70861)
		(width 0.14224)
		(layer "In2.Cu")
		(net "HBA_MB_TX_N3")
	)
	(segment
		(start 76.284582 -24.039322)
		(end 76.702666 -24.124412)
		(width 0.14224)
		(layer "In2.Cu")
		(net "HBA_MB_TX_N3")
	)
	(segment
		(start 68.12661 -22.560788)
		(end 68.33616 -22.422104)
		(width 0.14224)
		(layer "In2.Cu")
		(net "HBA_MB_TX_N3")
	)
	(segment
		(start 66.941954 -22.319742)
		(end 67.151504 -22.181058)
		(width 0.14224)
		(layer "In2.Cu")
		(net "HBA_MB_TX_N3")
	)
	(segment
		(start 78.444344 -24.660098)
		(end 78.44409 -24.660352)
		(width 0.14224)
		(layer "In2.Cu")
		(net "HBA_MB_TX_N3")
	)
	(segment
		(start 73.91527 -23.55723)
		(end 74.333354 -23.64232)
		(width 0.14224)
		(layer "In2.Cu")
		(net "HBA_MB_TX_N3")
	)
	(segment
		(start 61.356494 -21.00199)
		(end 61.774578 -21.08708)
		(width 0.14224)
		(layer "In2.Cu")
		(net "HBA_MB_TX_N3")
	)
	(segment
		(start 67.569588 -22.266148)
		(end 67.708526 -22.475698)
		(width 0.14224)
		(layer "In2.Cu")
		(net "HBA_MB_TX_N3")
	)
	(segment
		(start 82.858356 -25.70861)
		(end 82.652616 -25.70861)
		(width 0.14224)
		(layer "In2.Cu")
		(net "HBA_MB_TX_N3")
	)
	(segment
		(start 65.757298 -22.078696)
		(end 65.966848 -21.940012)
		(width 0.14224)
		(layer "In2.Cu")
		(net "HBA_MB_TX_N3")
	)
	(segment
		(start 35.74288 -15.679674)
		(end 55.614062 -19.722592)
		(width 0.14224)
		(layer "In2.Cu")
		(net "HBA_MB_TX_N3")
	)
	(segment
		(start 59.962034 -20.899882)
		(end 60.171584 -20.761198)
		(width 0.14224)
		(layer "In2.Cu")
		(net "HBA_MB_TX_N3")
	)
	(segment
		(start 66.384932 -22.025102)
		(end 66.52387 -22.234652)
		(width 0.14224)
		(layer "In2.Cu")
		(net "HBA_MB_TX_N3")
	)
	(segment
		(start 68.754244 -22.507194)
		(end 68.893182 -22.716744)
		(width 0.14224)
		(layer "In2.Cu")
		(net "HBA_MB_TX_N3")
	)
	(segment
		(start 57.802272 -20.279106)
		(end 58.220356 -20.364196)
		(width 0.14224)
		(layer "In2.Cu")
		(net "HBA_MB_TX_N3")
	)
	(segment
		(start 74.472292 -23.85187)
		(end 74.890376 -23.93696)
		(width 0.14224)
		(layer "In2.Cu")
		(net "HBA_MB_TX_N3")
	)
	(segment
		(start 23.506938 -15.556738)
		(end 28.201874 -16.511778)
		(width 0.14224)
		(layer "In2.Cu")
		(net "HBA_MB_TX_N3")
	)
	(segment
		(start 68.33616 -22.422104)
		(end 68.754244 -22.507194)
		(width 0.14224)
		(layer "In2.Cu")
		(net "HBA_MB_TX_N3")
	)
	(segment
		(start 77.469238 -24.280368)
		(end 77.887322 -24.365458)
		(width 0.14224)
		(layer "In2.Cu")
		(net "HBA_MB_TX_N3")
	)
	(segment
		(start 77.259688 -24.419052)
		(end 77.469238 -24.280368)
		(width 0.14224)
		(layer "In2.Cu")
		(net "HBA_MB_TX_N3")
	)
	(segment
		(start 60.728606 -21.055838)
		(end 61.14669 -21.140928)
		(width 0.14224)
		(layer "In2.Cu")
		(net "HBA_MB_TX_N3")
	)
	(segment
		(start 69.311266 -22.801834)
		(end 69.52107 -22.66315)
		(width 0.14224)
		(layer "In2.Cu")
		(net "HBA_MB_TX_N3")
	)
	(segment
		(start 23.61057 -4.305808)
		(end 19.471386 -10.55751)
		(width 0.14224)
		(layer "In2.Cu")
		(net "HBA_MB_TX_N3")
	)
	(segment
		(start 28.201874 -16.511778)
		(end 31.707074 -15.798546)
		(width 0.14224)
		(layer "In2.Cu")
		(net "HBA_MB_TX_N3")
	)
	(segment
		(start 31.707074 -15.798546)
		(end 33.43275 -16.149828)
		(width 0.14224)
		(layer "In2.Cu")
		(net "HBA_MB_TX_N3")
	)
	(segment
		(start 19.487642 -11.993372)
		(end 20.550886 -13.600176)
		(width 0.14224)
		(layer "In2.Cu")
		(net "HBA_MB_TX_N3")
	)
	(via
		(at 86.581996 -24.462994)
		(size 0.508)
		(drill 0.254)
		(layers "F.Cu" "B.Cu")
		(net "HBA_MB_TX_N2")
	)
	(segment
		(start 84.943188 -24.329898)
		(end 84.514944 -24.329898)
		(width 0.21336)
		(layer "B.Cu")
		(net "HBA_MB_TX_N2")
	)
	(segment
		(start 86.581996 -24.462994)
		(end 86.294976 -24.175974)
		(width 0.21336)
		(layer "B.Cu")
		(net "HBA_MB_TX_N2")
	)
	(segment
		(start 85.097112 -24.175974)
		(end 84.943188 -24.329898)
		(width 0.21336)
		(layer "B.Cu")
		(net "HBA_MB_TX_N2")
	)
	(segment
		(start 86.294976 -24.175974)
		(end 85.097112 -24.175974)
		(width 0.21336)
		(layer "B.Cu")
		(net "HBA_MB_TX_N2")
	)
	(segment
		(start 31.462726 -14.751812)
		(end 33.223454 -15.109952)
		(width 0.14224)
		(layer "In2.Cu")
		(net "HBA_MB_TX_N2")
	)
	(segment
		(start 88.517984 -21.006562)
		(end 88.79078 -22.347174)
		(width 0.14224)
		(layer "In2.Cu")
		(net "HBA_MB_TX_N2")
	)
	(segment
		(start 28.031694 -15.450058)
		(end 31.462726 -14.751812)
		(width 0.14224)
		(layer "In2.Cu")
		(net "HBA_MB_TX_N2")
	)
	(segment
		(start 35.795458 -14.586966)
		(end 54.326536 -18.356326)
		(width 0.14224)
		(layer "In2.Cu")
		(net "HBA_MB_TX_N2")
	)
	(segment
		(start 88.79078 -22.347174)
		(end 88.537542 -23.589234)
		(width 0.14224)
		(layer "In2.Cu")
		(net "HBA_MB_TX_N2")
	)
	(segment
		(start 86.900258 -24.144732)
		(end 86.581996 -24.462994)
		(width 0.14224)
		(layer "In2.Cu")
		(net "HBA_MB_TX_N2")
	)
	(segment
		(start 86.620604 -19.09318)
		(end 87.743538 -19.836638)
		(width 0.14224)
		(layer "In2.Cu")
		(net "HBA_MB_TX_N2")
	)
	(segment
		(start 24.660352 -14.765274)
		(end 28.031694 -15.450058)
		(width 0.14224)
		(layer "In2.Cu")
		(net "HBA_MB_TX_N2")
	)
	(segment
		(start 81.878678 -18.128996)
		(end 86.620604 -19.09318)
		(width 0.14224)
		(layer "In2.Cu")
		(net "HBA_MB_TX_N2")
	)
	(segment
		(start 24.52751 -14.2875)
		(end 24.52751 -14.602714)
		(width 0.14224)
		(layer "In2.Cu")
		(net "HBA_MB_TX_N2")
	)
	(segment
		(start 64.36995 -16.31315)
		(end 77.587094 -19.001994)
		(width 0.14224)
		(layer "In2.Cu")
		(net "HBA_MB_TX_N2")
	)
	(segment
		(start 87.698834 -24.144732)
		(end 86.900258 -24.144732)
		(width 0.14224)
		(layer "In2.Cu")
		(net "HBA_MB_TX_N2")
	)
	(segment
		(start 24.52751 -14.602714)
		(end 24.660352 -14.765274)
		(width 0.14224)
		(layer "In2.Cu")
		(net "HBA_MB_TX_N2")
	)
	(segment
		(start 33.223454 -15.109952)
		(end 35.795458 -14.586966)
		(width 0.14224)
		(layer "In2.Cu")
		(net "HBA_MB_TX_N2")
	)
	(segment
		(start 54.326536 -18.356326)
		(end 64.36995 -16.31315)
		(width 0.14224)
		(layer "In2.Cu")
		(net "HBA_MB_TX_N2")
	)
	(segment
		(start 88.537542 -23.589234)
		(end 87.698834 -24.144732)
		(width 0.14224)
		(layer "In2.Cu")
		(net "HBA_MB_TX_N2")
	)
	(segment
		(start 87.743538 -19.836638)
		(end 88.517984 -21.006562)
		(width 0.14224)
		(layer "In2.Cu")
		(net "HBA_MB_TX_N2")
	)
	(segment
		(start 24.964898 -13.850112)
		(end 24.52751 -14.2875)
		(width 0.14224)
		(layer "In2.Cu")
		(net "HBA_MB_TX_N2")
	)
	(segment
		(start 77.587094 -19.001994)
		(end 81.878678 -18.128996)
		(width 0.14224)
		(layer "In2.Cu")
		(net "HBA_MB_TX_N2")
	)
	(segment
		(start 98.617278 -34.044128)
		(end 98.49866 -33.460436)
		(width 0.21336)
		(layer "F.Cu")
		(net "HBA_MB_TX_N1")
	)
	(segment
		(start 86.663022 -19.103086)
		(end 82.3214 -18.219928)
		(width 0.21336)
		(layer "F.Cu")
		(net "HBA_MB_TX_N1")
	)
	(segment
		(start 98.617278 -34.777172)
		(end 98.617278 -34.044128)
		(width 0.21336)
		(layer "F.Cu")
		(net "HBA_MB_TX_N1")
	)
	(segment
		(start 82.883502 -21.979382)
		(end 83.086956 -22.182836)
		(width 0.21336)
		(layer "F.Cu")
		(net "HBA_MB_TX_N1")
	)
	(segment
		(start 80.920336 -20.748752)
		(end 81.618074 -21.801836)
		(width 0.21336)
		(layer "F.Cu")
		(net "HBA_MB_TX_N1")
	)
	(segment
		(start 90.814144 -21.850604)
		(end 86.663022 -19.103086)
		(width 0.21336)
		(layer "F.Cu")
		(net "HBA_MB_TX_N1")
	)
	(segment
		(start 98.890074 -35.049968)
		(end 98.617278 -34.777172)
		(width 0.21336)
		(layer "F.Cu")
		(net "HBA_MB_TX_N1")
	)
	(segment
		(start 81.618074 -21.801836)
		(end 82.490564 -21.979382)
		(width 0.21336)
		(layer "F.Cu")
		(net "HBA_MB_TX_N1")
	)
	(segment
		(start 82.490564 -21.979382)
		(end 82.883502 -21.979382)
		(width 0.21336)
		(layer "F.Cu")
		(net "HBA_MB_TX_N1")
	)
	(segment
		(start 81.297526 -18.8976)
		(end 80.920336 -20.748752)
		(width 0.21336)
		(layer "F.Cu")
		(net "HBA_MB_TX_N1")
	)
	(segment
		(start 98.49866 -33.460436)
		(end 90.814144 -21.850604)
		(width 0.21336)
		(layer "F.Cu")
		(net "HBA_MB_TX_N1")
	)
	(segment
		(start 82.3214 -18.219928)
		(end 81.297526 -18.8976)
		(width 0.21336)
		(layer "F.Cu")
		(net "HBA_MB_TX_N1")
	)
	(via
		(at 83.086956 -22.182836)
		(size 0.508)
		(drill 0.254)
		(layers "F.Cu" "B.Cu")
		(net "HBA_MB_TX_N1")
	)
	(segment
		(start 82.437478 -21.895816)
		(end 82.253328 -22.079966)
		(width 0.21336)
		(layer "B.Cu")
		(net "HBA_MB_TX_N1")
	)
	(segment
		(start 83.086956 -22.182836)
		(end 82.799936 -21.895816)
		(width 0.21336)
		(layer "B.Cu")
		(net "HBA_MB_TX_N1")
	)
	(segment
		(start 82.799936 -21.895816)
		(end 82.437478 -21.895816)
		(width 0.21336)
		(layer "B.Cu")
		(net "HBA_MB_TX_N1")
	)
	(segment
		(start 82.253328 -22.079966)
		(end 81.814924 -22.079966)
		(width 0.21336)
		(layer "B.Cu")
		(net "HBA_MB_TX_N1")
	)
	(segment
		(start 87.149432 -28.693618)
		(end 87.021924 -28.066492)
		(width 0.21336)
		(layer "F.Cu")
		(net "HBA_MB_TX_N0")
	)
	(segment
		(start 98.528378 -51.388264)
		(end 98.528378 -50.54727)
		(width 0.21336)
		(layer "F.Cu")
		(net "HBA_MB_TX_N0")
	)
	(segment
		(start 87.31758 -30.665928)
		(end 87.495888 -30.39618)
		(width 0.21336)
		(layer "F.Cu")
		(net "HBA_MB_TX_N0")
	)
	(segment
		(start 87.664036 -32.36849)
		(end 87.842344 -32.098742)
		(width 0.21336)
		(layer "F.Cu")
		(net "HBA_MB_TX_N0")
	)
	(segment
		(start 87.495888 -30.39618)
		(end 87.36838 -29.769054)
		(width 0.21336)
		(layer "F.Cu")
		(net "HBA_MB_TX_N0")
	)
	(segment
		(start 92.811854 -46.243494)
		(end 89.454736 -41.171368)
		(width 0.21336)
		(layer "F.Cu")
		(net "HBA_MB_TX_N0")
	)
	(segment
		(start 86.752176 -27.88793)
		(end 86.624668 -27.260804)
		(width 0.21336)
		(layer "F.Cu")
		(net "HBA_MB_TX_N0")
	)
	(segment
		(start 85.119972 -22.81682)
		(end 86.468204 -21.924518)
		(width 0.21336)
		(layer "F.Cu")
		(net "HBA_MB_TX_N0")
	)
	(segment
		(start 88.1888 -33.801304)
		(end 88.061292 -33.174178)
		(width 0.21336)
		(layer "F.Cu")
		(net "HBA_MB_TX_N0")
	)
	(segment
		(start 98.528378 -50.54727)
		(end 97.916238 -49.621948)
		(width 0.21336)
		(layer "F.Cu")
		(net "HBA_MB_TX_N0")
	)
	(segment
		(start 89.454736 -41.171368)
		(end 88.010238 -34.071052)
		(width 0.21336)
		(layer "F.Cu")
		(net "HBA_MB_TX_N0")
	)
	(segment
		(start 87.36838 -29.769054)
		(end 87.098632 -29.590492)
		(width 0.21336)
		(layer "F.Cu")
		(net "HBA_MB_TX_N0")
	)
	(segment
		(start 86.624668 -27.260804)
		(end 85.1281 -24.99995)
		(width 0.21336)
		(layer "F.Cu")
		(net "HBA_MB_TX_N0")
	)
	(segment
		(start 87.445088 -31.293054)
		(end 87.31758 -30.665928)
		(width 0.21336)
		(layer "F.Cu")
		(net "HBA_MB_TX_N0")
	)
	(segment
		(start 84.90204 -23.889462)
		(end 85.119972 -22.81682)
		(width 0.21336)
		(layer "F.Cu")
		(net "HBA_MB_TX_N0")
	)
	(segment
		(start 88.010238 -34.071052)
		(end 88.1888 -33.801304)
		(width 0.21336)
		(layer "F.Cu")
		(net "HBA_MB_TX_N0")
	)
	(segment
		(start 85.1281 -24.99995)
		(end 84.90204 -23.889462)
		(width 0.21336)
		(layer "F.Cu")
		(net "HBA_MB_TX_N0")
	)
	(segment
		(start 86.468204 -21.924518)
		(end 86.842092 -21.924518)
		(width 0.21336)
		(layer "F.Cu")
		(net "HBA_MB_TX_N0")
	)
	(segment
		(start 97.916238 -49.621948)
		(end 92.811854 -46.243494)
		(width 0.21336)
		(layer "F.Cu")
		(net "HBA_MB_TX_N0")
	)
	(segment
		(start 88.061292 -33.174178)
		(end 87.791544 -32.995616)
		(width 0.21336)
		(layer "F.Cu")
		(net "HBA_MB_TX_N0")
	)
	(segment
		(start 87.842344 -32.098742)
		(end 87.714836 -31.471616)
		(width 0.21336)
		(layer "F.Cu")
		(net "HBA_MB_TX_N0")
	)
	(segment
		(start 87.098632 -29.590492)
		(end 86.971124 -28.963366)
		(width 0.21336)
		(layer "F.Cu")
		(net "HBA_MB_TX_N0")
	)
	(segment
		(start 86.971124 -28.963366)
		(end 87.149432 -28.693618)
		(width 0.21336)
		(layer "F.Cu")
		(net "HBA_MB_TX_N0")
	)
	(segment
		(start 87.714836 -31.471616)
		(end 87.445088 -31.293054)
		(width 0.21336)
		(layer "F.Cu")
		(net "HBA_MB_TX_N0")
	)
	(segment
		(start 87.021924 -28.066492)
		(end 86.752176 -27.88793)
		(width 0.21336)
		(layer "F.Cu")
		(net "HBA_MB_TX_N0")
	)
	(segment
		(start 98.890074 -51.74996)
		(end 98.528378 -51.388264)
		(width 0.21336)
		(layer "F.Cu")
		(net "HBA_MB_TX_N0")
	)
	(segment
		(start 86.842092 -21.924518)
		(end 87.129112 -22.211538)
		(width 0.21336)
		(layer "F.Cu")
		(net "HBA_MB_TX_N0")
	)
	(segment
		(start 87.791544 -32.995616)
		(end 87.664036 -32.36849)
		(width 0.21336)
		(layer "F.Cu")
		(net "HBA_MB_TX_N0")
	)
	(via
		(at 87.129112 -22.211538)
		(size 0.508)
		(drill 0.254)
		(layers "F.Cu" "B.Cu")
		(net "HBA_MB_TX_N0")
	)
	(segment
		(start 85.168232 -21.924518)
		(end 85.012784 -22.079966)
		(width 0.21336)
		(layer "B.Cu")
		(net "HBA_MB_TX_N0")
	)
	(segment
		(start 87.129112 -22.211538)
		(end 86.842092 -21.924518)
		(width 0.21336)
		(layer "B.Cu")
		(net "HBA_MB_TX_N0")
	)
	(segment
		(start 85.012784 -22.079966)
		(end 84.514944 -22.079966)
		(width 0.21336)
		(layer "B.Cu")
		(net "HBA_MB_TX_N0")
	)
	(segment
		(start 86.842092 -21.924518)
		(end 85.168232 -21.924518)
		(width 0.21336)
		(layer "B.Cu")
		(net "HBA_MB_TX_N0")
	)
	(segment
		(start 35.024568 -3.85699)
		(end 35.651694 -3.984498)
		(width 0.21336)
		(layer "B.Cu")
		(net "HBA_MB_RX_P3")
	)
	(segment
		(start 74.756772 -23.734014)
		(end 75.04938 -23.734014)
		(width 0.21336)
		(layer "B.Cu")
		(net "HBA_MB_RX_P3")
	)
	(segment
		(start 75.203304 -23.58009)
		(end 75.584812 -23.58009)
		(width 0.21336)
		(layer "B.Cu")
		(net "HBA_MB_RX_P3")
	)
	(segment
		(start 39.056818 -4.67741)
		(end 39.326566 -4.499102)
		(width 0.21336)
		(layer "B.Cu")
		(net "HBA_MB_RX_P3")
	)
	(segment
		(start 37.354256 -4.330954)
		(end 37.624004 -4.152646)
		(width 0.21336)
		(layer "B.Cu")
		(net "HBA_MB_RX_P3")
	)
	(segment
		(start 36.548568 -3.933698)
		(end 36.72713 -4.203446)
		(width 0.21336)
		(layer "B.Cu")
		(net "HBA_MB_RX_P3")
	)
	(segment
		(start 74.521314 -23.568914)
		(end 74.756772 -23.73376)
		(width 0.21336)
		(layer "B.Cu")
		(net "HBA_MB_RX_P3")
	)
	(segment
		(start 28.393644 -3.351276)
		(end 28.62453 -3.633724)
		(width 0.21336)
		(layer "B.Cu")
		(net "HBA_MB_RX_P3")
	)
	(segment
		(start 33.949132 -3.637788)
		(end 33.949132 -3.638042)
		(width 0.21336)
		(layer "B.Cu")
		(net "HBA_MB_RX_P3")
	)
	(segment
		(start 35.921442 -3.80619)
		(end 36.548568 -3.933698)
		(width 0.21336)
		(layer "B.Cu")
		(net "HBA_MB_RX_P3")
	)
	(segment
		(start 60.216034 -12.591542)
		(end 72.743314 -20.882864)
		(width 0.21336)
		(layer "B.Cu")
		(net "HBA_MB_RX_P3")
	)
	(segment
		(start 33.322006 -3.510534)
		(end 33.949132 -3.637788)
		(width 0.21336)
		(layer "B.Cu")
		(net "HBA_MB_RX_P3")
	)
	(segment
		(start 28.393644 -2.93116)
		(end 28.393644 -3.351276)
		(width 0.21336)
		(layer "B.Cu")
		(net "HBA_MB_RX_P3")
	)
	(segment
		(start 30.670246 -4.05003)
		(end 33.322006 -3.510534)
		(width 0.21336)
		(layer "B.Cu")
		(net "HBA_MB_RX_P3")
	)
	(segment
		(start 29.647388 -3.842004)
		(end 30.670246 -4.05003)
		(width 0.21336)
		(layer "B.Cu")
		(net "HBA_MB_RX_P3")
	)
	(segment
		(start 36.72713 -4.203446)
		(end 37.354256 -4.330954)
		(width 0.21336)
		(layer "B.Cu")
		(net "HBA_MB_RX_P3")
	)
	(segment
		(start 51.476148 -10.812526)
		(end 60.216034 -12.591542)
		(width 0.21336)
		(layer "B.Cu")
		(net "HBA_MB_RX_P3")
	)
	(segment
		(start 28.62453 -3.633724)
		(end 29.647642 -3.842004)
		(width 0.21336)
		(layer "B.Cu")
		(net "HBA_MB_RX_P3")
	)
	(segment
		(start 74.521314 -23.56866)
		(end 74.521314 -23.568914)
		(width 0.21336)
		(layer "B.Cu")
		(net "HBA_MB_RX_P3")
	)
	(segment
		(start 75.04938 -23.734014)
		(end 75.203304 -23.58009)
		(width 0.21336)
		(layer "B.Cu")
		(net "HBA_MB_RX_P3")
	)
	(segment
		(start 33.949132 -3.638042)
		(end 34.21888 -3.459734)
		(width 0.21336)
		(layer "B.Cu")
		(net "HBA_MB_RX_P3")
	)
	(segment
		(start 72.743314 -20.882864)
		(end 74.521314 -23.56866)
		(width 0.21336)
		(layer "B.Cu")
		(net "HBA_MB_RX_P3")
	)
	(segment
		(start 39.326566 -4.499102)
		(end 39.953692 -4.62661)
		(width 0.21336)
		(layer "B.Cu")
		(net "HBA_MB_RX_P3")
	)
	(segment
		(start 38.25113 -4.280154)
		(end 38.429692 -4.549902)
		(width 0.21336)
		(layer "B.Cu")
		(net "HBA_MB_RX_P3")
	)
	(segment
		(start 43.604688 -5.602732)
		(end 51.476148 -10.812526)
		(width 0.21336)
		(layer "B.Cu")
		(net "HBA_MB_RX_P3")
	)
	(segment
		(start 74.756772 -23.73376)
		(end 74.756772 -23.734014)
		(width 0.21336)
		(layer "B.Cu")
		(net "HBA_MB_RX_P3")
	)
	(segment
		(start 40.132 -4.896104)
		(end 43.604688 -5.602732)
		(width 0.21336)
		(layer "B.Cu")
		(net "HBA_MB_RX_P3")
	)
	(segment
		(start 34.846006 -3.587242)
		(end 35.024568 -3.85699)
		(width 0.21336)
		(layer "B.Cu")
		(net "HBA_MB_RX_P3")
	)
	(segment
		(start 34.21888 -3.459734)
		(end 34.846006 -3.587242)
		(width 0.21336)
		(layer "B.Cu")
		(net "HBA_MB_RX_P3")
	)
	(segment
		(start 28.774898 -2.549906)
		(end 28.393644 -2.93116)
		(width 0.21336)
		(layer "B.Cu")
		(net "HBA_MB_RX_P3")
	)
	(segment
		(start 37.624004 -4.152646)
		(end 38.25113 -4.280154)
		(width 0.21336)
		(layer "B.Cu")
		(net "HBA_MB_RX_P3")
	)
	(segment
		(start 38.429692 -4.549902)
		(end 39.056818 -4.67741)
		(width 0.21336)
		(layer "B.Cu")
		(net "HBA_MB_RX_P3")
	)
	(segment
		(start 35.651694 -3.984498)
		(end 35.921442 -3.80619)
		(width 0.21336)
		(layer "B.Cu")
		(net "HBA_MB_RX_P3")
	)
	(segment
		(start 29.647642 -3.842004)
		(end 29.647388 -3.842004)
		(width 0.21336)
		(layer "B.Cu")
		(net "HBA_MB_RX_P3")
	)
	(segment
		(start 39.953692 -4.62661)
		(end 40.132 -4.896104)
		(width 0.21336)
		(layer "B.Cu")
		(net "HBA_MB_RX_P3")
	)
	(segment
		(start 77.92466 -23.58009)
		(end 78.284832 -23.58009)
		(width 0.21336)
		(layer "B.Cu")
		(net "HBA_MB_RX_P2")
	)
	(segment
		(start 75.574398 -25.98166)
		(end 76.336906 -25.477216)
		(width 0.21336)
		(layer "B.Cu")
		(net "HBA_MB_RX_P2")
	)
	(segment
		(start 38.739826 -15.52829)
		(end 39.366952 -15.655798)
		(width 0.21336)
		(layer "B.Cu")
		(net "HBA_MB_RX_P2")
	)
	(segment
		(start 39.366952 -15.655798)
		(end 39.545514 -15.925546)
		(width 0.21336)
		(layer "B.Cu")
		(net "HBA_MB_RX_P2")
	)
	(segment
		(start 36.14039 -15.232634)
		(end 36.767516 -15.360142)
		(width 0.21336)
		(layer "B.Cu")
		(net "HBA_MB_RX_P2")
	)
	(segment
		(start 76.842874 -24.16683)
		(end 77.31506 -23.694644)
		(width 0.21336)
		(layer "B.Cu")
		(net "HBA_MB_RX_P2")
	)
	(segment
		(start 34.437828 -14.886178)
		(end 35.064954 -15.013686)
		(width 0.21336)
		(layer "B.Cu")
		(net "HBA_MB_RX_P2")
	)
	(segment
		(start 37.842952 -15.57909)
		(end 38.470078 -15.706598)
		(width 0.21336)
		(layer "B.Cu")
		(net "HBA_MB_RX_P2")
	)
	(segment
		(start 35.064954 -15.013686)
		(end 35.334702 -14.835378)
		(width 0.21336)
		(layer "B.Cu")
		(net "HBA_MB_RX_P2")
	)
	(segment
		(start 46.814994 -17.404334)
		(end 53.846984 -15.97406)
		(width 0.21336)
		(layer "B.Cu")
		(net "HBA_MB_RX_P2")
	)
	(segment
		(start 77.810106 -23.694644)
		(end 77.92466 -23.58009)
		(width 0.21336)
		(layer "B.Cu")
		(net "HBA_MB_RX_P2")
	)
	(segment
		(start 76.336906 -25.477216)
		(end 76.842874 -24.971248)
		(width 0.21336)
		(layer "B.Cu")
		(net "HBA_MB_RX_P2")
	)
	(segment
		(start 53.846984 -15.97406)
		(end 63.678054 -17.97431)
		(width 0.21336)
		(layer "B.Cu")
		(net "HBA_MB_RX_P2")
	)
	(segment
		(start 41.248076 -16.271748)
		(end 46.814994 -17.404334)
		(width 0.21336)
		(layer "B.Cu")
		(net "HBA_MB_RX_P2")
	)
	(segment
		(start 40.17264 -16.053054)
		(end 40.442388 -15.874746)
		(width 0.21336)
		(layer "B.Cu")
		(net "HBA_MB_RX_P2")
	)
	(segment
		(start 37.66439 -15.309342)
		(end 37.842952 -15.57909)
		(width 0.21336)
		(layer "B.Cu")
		(net "HBA_MB_RX_P2")
	)
	(segment
		(start 63.678054 -17.97431)
		(end 71.857108 -23.38705)
		(width 0.21336)
		(layer "B.Cu")
		(net "HBA_MB_RX_P2")
	)
	(segment
		(start 71.857108 -23.38705)
		(end 72.74687 -24.731218)
		(width 0.21336)
		(layer "B.Cu")
		(net "HBA_MB_RX_P2")
	)
	(segment
		(start 77.31506 -23.694644)
		(end 77.810106 -23.694644)
		(width 0.21336)
		(layer "B.Cu")
		(net "HBA_MB_RX_P2")
	)
	(segment
		(start 28.563824 -14.921484)
		(end 31.413704 -15.501366)
		(width 0.21336)
		(layer "B.Cu")
		(net "HBA_MB_RX_P2")
	)
	(segment
		(start 38.470078 -15.706598)
		(end 38.739826 -15.52829)
		(width 0.21336)
		(layer "B.Cu")
		(net "HBA_MB_RX_P2")
	)
	(segment
		(start 28.360878 -14.264132)
		(end 28.360878 -14.615922)
		(width 0.21336)
		(layer "B.Cu")
		(net "HBA_MB_RX_P2")
	)
	(segment
		(start 36.767516 -15.360142)
		(end 37.037264 -15.181834)
		(width 0.21336)
		(layer "B.Cu")
		(net "HBA_MB_RX_P2")
	)
	(segment
		(start 28.774898 -13.850112)
		(end 28.360878 -14.264132)
		(width 0.21336)
		(layer "B.Cu")
		(net "HBA_MB_RX_P2")
	)
	(segment
		(start 72.74687 -24.731218)
		(end 74.106024 -25.682956)
		(width 0.21336)
		(layer "B.Cu")
		(net "HBA_MB_RX_P2")
	)
	(segment
		(start 40.442388 -15.874746)
		(end 41.069514 -16.002254)
		(width 0.21336)
		(layer "B.Cu")
		(net "HBA_MB_RX_P2")
	)
	(segment
		(start 74.106024 -25.682956)
		(end 75.574398 -25.98166)
		(width 0.21336)
		(layer "B.Cu")
		(net "HBA_MB_RX_P2")
	)
	(segment
		(start 39.545514 -15.925546)
		(end 40.17264 -16.053054)
		(width 0.21336)
		(layer "B.Cu")
		(net "HBA_MB_RX_P2")
	)
	(segment
		(start 35.334702 -14.835378)
		(end 35.961828 -14.962886)
		(width 0.21336)
		(layer "B.Cu")
		(net "HBA_MB_RX_P2")
	)
	(segment
		(start 31.413704 -15.501366)
		(end 34.437828 -14.886178)
		(width 0.21336)
		(layer "B.Cu")
		(net "HBA_MB_RX_P2")
	)
	(segment
		(start 76.842874 -24.971248)
		(end 76.842874 -24.16683)
		(width 0.21336)
		(layer "B.Cu")
		(net "HBA_MB_RX_P2")
	)
	(segment
		(start 28.360878 -14.615922)
		(end 28.563824 -14.921484)
		(width 0.21336)
		(layer "B.Cu")
		(net "HBA_MB_RX_P2")
	)
	(segment
		(start 41.069514 -16.002254)
		(end 41.248076 -16.271748)
		(width 0.21336)
		(layer "B.Cu")
		(net "HBA_MB_RX_P2")
	)
	(segment
		(start 35.961828 -14.962886)
		(end 36.14039 -15.232634)
		(width 0.21336)
		(layer "B.Cu")
		(net "HBA_MB_RX_P2")
	)
	(segment
		(start 37.037264 -15.181834)
		(end 37.66439 -15.309342)
		(width 0.21336)
		(layer "B.Cu")
		(net "HBA_MB_RX_P2")
	)
	(segment
		(start 101.578156 -32.53359)
		(end 93.74124 -27.346148)
		(width 0.21336)
		(layer "B.Cu")
		(net "HBA_MB_RX_P1")
	)
	(segment
		(start 76.160376 -21.536152)
		(end 75.954128 -21.329904)
		(width 0.21336)
		(layer "B.Cu")
		(net "HBA_MB_RX_P1")
	)
	(segment
		(start 83.023964 -18.173192)
		(end 80.939386 -17.749012)
		(width 0.21336)
		(layer "B.Cu")
		(net "HBA_MB_RX_P1")
	)
	(segment
		(start 102.093268 -33.311592)
		(end 101.578156 -32.53359)
		(width 0.21336)
		(layer "B.Cu")
		(net "HBA_MB_RX_P1")
	)
	(segment
		(start 102.700074 -35.049968)
		(end 102.28834 -34.638234)
		(width 0.21336)
		(layer "B.Cu")
		(net "HBA_MB_RX_P1")
	)
	(segment
		(start 76.628244 -19.708876)
		(end 76.628244 -21.322792)
		(width 0.21336)
		(layer "B.Cu")
		(net "HBA_MB_RX_P1")
	)
	(segment
		(start 93.74124 -27.346148)
		(end 88.821006 -19.91233)
		(width 0.21336)
		(layer "B.Cu")
		(net "HBA_MB_RX_P1")
	)
	(segment
		(start 102.28834 -34.638234)
		(end 102.28834 -34.270188)
		(width 0.21336)
		(layer "B.Cu")
		(net "HBA_MB_RX_P1")
	)
	(segment
		(start 80.939386 -17.749012)
		(end 79.560166 -18.029682)
		(width 0.21336)
		(layer "B.Cu")
		(net "HBA_MB_RX_P1")
	)
	(segment
		(start 84.279486 -17.917668)
		(end 83.023964 -18.173192)
		(width 0.21336)
		(layer "B.Cu")
		(net "HBA_MB_RX_P1")
	)
	(segment
		(start 86.568534 -18.38325)
		(end 84.279486 -17.917668)
		(width 0.21336)
		(layer "B.Cu")
		(net "HBA_MB_RX_P1")
	)
	(segment
		(start 79.560166 -18.029682)
		(end 77.937868 -17.699482)
		(width 0.21336)
		(layer "B.Cu")
		(net "HBA_MB_RX_P1")
	)
	(segment
		(start 102.28834 -34.270188)
		(end 102.093268 -33.311592)
		(width 0.21336)
		(layer "B.Cu")
		(net "HBA_MB_RX_P1")
	)
	(segment
		(start 75.954128 -21.329904)
		(end 75.584812 -21.329904)
		(width 0.21336)
		(layer "B.Cu")
		(net "HBA_MB_RX_P1")
	)
	(segment
		(start 76.628244 -21.322792)
		(end 76.414884 -21.536152)
		(width 0.21336)
		(layer "B.Cu")
		(net "HBA_MB_RX_P1")
	)
	(segment
		(start 76.414884 -21.536152)
		(end 76.160376 -21.536152)
		(width 0.21336)
		(layer "B.Cu")
		(net "HBA_MB_RX_P1")
	)
	(segment
		(start 88.821006 -19.91233)
		(end 86.568534 -18.38325)
		(width 0.21336)
		(layer "B.Cu")
		(net "HBA_MB_RX_P1")
	)
	(segment
		(start 76.896976 -18.388838)
		(end 76.628244 -19.708876)
		(width 0.21336)
		(layer "B.Cu")
		(net "HBA_MB_RX_P1")
	)
	(segment
		(start 77.937868 -17.699482)
		(end 76.896976 -18.388838)
		(width 0.21336)
		(layer "B.Cu")
		(net "HBA_MB_RX_P1")
	)
	(segment
		(start 78.79207 -21.329904)
		(end 78.284832 -21.329904)
		(width 0.21336)
		(layer "B.Cu")
		(net "HBA_MB_RX_P0")
	)
	(segment
		(start 78.940914 -21.478748)
		(end 78.79207 -21.329904)
		(width 0.21336)
		(layer "B.Cu")
		(net "HBA_MB_RX_P0")
	)
	(segment
		(start 79.399638 -21.478748)
		(end 78.940914 -21.478748)
		(width 0.21336)
		(layer "B.Cu")
		(net "HBA_MB_RX_P0")
	)
	(segment
		(start 80.321658 -24.001476)
		(end 80.635602 -22.457664)
		(width 0.21336)
		(layer "B.Cu")
		(net "HBA_MB_RX_P0")
	)
	(segment
		(start 102.286054 -51.33594)
		(end 102.286054 -50.734214)
		(width 0.21336)
		(layer "B.Cu")
		(net "HBA_MB_RX_P0")
	)
	(segment
		(start 80.635602 -22.457664)
		(end 80.079596 -21.616924)
		(width 0.21336)
		(layer "B.Cu")
		(net "HBA_MB_RX_P0")
	)
	(segment
		(start 80.079596 -21.616924)
		(end 79.399638 -21.478748)
		(width 0.21336)
		(layer "B.Cu")
		(net "HBA_MB_RX_P0")
	)
	(segment
		(start 102.286054 -50.734214)
		(end 101.541326 -49.608994)
		(width 0.21336)
		(layer "B.Cu")
		(net "HBA_MB_RX_P0")
	)
	(segment
		(start 95.081852 -47.58055)
		(end 80.697324 -25.847548)
		(width 0.21336)
		(layer "B.Cu")
		(net "HBA_MB_RX_P0")
	)
	(segment
		(start 101.541326 -49.608994)
		(end 96.640396 -48.612044)
		(width 0.21336)
		(layer "B.Cu")
		(net "HBA_MB_RX_P0")
	)
	(segment
		(start 102.700074 -51.74996)
		(end 102.286054 -51.33594)
		(width 0.21336)
		(layer "B.Cu")
		(net "HBA_MB_RX_P0")
	)
	(segment
		(start 96.640396 -48.612044)
		(end 95.081852 -47.58055)
		(width 0.21336)
		(layer "B.Cu")
		(net "HBA_MB_RX_P0")
	)
	(segment
		(start 80.697324 -25.847548)
		(end 80.321658 -24.001476)
		(width 0.21336)
		(layer "B.Cu")
		(net "HBA_MB_RX_P0")
	)
	(segment
		(start 33.322006 -3.961638)
		(end 43.432476 -6.018784)
		(width 0.21336)
		(layer "B.Cu")
		(net "HBA_MB_RX_N3")
	)
	(segment
		(start 75.18146 -24.329898)
		(end 75.584812 -24.329898)
		(width 0.21336)
		(layer "B.Cu")
		(net "HBA_MB_RX_N3")
	)
	(segment
		(start 74.617326 -24.175974)
		(end 75.027536 -24.175974)
		(width 0.21336)
		(layer "B.Cu")
		(net "HBA_MB_RX_N3")
	)
	(segment
		(start 30.670246 -4.501134)
		(end 33.322006 -3.961638)
		(width 0.21336)
		(layer "B.Cu")
		(net "HBA_MB_RX_N3")
	)
	(segment
		(start 43.432476 -6.018784)
		(end 51.303936 -11.228578)
		(width 0.21336)
		(layer "B.Cu")
		(net "HBA_MB_RX_N3")
	)
	(segment
		(start 75.027536 -24.175974)
		(end 75.18146 -24.329898)
		(width 0.21336)
		(layer "B.Cu")
		(net "HBA_MB_RX_N3")
	)
	(segment
		(start 72.42429 -21.201888)
		(end 74.198734 -23.882604)
		(width 0.21336)
		(layer "B.Cu")
		(net "HBA_MB_RX_N3")
	)
	(segment
		(start 27.504898 -2.549906)
		(end 27.951684 -2.996692)
		(width 0.21336)
		(layer "B.Cu")
		(net "HBA_MB_RX_N3")
	)
	(segment
		(start 27.951684 -2.996692)
		(end 27.951684 -3.50901)
		(width 0.21336)
		(layer "B.Cu")
		(net "HBA_MB_RX_N3")
	)
	(segment
		(start 27.951684 -3.50901)
		(end 28.381706 -4.035552)
		(width 0.21336)
		(layer "B.Cu")
		(net "HBA_MB_RX_N3")
	)
	(segment
		(start 74.198734 -23.882604)
		(end 74.617326 -24.175974)
		(width 0.21336)
		(layer "B.Cu")
		(net "HBA_MB_RX_N3")
	)
	(segment
		(start 60.043822 -13.007594)
		(end 72.42429 -21.201888)
		(width 0.21336)
		(layer "B.Cu")
		(net "HBA_MB_RX_N3")
	)
	(segment
		(start 28.381706 -4.035552)
		(end 30.670246 -4.501134)
		(width 0.21336)
		(layer "B.Cu")
		(net "HBA_MB_RX_N3")
	)
	(segment
		(start 51.303936 -11.228578)
		(end 60.043822 -13.007594)
		(width 0.21336)
		(layer "B.Cu")
		(net "HBA_MB_RX_N3")
	)
	(segment
		(start 27.504898 -13.850112)
		(end 27.918918 -14.264132)
		(width 0.21336)
		(layer "B.Cu")
		(net "HBA_MB_RX_N2")
	)
	(segment
		(start 75.665584 -26.451306)
		(end 76.580238 -25.846278)
		(width 0.21336)
		(layer "B.Cu")
		(net "HBA_MB_RX_N2")
	)
	(segment
		(start 77.498194 -24.136604)
		(end 77.74051 -24.136604)
		(width 0.21336)
		(layer "B.Cu")
		(net "HBA_MB_RX_N2")
	)
	(segment
		(start 76.580238 -25.846278)
		(end 76.617322 -25.821894)
		(width 0.21336)
		(layer "B.Cu")
		(net "HBA_MB_RX_N2")
	)
	(segment
		(start 27.918918 -14.749526)
		(end 28.296616 -15.318232)
		(width 0.21336)
		(layer "B.Cu")
		(net "HBA_MB_RX_N2")
	)
	(segment
		(start 53.846984 -16.425164)
		(end 63.505842 -18.390362)
		(width 0.21336)
		(layer "B.Cu")
		(net "HBA_MB_RX_N2")
	)
	(segment
		(start 77.284834 -25.154382)
		(end 77.284834 -24.349964)
		(width 0.21336)
		(layer "B.Cu")
		(net "HBA_MB_RX_N2")
	)
	(segment
		(start 63.505842 -18.390362)
		(end 71.538084 -23.706074)
		(width 0.21336)
		(layer "B.Cu")
		(net "HBA_MB_RX_N2")
	)
	(segment
		(start 77.74051 -24.136604)
		(end 77.933804 -24.329898)
		(width 0.21336)
		(layer "B.Cu")
		(net "HBA_MB_RX_N2")
	)
	(segment
		(start 77.284834 -24.349964)
		(end 77.498194 -24.136604)
		(width 0.21336)
		(layer "B.Cu")
		(net "HBA_MB_RX_N2")
	)
	(segment
		(start 34.437828 -15.337282)
		(end 46.814994 -17.855438)
		(width 0.21336)
		(layer "B.Cu")
		(net "HBA_MB_RX_N2")
	)
	(segment
		(start 71.538084 -23.706074)
		(end 72.424544 -25.045162)
		(width 0.21336)
		(layer "B.Cu")
		(net "HBA_MB_RX_N2")
	)
	(segment
		(start 28.296616 -15.318232)
		(end 31.413704 -15.95247)
		(width 0.21336)
		(layer "B.Cu")
		(net "HBA_MB_RX_N2")
	)
	(segment
		(start 27.918918 -14.264132)
		(end 27.918918 -14.749526)
		(width 0.21336)
		(layer "B.Cu")
		(net "HBA_MB_RX_N2")
	)
	(segment
		(start 31.413704 -15.95247)
		(end 34.437828 -15.337282)
		(width 0.21336)
		(layer "B.Cu")
		(net "HBA_MB_RX_N2")
	)
	(segment
		(start 72.424544 -25.045162)
		(end 73.927716 -26.097738)
		(width 0.21336)
		(layer "B.Cu")
		(net "HBA_MB_RX_N2")
	)
	(segment
		(start 73.927716 -26.097738)
		(end 75.665584 -26.451306)
		(width 0.21336)
		(layer "B.Cu")
		(net "HBA_MB_RX_N2")
	)
	(segment
		(start 76.617322 -25.821894)
		(end 77.284834 -25.154382)
		(width 0.21336)
		(layer "B.Cu")
		(net "HBA_MB_RX_N2")
	)
	(segment
		(start 77.933804 -24.329898)
		(end 78.284832 -24.329898)
		(width 0.21336)
		(layer "B.Cu")
		(net "HBA_MB_RX_N2")
	)
	(segment
		(start 46.814994 -17.855438)
		(end 53.846984 -16.425164)
		(width 0.21336)
		(layer "B.Cu")
		(net "HBA_MB_RX_N2")
	)
	(segment
		(start 88.789256 -21.079714)
		(end 88.853772 -20.762722)
		(width 0.21336)
		(layer "B.Cu")
		(net "HBA_MB_RX_N1")
	)
	(segment
		(start 91.06027 -24.511)
		(end 90.706956 -23.977346)
		(width 0.21336)
		(layer "B.Cu")
		(net "HBA_MB_RX_N1")
	)
	(segment
		(start 89.748106 -22.52853)
		(end 89.812622 -22.211538)
		(width 0.21336)
		(layer "B.Cu")
		(net "HBA_MB_RX_N1")
	)
	(segment
		(start 79.560166 -18.480786)
		(end 78.029308 -18.169128)
		(width 0.21336)
		(layer "B.Cu")
		(net "HBA_MB_RX_N1")
	)
	(segment
		(start 101.84638 -34.314892)
		(end 101.677216 -33.483804)
		(width 0.21336)
		(layer "B.Cu")
		(net "HBA_MB_RX_N1")
	)
	(segment
		(start 89.812622 -22.211538)
		(end 89.459308 -21.677884)
		(width 0.21336)
		(layer "B.Cu")
		(net "HBA_MB_RX_N1")
	)
	(segment
		(start 89.14257 -21.613368)
		(end 88.789256 -21.079714)
		(width 0.21336)
		(layer "B.Cu")
		(net "HBA_MB_RX_N1")
	)
	(segment
		(start 83.023964 -18.624296)
		(end 80.939386 -18.200116)
		(width 0.21336)
		(layer "B.Cu")
		(net "HBA_MB_RX_N1")
	)
	(segment
		(start 91.730322 -25.10917)
		(end 91.377008 -24.575516)
		(width 0.21336)
		(layer "B.Cu")
		(net "HBA_MB_RX_N1")
	)
	(segment
		(start 76.012802 -22.079966)
		(end 75.584812 -22.079966)
		(width 0.21336)
		(layer "B.Cu")
		(net "HBA_MB_RX_N1")
	)
	(segment
		(start 91.377008 -24.575516)
		(end 91.06027 -24.511)
		(width 0.21336)
		(layer "B.Cu")
		(net "HBA_MB_RX_N1")
	)
	(segment
		(start 88.853772 -20.762722)
		(end 88.500458 -20.229068)
		(width 0.21336)
		(layer "B.Cu")
		(net "HBA_MB_RX_N1")
	)
	(segment
		(start 77.293724 -18.656554)
		(end 77.070204 -19.75358)
		(width 0.21336)
		(layer "B.Cu")
		(net "HBA_MB_RX_N1")
	)
	(segment
		(start 101.430074 -35.049968)
		(end 101.84638 -34.633662)
		(width 0.21336)
		(layer "B.Cu")
		(net "HBA_MB_RX_N1")
	)
	(segment
		(start 84.279486 -18.368772)
		(end 83.023964 -18.624296)
		(width 0.21336)
		(layer "B.Cu")
		(net "HBA_MB_RX_N1")
	)
	(segment
		(start 97.340166 -30.258766)
		(end 93.422216 -27.665172)
		(width 0.21336)
		(layer "B.Cu")
		(net "HBA_MB_RX_N1")
	)
	(segment
		(start 86.393528 -18.798794)
		(end 84.279486 -18.368772)
		(width 0.21336)
		(layer "B.Cu")
		(net "HBA_MB_RX_N1")
	)
	(segment
		(start 77.070204 -19.75358)
		(end 77.070204 -21.505926)
		(width 0.21336)
		(layer "B.Cu")
		(net "HBA_MB_RX_N1")
	)
	(segment
		(start 90.771472 -23.660354)
		(end 90.418158 -23.1267)
		(width 0.21336)
		(layer "B.Cu")
		(net "HBA_MB_RX_N1")
	)
	(segment
		(start 91.665806 -25.426162)
		(end 91.730322 -25.10917)
		(width 0.21336)
		(layer "B.Cu")
		(net "HBA_MB_RX_N1")
	)
	(segment
		(start 101.677216 -33.483804)
		(end 101.259132 -32.852614)
		(width 0.21336)
		(layer "B.Cu")
		(net "HBA_MB_RX_N1")
	)
	(segment
		(start 78.029308 -18.169128)
		(end 77.293724 -18.656554)
		(width 0.21336)
		(layer "B.Cu")
		(net "HBA_MB_RX_N1")
	)
	(segment
		(start 101.259132 -32.852614)
		(end 97.34042 -30.258512)
		(width 0.21336)
		(layer "B.Cu")
		(net "HBA_MB_RX_N1")
	)
	(segment
		(start 76.114656 -21.978112)
		(end 76.012802 -22.079966)
		(width 0.21336)
		(layer "B.Cu")
		(net "HBA_MB_RX_N1")
	)
	(segment
		(start 101.84638 -34.633662)
		(end 101.84638 -34.314892)
		(width 0.21336)
		(layer "B.Cu")
		(net "HBA_MB_RX_N1")
	)
	(segment
		(start 76.598018 -21.978112)
		(end 76.114656 -21.978112)
		(width 0.21336)
		(layer "B.Cu")
		(net "HBA_MB_RX_N1")
	)
	(segment
		(start 88.500458 -20.229068)
		(end 86.393528 -18.798794)
		(width 0.21336)
		(layer "B.Cu")
		(net "HBA_MB_RX_N1")
	)
	(segment
		(start 89.459308 -21.677884)
		(end 89.14257 -21.613368)
		(width 0.21336)
		(layer "B.Cu")
		(net "HBA_MB_RX_N1")
	)
	(segment
		(start 92.01912 -25.959816)
		(end 91.665806 -25.426162)
		(width 0.21336)
		(layer "B.Cu")
		(net "HBA_MB_RX_N1")
	)
	(segment
		(start 93.422216 -27.665172)
		(end 92.336112 -26.024332)
		(width 0.21336)
		(layer "B.Cu")
		(net "HBA_MB_RX_N1")
	)
	(segment
		(start 90.10142 -23.062184)
		(end 89.748106 -22.52853)
		(width 0.21336)
		(layer "B.Cu")
		(net "HBA_MB_RX_N1")
	)
	(segment
		(start 80.939386 -18.200116)
		(end 79.560166 -18.480786)
		(width 0.21336)
		(layer "B.Cu")
		(net "HBA_MB_RX_N1")
	)
	(segment
		(start 77.070204 -21.505926)
		(end 76.598018 -21.978112)
		(width 0.21336)
		(layer "B.Cu")
		(net "HBA_MB_RX_N1")
	)
	(segment
		(start 92.336112 -26.024332)
		(end 92.01912 -25.959816)
		(width 0.21336)
		(layer "B.Cu")
		(net "HBA_MB_RX_N1")
	)
	(segment
		(start 90.706956 -23.977346)
		(end 90.771472 -23.660354)
		(width 0.21336)
		(layer "B.Cu")
		(net "HBA_MB_RX_N1")
	)
	(segment
		(start 90.418158 -23.1267)
		(end 90.10142 -23.062184)
		(width 0.21336)
		(layer "B.Cu")
		(net "HBA_MB_RX_N1")
	)
	(segment
		(start 97.34042 -30.258512)
		(end 97.340166 -30.258766)
		(width 0.21336)
		(layer "B.Cu")
		(net "HBA_MB_RX_N1")
	)
	(segment
		(start 80.57007 -26.870406)
		(end 80.634586 -26.553414)
		(width 0.21336)
		(layer "B.Cu")
		(net "HBA_MB_RX_N0")
	)
	(segment
		(start 79.81188 -22.013672)
		(end 79.354934 -21.920708)
		(width 0.21336)
		(layer "B.Cu")
		(net "HBA_MB_RX_N0")
	)
	(segment
		(start 96.468184 -49.028096)
		(end 94.762828 -47.899574)
		(width 0.21336)
		(layer "B.Cu")
		(net "HBA_MB_RX_N0")
	)
	(segment
		(start 79.870554 -24.001476)
		(end 80.165956 -22.54885)
		(width 0.21336)
		(layer "B.Cu")
		(net "HBA_MB_RX_N0")
	)
	(segment
		(start 99.74961 -49.929034)
		(end 99.571048 -49.659286)
		(width 0.21336)
		(layer "B.Cu")
		(net "HBA_MB_RX_N0")
	)
	(segment
		(start 100.376736 -50.056542)
		(end 99.74961 -49.929034)
		(width 0.21336)
		(layer "B.Cu")
		(net "HBA_MB_RX_N0")
	)
	(segment
		(start 78.798928 -22.079966)
		(end 78.284832 -22.079966)
		(width 0.21336)
		(layer "B.Cu")
		(net "HBA_MB_RX_N0")
	)
	(segment
		(start 100.646484 -49.878234)
		(end 100.376736 -50.056542)
		(width 0.21336)
		(layer "B.Cu")
		(net "HBA_MB_RX_N0")
	)
	(segment
		(start 81.593436 -28.00223)
		(end 81.240122 -27.468576)
		(width 0.21336)
		(layer "B.Cu")
		(net "HBA_MB_RX_N0")
	)
	(segment
		(start 82.198972 -28.917392)
		(end 81.882234 -28.852876)
		(width 0.21336)
		(layer "B.Cu")
		(net "HBA_MB_RX_N0")
	)
	(segment
		(start 98.674174 -49.710086)
		(end 98.047048 -49.582578)
		(width 0.21336)
		(layer "B.Cu")
		(net "HBA_MB_RX_N0")
	)
	(segment
		(start 97.868486 -49.313084)
		(end 96.468184 -49.028096)
		(width 0.21336)
		(layer "B.Cu")
		(net "HBA_MB_RX_N0")
	)
	(segment
		(start 98.943922 -49.531778)
		(end 98.674174 -49.710086)
		(width 0.21336)
		(layer "B.Cu")
		(net "HBA_MB_RX_N0")
	)
	(segment
		(start 101.430074 -51.74996)
		(end 101.844094 -51.33594)
		(width 0.21336)
		(layer "B.Cu")
		(net "HBA_MB_RX_N0")
	)
	(segment
		(start 101.844094 -51.33594)
		(end 101.844094 -50.867564)
		(width 0.21336)
		(layer "B.Cu")
		(net "HBA_MB_RX_N0")
	)
	(segment
		(start 80.281272 -26.01976)
		(end 79.870554 -24.001476)
		(width 0.21336)
		(layer "B.Cu")
		(net "HBA_MB_RX_N0")
	)
	(segment
		(start 81.882234 -28.852876)
		(end 81.52892 -28.319222)
		(width 0.21336)
		(layer "B.Cu")
		(net "HBA_MB_RX_N0")
	)
	(segment
		(start 81.52892 -28.319222)
		(end 81.593436 -28.00223)
		(width 0.21336)
		(layer "B.Cu")
		(net "HBA_MB_RX_N0")
	)
	(segment
		(start 79.354934 -21.920708)
		(end 78.958186 -21.920708)
		(width 0.21336)
		(layer "B.Cu")
		(net "HBA_MB_RX_N0")
	)
	(segment
		(start 80.923384 -27.40406)
		(end 80.57007 -26.870406)
		(width 0.21336)
		(layer "B.Cu")
		(net "HBA_MB_RX_N0")
	)
	(segment
		(start 78.958186 -21.920708)
		(end 78.798928 -22.079966)
		(width 0.21336)
		(layer "B.Cu")
		(net "HBA_MB_RX_N0")
	)
	(segment
		(start 94.762828 -47.899574)
		(end 82.198972 -28.917392)
		(width 0.21336)
		(layer "B.Cu")
		(net "HBA_MB_RX_N0")
	)
	(segment
		(start 101.27361 -50.005742)
		(end 100.646484 -49.878234)
		(width 0.21336)
		(layer "B.Cu")
		(net "HBA_MB_RX_N0")
	)
	(segment
		(start 80.165956 -22.54885)
		(end 79.81188 -22.013672)
		(width 0.21336)
		(layer "B.Cu")
		(net "HBA_MB_RX_N0")
	)
	(segment
		(start 99.571048 -49.659286)
		(end 98.943922 -49.531778)
		(width 0.21336)
		(layer "B.Cu")
		(net "HBA_MB_RX_N0")
	)
	(segment
		(start 98.047048 -49.582578)
		(end 97.868486 -49.313084)
		(width 0.21336)
		(layer "B.Cu")
		(net "HBA_MB_RX_N0")
	)
	(segment
		(start 81.240122 -27.468576)
		(end 80.923384 -27.40406)
		(width 0.21336)
		(layer "B.Cu")
		(net "HBA_MB_RX_N0")
	)
	(segment
		(start 101.844094 -50.867564)
		(end 101.27361 -50.005742)
		(width 0.21336)
		(layer "B.Cu")
		(net "HBA_MB_RX_N0")
	)
	(segment
		(start 80.634586 -26.553414)
		(end 80.281272 -26.01976)
		(width 0.21336)
		(layer "B.Cu")
		(net "HBA_MB_RX_N0")
	)
	(segment
		(start 81.52511 -7.04469)
		(end 81.8134 -6.7564)
		(width 0.18288)
		(layer "F.Cu")
		(net "ENIN_P1")
	)
	(segment
		(start 81.52511 -8.1407)
		(end 81.52511 -7.04469)
		(width 0.18288)
		(layer "F.Cu")
		(net "ENIN_P1")
	)
	(via
		(at 81.8134 -6.7564)
		(size 0.7112)
		(drill 0.254)
		(layers "F.Cu" "B.Cu")
		(net "ENIN_P1")
	)
	(segment
		(start 81.8134 -6.7564)
		(end 81.8134 -8.19912)
		(width 0.18288)
		(layer "B.Cu")
		(net "ENIN_P1")
	)
	(segment
		(start 81.8134 -8.19912)
		(end 81.63052 -8.382)
		(width 0.18288)
		(layer "B.Cu")
		(net "ENIN_P1")
	)
	(segment
		(start 81.63052 -8.382)
		(end 81.01584 -8.382)
		(width 0.18288)
		(layer "B.Cu")
		(net "ENIN_P1")
	)
	(segment
		(start 79.9846 -11.7602)
		(end 80.3656 -11.3792)
		(width 0.254)
		(layer "B.Cu")
		(net "CEXT_P5")
	)
	(segment
		(start 79.5528 -11.7602)
		(end 79.9846 -11.7602)
		(width 0.254)
		(layer "B.Cu")
		(net "CEXT_P5")
	)
	(segment
		(start 80.3656 -11.3792)
		(end 80.3656 -10.2616)
		(width 0.254)
		(layer "B.Cu")
		(net "CEXT_P5")
	)
	(segment
		(start 74.556366 -14.873478)
		(end 77.794866 -14.873478)
		(width 0.254)
		(layer "B.Cu")
		(net "P5V_R_E1")
	)
	(segment
		(start 78.116176 -14.552168)
		(end 78.265782 -14.402562)
		(width 0.254)
		(layer "B.Cu")
		(net "P5V_R_E1")
	)
	(segment
		(start 78.265782 -14.402562)
		(end 80.422496 -14.402562)
		(width 0.254)
		(layer "B.Cu")
		(net "P5V_R_E1")
	)
	(segment
		(start 77.794866 -14.873478)
		(end 78.116176 -14.552168)
		(width 0.254)
		(layer "B.Cu")
		(net "P5V_R_E1")
	)
	(via
		(at 86.106 -50.419)
		(size 0.5588)
		(drill 0.3048)
		(layers "F.Cu" "B.Cu")
		(net "P5V")
	)
	(via
		(at 85.09 -50.419)
		(size 0.5588)
		(drill 0.3048)
		(layers "F.Cu" "B.Cu")
		(net "P5V")
	)
	(via
		(at 70.729348 -13.064998)
		(size 0.5588)
		(drill 0.3048)
		(layers "F.Cu" "B.Cu")
		(net "P5V")
	)
	(via
		(at 86.106 -49.149)
		(size 0.5588)
		(drill 0.3048)
		(layers "F.Cu" "B.Cu")
		(net "P5V")
	)
	(via
		(at 13.377418 -21.171154)
		(size 0.5588)
		(drill 0.3048)
		(layers "F.Cu" "B.Cu")
		(net "P5V")
	)
	(via
		(at 15.339822 -21.319236)
		(size 0.5588)
		(drill 0.3048)
		(layers "F.Cu" "B.Cu")
		(net "P5V")
	)
	(via
		(at 71.618856 -12.129008)
		(size 0.5588)
		(drill 0.3048)
		(layers "F.Cu" "B.Cu")
		(net "P5V")
	)
	(via
		(at 14.393418 -21.171154)
		(size 0.5588)
		(drill 0.3048)
		(layers "F.Cu" "B.Cu")
		(net "P5V")
	)
	(via
		(at 85.09 -51.689)
		(size 0.5588)
		(drill 0.3048)
		(layers "F.Cu" "B.Cu")
		(net "P5V")
	)
	(via
		(at 71.665592 -13.049504)
		(size 0.5588)
		(drill 0.3048)
		(layers "F.Cu" "B.Cu")
		(net "P5V")
	)
	(via
		(at 70.682612 -12.144502)
		(size 0.5588)
		(drill 0.3048)
		(layers "F.Cu" "B.Cu")
		(net "P5V")
	)
	(via
		(at 85.09 -49.149)
		(size 0.5588)
		(drill 0.3048)
		(layers "F.Cu" "B.Cu")
		(net "P5V")
	)
	(via
		(at 15.359126 -20.274026)
		(size 0.5588)
		(drill 0.3048)
		(layers "F.Cu" "B.Cu")
		(net "P5V")
	)
	(via
		(at 71.651622 -14.016736)
		(size 0.5588)
		(drill 0.3048)
		(layers "F.Cu" "B.Cu")
		(net "P5V")
	)
	(via
		(at 86.106 -51.689)
		(size 0.5588)
		(drill 0.3048)
		(layers "F.Cu" "B.Cu")
		(net "P5V")
	)
	(via
		(at 70.715378 -14.03223)
		(size 0.5588)
		(drill 0.3048)
		(layers "F.Cu" "B.Cu")
		(net "P5V")
	)
	(segment
		(start 132.180076 -22.049994)
		(end 132.180076 -23.320502)
		(width 0.508)
		(layer "B.Cu")
		(net "P5V")
	)
	(segment
		(start 74.316336 -13.335)
		(end 74.883264 -13.901928)
		(width 0.508)
		(layer "B.Cu")
		(net "P5V")
	)
	(segment
		(start 132.180076 -20.779486)
		(end 132.180076 -22.049994)
		(width 0.508)
		(layer "B.Cu")
		(net "P5V")
	)
	(segment
		(start 74.883264 -13.901928)
		(end 76.312776 -13.901928)
		(width 0.508)
		(layer "B.Cu")
		(net "P5V")
	)
	(segment
		(start 73.025 -13.335)
		(end 74.316336 -13.335)
		(width 0.508)
		(layer "B.Cu")
		(net "P5V")
	)
	(segment
		(start 130.909568 -22.049994)
		(end 132.180076 -22.049994)
		(width 0.508)
		(layer "In3.Cu")
		(net "P5V")
	)
	(segment
		(start 132.180076 -20.779486)
		(end 132.180076 -22.049994)
		(width 0.508)
		(layer "In3.Cu")
		(net "P5V")
	)
	(segment
		(start 132.180076 -22.049994)
		(end 133.450584 -22.049994)
		(width 0.508)
		(layer "In3.Cu")
		(net "P5V")
	)
	(segment
		(start 132.180076 -22.049994)
		(end 132.180076 -23.320502)
		(width 0.508)
		(layer "In3.Cu")
		(net "P5V")
	)
	(segment
		(start 85.4075 -5.08)
		(end 84.525612 -5.08)
		(width 0.508)
		(layer "F.Cu")
		(net "P3V3")
	)
	(segment
		(start 15.494 -17.272)
		(end 19.4564 -17.272)
		(width 0.508)
		(layer "F.Cu")
		(net "P3V3")
	)
	(segment
		(start 85.4075 -5.890514)
		(end 85.4075 -5.08)
		(width 0.508)
		(layer "F.Cu")
		(net "P3V3")
	)
	(segment
		(start 55.95874 -1.038098)
		(end 67.020948 -1.038098)
		(width 0.508)
		(layer "F.Cu")
		(net "P3V3")
	)
	(segment
		(start 55.054246 -9.029446)
		(end 55.5244 -9.4996)
		(width 0.508)
		(layer "F.Cu")
		(net "P3V3")
	)
	(segment
		(start 14.7066 -3.287776)
		(end 14.7066 -16.4846)
		(width 0.508)
		(layer "F.Cu")
		(net "P3V3")
	)
	(segment
		(start 53.721 -19.8755)
		(end 53.721 -20.8026)
		(width 0.508)
		(layer "F.Cu")
		(net "P3V3")
	)
	(segment
		(start 85.91042 -6.393434)
		(end 85.4075 -5.890514)
		(width 0.508)
		(layer "F.Cu")
		(net "P3V3")
	)
	(segment
		(start 122.8598 -57.7215)
		(end 122.8598 -58.552588)
		(width 0.508)
		(layer "F.Cu")
		(net "P3V3")
	)
	(segment
		(start 18.686018 -1.038098)
		(end 16.956278 -1.038098)
		(width 0.508)
		(layer "F.Cu")
		(net "P3V3")
	)
	(segment
		(start 67.020948 -1.038098)
		(end 68.08343 -2.10058)
		(width 0.508)
		(layer "F.Cu")
		(net "P3V3")
	)
	(segment
		(start 128.744472 -41.411144)
		(end 128.744472 -42.316146)
		(width 0.508)
		(layer "F.Cu")
		(net "P3V3")
	)
	(segment
		(start 85.91042 -7.86638)
		(end 85.91042 -6.393434)
		(width 0.508)
		(layer "F.Cu")
		(net "P3V3")
	)
	(segment
		(start 54.598824 -9.029446)
		(end 55.054246 -9.029446)
		(width 0.508)
		(layer "F.Cu")
		(net "P3V3")
	)
	(segment
		(start 53.721 -20.8026)
		(end 54.1274 -21.209)
		(width 0.508)
		(layer "F.Cu")
		(net "P3V3")
	)
	(segment
		(start 77.6605 -33.909)
		(end 76.708 -33.909)
		(width 0.508)
		(layer "F.Cu")
		(net "P3V3")
	)
	(segment
		(start 84.3407 -8.450834)
		(end 85.325966 -8.450834)
		(width 0.508)
		(layer "F.Cu")
		(net "P3V3")
	)
	(segment
		(start 85.325966 -8.450834)
		(end 85.91042 -7.86638)
		(width 0.508)
		(layer "F.Cu")
		(net "P3V3")
	)
	(segment
		(start 14.7066 -16.4846)
		(end 15.494 -17.272)
		(width 0.508)
		(layer "F.Cu")
		(net "P3V3")
	)
	(segment
		(start 16.956278 -1.038098)
		(end 14.7066 -3.287776)
		(width 0.508)
		(layer "F.Cu")
		(net "P3V3")
	)
	(segment
		(start 68.08343 -3.00482)
		(end 65.554352 -5.533898)
		(width 0.508)
		(layer "F.Cu")
		(net "P3V3")
	)
	(segment
		(start 68.08343 -2.10058)
		(end 68.08343 -3.00482)
		(width 0.508)
		(layer "F.Cu")
		(net "P3V3")
	)
	(via
		(at 79.871316 -54.1655)
		(size 0.5588)
		(drill 0.3048)
		(layers "F.Cu" "B.Cu")
		(net "P3V3")
	)
	(via
		(at 122.8598 -58.552588)
		(size 0.5588)
		(drill 0.3048)
		(layers "F.Cu" "B.Cu")
		(net "P3V3")
	)
	(via
		(at 71.26097 -15.631668)
		(size 0.5588)
		(drill 0.3048)
		(layers "F.Cu" "B.Cu")
		(net "P3V3")
	)
	(via
		(at 55.95874 -1.038098)
		(size 0.508)
		(drill 0.254)
		(layers "F.Cu" "B.Cu")
		(net "P3V3")
	)
	(via
		(at 68.08343 -2.10058)
		(size 0.508)
		(drill 0.254)
		(layers "F.Cu" "B.Cu")
		(net "P3V3")
	)
	(via
		(at 84.525612 -5.08)
		(size 0.5588)
		(drill 0.3048)
		(layers "F.Cu" "B.Cu")
		(net "P3V3")
	)
	(via
		(at 76.708 -33.909)
		(size 0.5588)
		(drill 0.3048)
		(layers "F.Cu" "B.Cu")
		(net "P3V3")
	)
	(via
		(at 128.744472 -42.316146)
		(size 0.508)
		(drill 0.254)
		(layers "F.Cu" "B.Cu")
		(net "P3V3")
	)
	(via
		(at 121.945654 -58.576464)
		(size 0.5588)
		(drill 0.3048)
		(layers "F.Cu" "B.Cu")
		(net "P3V3")
	)
	(via
		(at 55.5244 -9.4996)
		(size 0.508)
		(drill 0.254)
		(layers "F.Cu" "B.Cu")
		(net "P3V3")
	)
	(via
		(at 18.686018 -1.038098)
		(size 0.508)
		(drill 0.254)
		(layers "F.Cu" "B.Cu")
		(net "P3V3")
	)
	(via
		(at 76.685902 -32.974534)
		(size 0.5588)
		(drill 0.3048)
		(layers "F.Cu" "B.Cu")
		(net "P3V3")
	)
	(via
		(at 80.052164 -13.251688)
		(size 0.508)
		(drill 0.254)
		(layers "F.Cu" "B.Cu")
		(net "P3V3")
	)
	(via
		(at 72.210168 -15.62227)
		(size 0.5588)
		(drill 0.3048)
		(layers "F.Cu" "B.Cu")
		(net "P3V3")
	)
	(via
		(at 19.4564 -17.272)
		(size 0.508)
		(drill 0.254)
		(layers "F.Cu" "B.Cu")
		(net "P3V3")
	)
	(via
		(at 65.554352 -5.533898)
		(size 0.508)
		(drill 0.254)
		(layers "F.Cu" "B.Cu")
		(net "P3V3")
	)
	(via
		(at 54.1274 -21.209)
		(size 0.508)
		(drill 0.254)
		(layers "F.Cu" "B.Cu")
		(net "P3V3")
	)
	(segment
		(start 19.4564 -17.272)
		(end 22.098 -19.9136)
		(width 0.508)
		(layer "B.Cu")
		(net "P3V3")
	)
	(segment
		(start 81.01584 -12.267184)
		(end 80.973422 -12.309602)
		(width 0.381)
		(layer "B.Cu")
		(net "P3V3")
	)
	(segment
		(start 65.554352 -5.533898)
		(end 65.554352 -6.75005)
		(width 0.508)
		(layer "B.Cu")
		(net "P3V3")
	)
	(segment
		(start 22.098 -19.9136)
		(end 53.594 -19.9136)
		(width 0.508)
		(layer "B.Cu")
		(net "P3V3")
	)
	(segment
		(start 80.62976 -54.1655)
		(end 79.871316 -54.1655)
		(width 0.381)
		(layer "B.Cu")
		(net "P3V3")
	)
	(segment
		(start 80.052164 -13.251688)
		(end 78.116176 -13.251688)
		(width 0.508)
		(layer "B.Cu")
		(net "P3V3")
	)
	(segment
		(start 68.08343 -2.10058)
		(end 70.699884 -2.10058)
		(width 0.381)
		(layer "B.Cu")
		(net "P3V3")
	)
	(segment
		(start 74.379582 -5.780278)
		(end 74.379582 -6.930644)
		(width 0.381)
		(layer "B.Cu")
		(net "P3V3")
	)
	(segment
		(start 65.554352 -6.75005)
		(end 62.804802 -9.4996)
		(width 0.508)
		(layer "B.Cu")
		(net "P3V3")
	)
	(segment
		(start 70.699884 -2.10058)
		(end 74.379582 -5.780278)
		(width 0.381)
		(layer "B.Cu")
		(net "P3V3")
	)
	(segment
		(start 80.973422 -12.933426)
		(end 80.370426 -12.933426)
		(width 0.508)
		(layer "B.Cu")
		(net "P3V3")
	)
	(segment
		(start 75.818238 -8.3693)
		(end 76.54036 -8.3693)
		(width 0.381)
		(layer "B.Cu")
		(net "P3V3")
	)
	(segment
		(start 53.594 -19.9136)
		(end 54.1274 -20.447)
		(width 0.508)
		(layer "B.Cu")
		(net "P3V3")
	)
	(segment
		(start 54.1274 -20.447)
		(end 54.1274 -21.209)
		(width 0.508)
		(layer "B.Cu")
		(net "P3V3")
	)
	(segment
		(start 80.973422 -12.309602)
		(end 80.973422 -12.933426)
		(width 0.381)
		(layer "B.Cu")
		(net "P3V3")
	)
	(segment
		(start 81.01584 -10.2616)
		(end 81.01584 -12.267184)
		(width 0.381)
		(layer "B.Cu")
		(net "P3V3")
	)
	(segment
		(start 74.379582 -6.930644)
		(end 75.818238 -8.3693)
		(width 0.381)
		(layer "B.Cu")
		(net "P3V3")
	)
	(segment
		(start 80.370426 -12.933426)
		(end 80.052164 -13.251688)
		(width 0.508)
		(layer "B.Cu")
		(net "P3V3")
	)
	(segment
		(start 62.804802 -9.4996)
		(end 55.5244 -9.4996)
		(width 0.508)
		(layer "B.Cu")
		(net "P3V3")
	)
	(segment
		(start 55.95874 -1.038098)
		(end 18.686018 -1.038098)
		(width 0.508)
		(layer "In3.Cu")
		(net "P3V3")
	)
	(segment
		(start 88.131904 -9.288272)
		(end 88.638634 -9.795002)
		(width 0.508)
		(layer "F.Cu")
		(net "P12V")
	)
	(segment
		(start 88.704166 -14.419834)
		(end 88.704166 -13.41374)
		(width 0.508)
		(layer "F.Cu")
		(net "P12V")
	)
	(segment
		(start 87.649304 -15.474696)
		(end 88.704166 -14.419834)
		(width 0.508)
		(layer "F.Cu")
		(net "P12V")
	)
	(segment
		(start 81.200752 -34.632138)
		(end 83.733386 -34.632138)
		(width 0.508)
		(layer "F.Cu")
		(net "P12V")
	)
	(segment
		(start 80.7085 -35.12439)
		(end 81.200752 -34.632138)
		(width 0.508)
		(layer "F.Cu")
		(net "P12V")
	)
	(segment
		(start 86.537292 -37.436044)
		(end 86.537292 -39.303452)
		(width 0.508)
		(layer "F.Cu")
		(net "P12V")
	)
	(segment
		(start 88.131904 -7.943596)
		(end 88.131904 -9.288272)
		(width 0.508)
		(layer "F.Cu")
		(net "P12V")
	)
	(segment
		(start 72.806052 -8.614918)
		(end 79.66583 -15.474696)
		(width 0.508)
		(layer "F.Cu")
		(net "P12V")
	)
	(segment
		(start 88.5825 -7.493)
		(end 88.131904 -7.943596)
		(width 0.508)
		(layer "F.Cu")
		(net "P12V")
	)
	(segment
		(start 80.7085 -36.068)
		(end 80.7085 -35.12439)
		(width 0.508)
		(layer "F.Cu")
		(net "P12V")
	)
	(segment
		(start 84.328 -43.306238)
		(end 84.328 -46.609)
		(width 0.508)
		(layer "F.Cu")
		(net "P12V")
	)
	(segment
		(start 83.733386 -34.632138)
		(end 86.537292 -37.436044)
		(width 0.508)
		(layer "F.Cu")
		(net "P12V")
	)
	(segment
		(start 85.541866 -42.092372)
		(end 84.328 -43.306238)
		(width 0.508)
		(layer "F.Cu")
		(net "P12V")
	)
	(segment
		(start 79.66583 -15.474696)
		(end 87.649304 -15.474696)
		(width 0.508)
		(layer "F.Cu")
		(net "P12V")
	)
	(segment
		(start 88.638634 -9.795002)
		(end 88.638634 -10.620502)
		(width 0.508)
		(layer "F.Cu")
		(net "P12V")
	)
	(via
		(at 89.044526 -25.974802)
		(size 0.5588)
		(drill 0.3048)
		(layers "F.Cu" "B.Cu")
		(net "P12V")
	)
	(via
		(at 86.537292 -39.303452)
		(size 0.5588)
		(drill 0.3048)
		(layers "F.Cu" "B.Cu")
		(net "P12V")
	)
	(via
		(at 89.654634 -10.620502)
		(size 0.5588)
		(drill 0.3048)
		(layers "F.Cu" "B.Cu")
		(net "P12V")
	)
	(via
		(at 89.68613 -11.566652)
		(size 0.5588)
		(drill 0.3048)
		(layers "F.Cu" "B.Cu")
		(net "P12V")
	)
	(via
		(at 89.535254 -26.83256)
		(size 0.5588)
		(drill 0.3048)
		(layers "F.Cu" "B.Cu")
		(net "P12V")
	)
	(via
		(at 89.720166 -13.41374)
		(size 0.5588)
		(drill 0.3048)
		(layers "F.Cu" "B.Cu")
		(net "P12V")
	)
	(via
		(at 91.141296 -27.647646)
		(size 0.5588)
		(drill 0.3048)
		(layers "F.Cu" "B.Cu")
		(net "P12V")
	)
	(via
		(at 90.551254 -26.83256)
		(size 0.5588)
		(drill 0.3048)
		(layers "F.Cu" "B.Cu")
		(net "P12V")
	)
	(via
		(at 88.638634 -10.620502)
		(size 0.5588)
		(drill 0.3048)
		(layers "F.Cu" "B.Cu")
		(net "P12V")
	)
	(via
		(at 84.328 -46.609)
		(size 0.5588)
		(drill 0.3048)
		(layers "F.Cu" "B.Cu")
		(net "P12V")
	)
	(via
		(at 88.67013 -11.566652)
		(size 0.5588)
		(drill 0.3048)
		(layers "F.Cu" "B.Cu")
		(net "P12V")
	)
	(via
		(at 89.110058 -27.679904)
		(size 0.5588)
		(drill 0.3048)
		(layers "F.Cu" "B.Cu")
		(net "P12V")
	)
	(via
		(at 88.669876 -12.485878)
		(size 0.5588)
		(drill 0.3048)
		(layers "F.Cu" "B.Cu")
		(net "P12V")
	)
	(via
		(at 86.557866 -40.228774)
		(size 0.5588)
		(drill 0.3048)
		(layers "F.Cu" "B.Cu")
		(net "P12V")
	)
	(via
		(at 86.557866 -41.154096)
		(size 0.5588)
		(drill 0.3048)
		(layers "F.Cu" "B.Cu")
		(net "P12V")
	)
	(via
		(at 86.557866 -42.092372)
		(size 0.5588)
		(drill 0.3048)
		(layers "F.Cu" "B.Cu")
		(net "P12V")
	)
	(via
		(at 72.806052 -8.614918)
		(size 0.5588)
		(drill 0.3048)
		(layers "F.Cu" "B.Cu")
		(net "P12V")
	)
	(via
		(at 88.568784 -26.770584)
		(size 0.5588)
		(drill 0.3048)
		(layers "F.Cu" "B.Cu")
		(net "P12V")
	)
	(via
		(at 85.541866 -40.228774)
		(size 0.5588)
		(drill 0.3048)
		(layers "F.Cu" "B.Cu")
		(net "P12V")
	)
	(via
		(at 90.06332 -25.997154)
		(size 0.5588)
		(drill 0.3048)
		(layers "F.Cu" "B.Cu")
		(net "P12V")
	)
	(via
		(at 85.521292 -39.303452)
		(size 0.5588)
		(drill 0.3048)
		(layers "F.Cu" "B.Cu")
		(net "P12V")
	)
	(via
		(at 89.685876 -12.485878)
		(size 0.5588)
		(drill 0.3048)
		(layers "F.Cu" "B.Cu")
		(net "P12V")
	)
	(via
		(at 85.541866 -41.154096)
		(size 0.5588)
		(drill 0.3048)
		(layers "F.Cu" "B.Cu")
		(net "P12V")
	)
	(via
		(at 85.541866 -42.092372)
		(size 0.5588)
		(drill 0.3048)
		(layers "F.Cu" "B.Cu")
		(net "P12V")
	)
	(via
		(at 88.704166 -13.41374)
		(size 0.5588)
		(drill 0.3048)
		(layers "F.Cu" "B.Cu")
		(net "P12V")
	)
	(via
		(at 90.126058 -27.679904)
		(size 0.5588)
		(drill 0.3048)
		(layers "F.Cu" "B.Cu")
		(net "P12V")
	)
	(segment
		(start 123.17984 -22.049994)
		(end 123.17984 -23.320502)
		(width 0.508)
		(layer "B.Cu")
		(net "P12V")
	)
	(segment
		(start 72.411082 -8.219948)
		(end 72.806052 -8.614918)
		(width 0.508)
		(layer "B.Cu")
		(net "P12V")
	)
	(segment
		(start 72.411082 -7.614412)
		(end 72.411082 -8.219948)
		(width 0.508)
		(layer "B.Cu")
		(net "P12V")
	)
	(segment
		(start 123.17984 -20.779486)
		(end 123.17984 -22.049994)
		(width 0.508)
		(layer "B.Cu")
		(net "P12V")
	)
	(segment
		(start 84.328 -45.6565)
		(end 84.328 -46.609)
		(width 0.508)
		(layer "B.Cu")
		(net "P12V")
	)
	(segment
		(start 121.909332 -22.049994)
		(end 123.17984 -22.049994)
		(width 0.508)
		(layer "In2.Cu")
		(net "P12V")
	)
	(segment
		(start 123.17984 -22.049994)
		(end 123.17984 -23.320502)
		(width 0.508)
		(layer "In2.Cu")
		(net "P12V")
	)
	(segment
		(start 123.17984 -22.049994)
		(end 124.450348 -22.049994)
		(width 0.508)
		(layer "In2.Cu")
		(net "P12V")
	)
	(segment
		(start 123.17984 -20.779486)
		(end 123.17984 -22.049994)
		(width 0.508)
		(layer "In2.Cu")
		(net "P12V")
	)
	(segment
		(start 49.094898 -2.549906)
		(end 47.462694 -0.917702)
		(width 0.254)
		(layer "F.Cu")
		(net "HDD_ACT_LED3")
	)
	(segment
		(start 21.345144 -0.917702)
		(end 19.59229 -2.670556)
		(width 0.254)
		(layer "F.Cu")
		(net "HDD_ACT_LED3")
	)
	(segment
		(start 19.59229 -6.769862)
		(end 18.95729 -7.404862)
		(width 0.254)
		(layer "F.Cu")
		(net "HDD_ACT_LED3")
	)
	(segment
		(start 19.59229 -2.670556)
		(end 19.59229 -6.769862)
		(width 0.254)
		(layer "F.Cu")
		(net "HDD_ACT_LED3")
	)
	(segment
		(start 47.462694 -0.917702)
		(end 21.345144 -0.917702)
		(width 0.254)
		(layer "F.Cu")
		(net "HDD_ACT_LED3")
	)
	(via
		(at 18.95729 -7.404862)
		(size 0.508)
		(drill 0.254)
		(layers "F.Cu" "B.Cu")
		(net "HDD_ACT_LED3")
	)
	(segment
		(start 18.95729 -7.404862)
		(end 17.062196 -9.299956)
		(width 0.254)
		(layer "B.Cu")
		(net "HDD_ACT_LED3")
	)
	(segment
		(start 17.062196 -9.299956)
		(end 13.899896 -9.299956)
		(width 0.254)
		(layer "B.Cu")
		(net "HDD_ACT_LED3")
	)
	(segment
		(start 49.53 -12.468606)
		(end 49.53 -10.559288)
		(width 0.254)
		(layer "F.Cu")
		(net "HDD_ACT_LED2")
	)
	(segment
		(start 49.094898 -12.903708)
		(end 49.53 -12.468606)
		(width 0.254)
		(layer "F.Cu")
		(net "HDD_ACT_LED2")
	)
	(segment
		(start 49.53 -10.559288)
		(end 48.292512 -9.3218)
		(width 0.254)
		(layer "F.Cu")
		(net "HDD_ACT_LED2")
	)
	(segment
		(start 48.292512 -9.3218)
		(end 19.0754 -9.3218)
		(width 0.254)
		(layer "F.Cu")
		(net "HDD_ACT_LED2")
	)
	(segment
		(start 49.094898 -13.850112)
		(end 49.094898 -12.903708)
		(width 0.254)
		(layer "F.Cu")
		(net "HDD_ACT_LED2")
	)
	(via
		(at 19.0754 -9.3218)
		(size 0.508)
		(drill 0.254)
		(layers "F.Cu" "B.Cu")
		(net "HDD_ACT_LED2")
	)
	(segment
		(start 19.0754 -9.3218)
		(end 18.097246 -10.299954)
		(width 0.254)
		(layer "B.Cu")
		(net "HDD_ACT_LED2")
	)
	(segment
		(start 18.097246 -10.299954)
		(end 13.899896 -10.299954)
		(width 0.254)
		(layer "B.Cu")
		(net "HDD_ACT_LED2")
	)
	(via
		(at 89.021666 -2.735072)
		(size 0.5588)
		(drill 0.3048)
		(layers "F.Cu" "B.Cu")
		(net "HDD_ACT_LED1")
	)
	(via
		(at 16.511524 -11.032236)
		(size 0.5588)
		(drill 0.3048)
		(layers "F.Cu" "B.Cu")
		(net "HDD_ACT_LED1")
	)
	(via
		(at 116.716556 -28.74645)
		(size 0.7112)
		(drill 0.3556)
		(layers "F.Cu" "B.Cu")
		(net "HDD_ACT_LED1")
	)
	(segment
		(start 89.021666 -2.735072)
		(end 90.355674 -2.735072)
		(width 0.254)
		(layer "B.Cu")
		(net "HDD_ACT_LED1")
	)
	(segment
		(start 114.778282 -26.808176)
		(end 116.716556 -28.74645)
		(width 0.254)
		(layer "B.Cu")
		(net "HDD_ACT_LED1")
	)
	(segment
		(start 16.511524 -11.032236)
		(end 16.243808 -11.299952)
		(width 0.254)
		(layer "B.Cu")
		(net "HDD_ACT_LED1")
	)
	(segment
		(start 16.243808 -11.299952)
		(end 13.899896 -11.299952)
		(width 0.254)
		(layer "B.Cu")
		(net "HDD_ACT_LED1")
	)
	(segment
		(start 94.041976 -6.421374)
		(end 94.041976 -25.023318)
		(width 0.254)
		(layer "B.Cu")
		(net "HDD_ACT_LED1")
	)
	(segment
		(start 94.041976 -25.023318)
		(end 95.826834 -26.808176)
		(width 0.254)
		(layer "B.Cu")
		(net "HDD_ACT_LED1")
	)
	(segment
		(start 95.826834 -26.808176)
		(end 114.778282 -26.808176)
		(width 0.254)
		(layer "B.Cu")
		(net "HDD_ACT_LED1")
	)
	(segment
		(start 123.020074 -35.049968)
		(end 116.716556 -28.74645)
		(width 0.254)
		(layer "B.Cu")
		(net "HDD_ACT_LED1")
	)
	(segment
		(start 90.355674 -2.735072)
		(end 94.041976 -6.421374)
		(width 0.254)
		(layer "B.Cu")
		(net "HDD_ACT_LED1")
	)
	(segment
		(start 77.675232 -8.163306)
		(end 82.996024 -2.842514)
		(width 0.254)
		(layer "In2.Cu")
		(net "HDD_ACT_LED1")
	)
	(segment
		(start 55.506112 -2.130298)
		(end 56.411368 -2.130298)
		(width 0.254)
		(layer "In2.Cu")
		(net "HDD_ACT_LED1")
	)
	(segment
		(start 20.410424 -4.135628)
		(end 20.410424 -2.99212)
		(width 0.254)
		(layer "In2.Cu")
		(net "HDD_ACT_LED1")
	)
	(segment
		(start 57.085992 -1.455674)
		(end 69.974714 -1.455674)
		(width 0.254)
		(layer "In2.Cu")
		(net "HDD_ACT_LED1")
	)
	(segment
		(start 16.511524 -8.034528)
		(end 20.410424 -4.135628)
		(width 0.254)
		(layer "In2.Cu")
		(net "HDD_ACT_LED1")
	)
	(segment
		(start 88.914224 -2.842514)
		(end 89.021666 -2.735072)
		(width 0.254)
		(layer "In2.Cu")
		(net "HDD_ACT_LED1")
	)
	(segment
		(start 76.682346 -8.163306)
		(end 77.675232 -8.163306)
		(width 0.254)
		(layer "In2.Cu")
		(net "HDD_ACT_LED1")
	)
	(segment
		(start 21.908516 -1.494028)
		(end 54.869842 -1.494028)
		(width 0.254)
		(layer "In2.Cu")
		(net "HDD_ACT_LED1")
	)
	(segment
		(start 82.996024 -2.842514)
		(end 88.914224 -2.842514)
		(width 0.254)
		(layer "In2.Cu")
		(net "HDD_ACT_LED1")
	)
	(segment
		(start 56.411368 -2.130298)
		(end 57.085992 -1.455674)
		(width 0.254)
		(layer "In2.Cu")
		(net "HDD_ACT_LED1")
	)
	(segment
		(start 54.869842 -1.494028)
		(end 55.506112 -2.130298)
		(width 0.254)
		(layer "In2.Cu")
		(net "HDD_ACT_LED1")
	)
	(segment
		(start 69.974714 -1.455674)
		(end 76.682346 -8.163306)
		(width 0.254)
		(layer "In2.Cu")
		(net "HDD_ACT_LED1")
	)
	(segment
		(start 20.410424 -2.99212)
		(end 21.908516 -1.494028)
		(width 0.254)
		(layer "In2.Cu")
		(net "HDD_ACT_LED1")
	)
	(segment
		(start 16.511524 -11.032236)
		(end 16.511524 -8.034528)
		(width 0.254)
		(layer "In2.Cu")
		(net "HDD_ACT_LED1")
	)
	(via
		(at 119.519954 -28.528772)
		(size 0.7112)
		(drill 0.3556)
		(layers "F.Cu" "B.Cu")
		(net "HDD_ACT_LED0")
	)
	(via
		(at 16.183102 -12.29995)
		(size 0.5588)
		(drill 0.3048)
		(layers "F.Cu" "B.Cu")
		(net "HDD_ACT_LED0")
	)
	(via
		(at 88.244934 -2.176272)
		(size 0.5588)
		(drill 0.3048)
		(layers "F.Cu" "B.Cu")
		(net "HDD_ACT_LED0")
	)
	(segment
		(start 128.436878 -33.75152)
		(end 124.742702 -33.75152)
		(width 0.254)
		(layer "B.Cu")
		(net "HDD_ACT_LED0")
	)
	(segment
		(start 117.240558 -26.249376)
		(end 119.519954 -28.528772)
		(width 0.254)
		(layer "B.Cu")
		(net "HDD_ACT_LED0")
	)
	(segment
		(start 126.32182 -39.520876)
		(end 129.428748 -36.413948)
		(width 0.254)
		(layer "B.Cu")
		(net "HDD_ACT_LED0")
	)
	(segment
		(start 126.32182 -46.693582)
		(end 126.32182 -39.520876)
		(width 0.254)
		(layer "B.Cu")
		(net "HDD_ACT_LED0")
	)
	(segment
		(start 13.899896 -12.29995)
		(end 16.183102 -12.29995)
		(width 0.254)
		(layer "B.Cu")
		(net "HDD_ACT_LED0")
	)
	(segment
		(start 129.428748 -36.413948)
		(end 129.428748 -34.74339)
		(width 0.254)
		(layer "B.Cu")
		(net "HDD_ACT_LED0")
	)
	(segment
		(start 96.058482 -26.249376)
		(end 117.240558 -26.249376)
		(width 0.254)
		(layer "B.Cu")
		(net "HDD_ACT_LED0")
	)
	(segment
		(start 94.600776 -6.189726)
		(end 94.600776 -24.79167)
		(width 0.254)
		(layer "B.Cu")
		(net "HDD_ACT_LED0")
	)
	(segment
		(start 94.600776 -24.79167)
		(end 96.058482 -26.249376)
		(width 0.254)
		(layer "B.Cu")
		(net "HDD_ACT_LED0")
	)
	(segment
		(start 123.020074 -49.995328)
		(end 126.32182 -46.693582)
		(width 0.254)
		(layer "B.Cu")
		(net "HDD_ACT_LED0")
	)
	(segment
		(start 90.587322 -2.176272)
		(end 94.600776 -6.189726)
		(width 0.254)
		(layer "B.Cu")
		(net "HDD_ACT_LED0")
	)
	(segment
		(start 123.020074 -51.74996)
		(end 123.020074 -49.995328)
		(width 0.254)
		(layer "B.Cu")
		(net "HDD_ACT_LED0")
	)
	(segment
		(start 124.742702 -33.75152)
		(end 119.519954 -28.528772)
		(width 0.254)
		(layer "B.Cu")
		(net "HDD_ACT_LED0")
	)
	(segment
		(start 129.428748 -34.74339)
		(end 128.436878 -33.75152)
		(width 0.254)
		(layer "B.Cu")
		(net "HDD_ACT_LED0")
	)
	(segment
		(start 88.244934 -2.176272)
		(end 90.587322 -2.176272)
		(width 0.254)
		(layer "B.Cu")
		(net "HDD_ACT_LED0")
	)
	(segment
		(start 15.916402 -12.03325)
		(end 15.916402 -7.788402)
		(width 0.254)
		(layer "In2.Cu")
		(net "HDD_ACT_LED0")
	)
	(segment
		(start 19.794982 -3.909822)
		(end 19.794982 -2.659634)
		(width 0.254)
		(layer "In2.Cu")
		(net "HDD_ACT_LED0")
	)
	(segment
		(start 16.183102 -12.29995)
		(end 15.916402 -12.03325)
		(width 0.254)
		(layer "In2.Cu")
		(net "HDD_ACT_LED0")
	)
	(segment
		(start 82.77987 -2.176272)
		(end 88.244934 -2.176272)
		(width 0.254)
		(layer "In2.Cu")
		(net "HDD_ACT_LED0")
	)
	(segment
		(start 55.10149 -0.935228)
		(end 55.73776 -1.571498)
		(width 0.254)
		(layer "In2.Cu")
		(net "HDD_ACT_LED0")
	)
	(segment
		(start 70.206362 -0.896874)
		(end 75.747626 -6.438138)
		(width 0.254)
		(layer "In2.Cu")
		(net "HDD_ACT_LED0")
	)
	(segment
		(start 78.518004 -6.438138)
		(end 82.77987 -2.176272)
		(width 0.254)
		(layer "In2.Cu")
		(net "HDD_ACT_LED0")
	)
	(segment
		(start 75.747626 -6.438138)
		(end 78.518004 -6.438138)
		(width 0.254)
		(layer "In2.Cu")
		(net "HDD_ACT_LED0")
	)
	(segment
		(start 21.519388 -0.935228)
		(end 55.10149 -0.935228)
		(width 0.254)
		(layer "In2.Cu")
		(net "HDD_ACT_LED0")
	)
	(segment
		(start 19.794982 -2.659634)
		(end 21.519388 -0.935228)
		(width 0.254)
		(layer "In2.Cu")
		(net "HDD_ACT_LED0")
	)
	(segment
		(start 55.73776 -1.571498)
		(end 56.17972 -1.571498)
		(width 0.254)
		(layer "In2.Cu")
		(net "HDD_ACT_LED0")
	)
	(segment
		(start 56.17972 -1.571498)
		(end 56.854344 -0.896874)
		(width 0.254)
		(layer "In2.Cu")
		(net "HDD_ACT_LED0")
	)
	(segment
		(start 56.854344 -0.896874)
		(end 70.206362 -0.896874)
		(width 0.254)
		(layer "In2.Cu")
		(net "HDD_ACT_LED0")
	)
	(segment
		(start 15.916402 -7.788402)
		(end 19.794982 -3.909822)
		(width 0.254)
		(layer "In2.Cu")
		(net "HDD_ACT_LED0")
	)
	(segment
		(start 49.326038 -4.051046)
		(end 47.824898 -2.549906)
		(width 0.254)
		(layer "F.Cu")
		(net "HBA_PRSNT3_N")
	)
	(segment
		(start 15.475712 -13.935456)
		(end 15.475712 -16.299942)
		(width 0.254)
		(layer "F.Cu")
		(net "HBA_PRSNT3_N")
	)
	(segment
		(start 17.7546 -9.523984)
		(end 17.7546 -11.656568)
		(width 0.254)
		(layer "F.Cu")
		(net "HBA_PRSNT3_N")
	)
	(segment
		(start 20.359624 -2.988564)
		(end 20.359624 -6.91896)
		(width 0.254)
		(layer "F.Cu")
		(net "HBA_PRSNT3_N")
	)
	(segment
		(start 53.6194 -8.1407)
		(end 53.6194 -7.571486)
		(width 0.254)
		(layer "F.Cu")
		(net "HBA_PRSNT3_N")
	)
	(segment
		(start 54.598824 -8.140446)
		(end 54.59857 -8.1407)
		(width 0.254)
		(layer "F.Cu")
		(net "HBA_PRSNT3_N")
	)
	(segment
		(start 53.6194 -7.571486)
		(end 50.09896 -4.051046)
		(width 0.254)
		(layer "F.Cu")
		(net "HBA_PRSNT3_N")
	)
	(segment
		(start 21.663152 -1.685036)
		(end 20.359624 -2.988564)
		(width 0.254)
		(layer "F.Cu")
		(net "HBA_PRSNT3_N")
	)
	(segment
		(start 47.824898 -2.549906)
		(end 46.960028 -1.685036)
		(width 0.254)
		(layer "F.Cu")
		(net "HBA_PRSNT3_N")
	)
	(segment
		(start 17.7546 -11.656568)
		(end 15.475712 -13.935456)
		(width 0.254)
		(layer "F.Cu")
		(net "HBA_PRSNT3_N")
	)
	(segment
		(start 54.59857 -8.1407)
		(end 53.6194 -8.1407)
		(width 0.254)
		(layer "F.Cu")
		(net "HBA_PRSNT3_N")
	)
	(segment
		(start 46.960028 -1.685036)
		(end 21.663152 -1.685036)
		(width 0.254)
		(layer "F.Cu")
		(net "HBA_PRSNT3_N")
	)
	(segment
		(start 20.359624 -6.91896)
		(end 17.7546 -9.523984)
		(width 0.254)
		(layer "F.Cu")
		(net "HBA_PRSNT3_N")
	)
	(segment
		(start 50.09896 -4.051046)
		(end 49.326038 -4.051046)
		(width 0.254)
		(layer "F.Cu")
		(net "HBA_PRSNT3_N")
	)
	(via
		(at 15.475712 -16.299942)
		(size 0.508)
		(drill 0.254)
		(layers "F.Cu" "B.Cu")
		(net "HBA_PRSNT3_N")
	)
	(via
		(at 66.396362 -4.787392)
		(size 0.7112)
		(drill 0.3556)
		(layers "F.Cu" "B.Cu")
		(net "HBA_PRSNT3_N")
	)
	(segment
		(start 67.598544 -3.58521)
		(end 66.396362 -4.787392)
		(width 0.254)
		(layer "B.Cu")
		(net "HBA_PRSNT3_N")
	)
	(segment
		(start 64.351662 -4.787392)
		(end 66.396362 -4.787392)
		(width 0.254)
		(layer "B.Cu")
		(net "HBA_PRSNT3_N")
	)
	(segment
		(start 74.19467 -8.4582)
		(end 73.084182 -7.347712)
		(width 0.254)
		(layer "B.Cu")
		(net "HBA_PRSNT3_N")
	)
	(segment
		(start 76.894944 -11.2268)
		(end 75.728068 -11.2268)
		(width 0.254)
		(layer "B.Cu")
		(net "HBA_PRSNT3_N")
	)
	(segment
		(start 70.428358 -3.58521)
		(end 67.598544 -3.58521)
		(width 0.254)
		(layer "B.Cu")
		(net "HBA_PRSNT3_N")
	)
	(segment
		(start 47.824898 -2.549906)
		(end 50.706528 -5.431536)
		(width 0.254)
		(layer "B.Cu")
		(net "HBA_PRSNT3_N")
	)
	(segment
		(start 13.899896 -16.299942)
		(end 15.475712 -16.299942)
		(width 0.254)
		(layer "B.Cu")
		(net "HBA_PRSNT3_N")
	)
	(segment
		(start 63.707518 -5.431536)
		(end 64.351662 -4.787392)
		(width 0.254)
		(layer "B.Cu")
		(net "HBA_PRSNT3_N")
	)
	(segment
		(start 73.084182 -6.241034)
		(end 70.428358 -3.58521)
		(width 0.254)
		(layer "B.Cu")
		(net "HBA_PRSNT3_N")
	)
	(segment
		(start 50.706528 -5.431536)
		(end 63.707518 -5.431536)
		(width 0.254)
		(layer "B.Cu")
		(net "HBA_PRSNT3_N")
	)
	(segment
		(start 77.1906 -10.0203)
		(end 77.1906 -10.931144)
		(width 0.254)
		(layer "B.Cu")
		(net "HBA_PRSNT3_N")
	)
	(segment
		(start 75.728068 -11.2268)
		(end 74.19467 -9.693402)
		(width 0.254)
		(layer "B.Cu")
		(net "HBA_PRSNT3_N")
	)
	(segment
		(start 74.19467 -9.693402)
		(end 74.19467 -8.4582)
		(width 0.254)
		(layer "B.Cu")
		(net "HBA_PRSNT3_N")
	)
	(segment
		(start 73.084182 -7.347712)
		(end 73.084182 -6.241034)
		(width 0.254)
		(layer "B.Cu")
		(net "HBA_PRSNT3_N")
	)
	(segment
		(start 77.1906 -10.931144)
		(end 76.894944 -11.2268)
		(width 0.254)
		(layer "B.Cu")
		(net "HBA_PRSNT3_N")
	)
	(segment
		(start 47.824898 -13.850112)
		(end 47.824898 -13.269468)
		(width 0.254)
		(layer "F.Cu")
		(net "HBA_PRSNT2_N")
	)
	(segment
		(start 47.824898 -13.269468)
		(end 47.570644 -13.015214)
		(width 0.254)
		(layer "F.Cu")
		(net "HBA_PRSNT2_N")
	)
	(segment
		(start 22.164548 -13.015214)
		(end 19.508216 -15.671546)
		(width 0.254)
		(layer "F.Cu")
		(net "HBA_PRSNT2_N")
	)
	(segment
		(start 47.824898 -14.106398)
		(end 47.824898 -13.850112)
		(width 0.254)
		(layer "F.Cu")
		(net "HBA_PRSNT2_N")
	)
	(segment
		(start 52.705 -18.9865)
		(end 47.824898 -14.106398)
		(width 0.254)
		(layer "F.Cu")
		(net "HBA_PRSNT2_N")
	)
	(segment
		(start 47.570644 -13.015214)
		(end 22.164548 -13.015214)
		(width 0.254)
		(layer "F.Cu")
		(net "HBA_PRSNT2_N")
	)
	(segment
		(start 53.721 -18.9865)
		(end 52.705 -18.9865)
		(width 0.254)
		(layer "F.Cu")
		(net "HBA_PRSNT2_N")
	)
	(via
		(at 66.532506 -2.759456)
		(size 0.7112)
		(drill 0.3556)
		(layers "F.Cu" "B.Cu")
		(net "HBA_PRSNT2_N")
	)
	(via
		(at 19.508216 -15.671546)
		(size 0.508)
		(drill 0.254)
		(layers "F.Cu" "B.Cu")
		(net "HBA_PRSNT2_N")
	)
	(segment
		(start 21.5392 -1.5748)
		(end 21.2852 -1.8288)
		(width 0.254)
		(layer "B.Cu")
		(net "HBA_PRSNT2_N")
	)
	(segment
		(start 73.642982 -7.116064)
		(end 73.642982 -6.009386)
		(width 0.254)
		(layer "B.Cu")
		(net "HBA_PRSNT2_N")
	)
	(segment
		(start 75.582272 -10.0203)
		(end 74.775314 -9.213342)
		(width 0.254)
		(layer "B.Cu")
		(net "HBA_PRSNT2_N")
	)
	(segment
		(start 73.642982 -6.009386)
		(end 70.393052 -2.759456)
		(width 0.254)
		(layer "B.Cu")
		(net "HBA_PRSNT2_N")
	)
	(segment
		(start 19.508216 -10.463784)
		(end 19.508216 -15.671546)
		(width 0.254)
		(layer "B.Cu")
		(net "HBA_PRSNT2_N")
	)
	(segment
		(start 70.393052 -2.759456)
		(end 66.532506 -2.759456)
		(width 0.254)
		(layer "B.Cu")
		(net "HBA_PRSNT2_N")
	)
	(segment
		(start 19.508216 -15.671546)
		(end 17.879822 -17.29994)
		(width 0.254)
		(layer "B.Cu")
		(net "HBA_PRSNT2_N")
	)
	(segment
		(start 74.775314 -8.248396)
		(end 73.642982 -7.116064)
		(width 0.254)
		(layer "B.Cu")
		(net "HBA_PRSNT2_N")
	)
	(segment
		(start 61.465968 -2.759456)
		(end 60.281312 -1.5748)
		(width 0.254)
		(layer "B.Cu")
		(net "HBA_PRSNT2_N")
	)
	(segment
		(start 17.879822 -17.29994)
		(end 13.899896 -17.29994)
		(width 0.254)
		(layer "B.Cu")
		(net "HBA_PRSNT2_N")
	)
	(segment
		(start 76.54036 -10.0203)
		(end 75.582272 -10.0203)
		(width 0.254)
		(layer "B.Cu")
		(net "HBA_PRSNT2_N")
	)
	(segment
		(start 21.2852 -1.8288)
		(end 21.2852 -8.6868)
		(width 0.254)
		(layer "B.Cu")
		(net "HBA_PRSNT2_N")
	)
	(segment
		(start 21.2852 -8.6868)
		(end 19.508216 -10.463784)
		(width 0.254)
		(layer "B.Cu")
		(net "HBA_PRSNT2_N")
	)
	(segment
		(start 66.532506 -2.759456)
		(end 61.465968 -2.759456)
		(width 0.254)
		(layer "B.Cu")
		(net "HBA_PRSNT2_N")
	)
	(segment
		(start 74.775314 -9.213342)
		(end 74.775314 -8.248396)
		(width 0.254)
		(layer "B.Cu")
		(net "HBA_PRSNT2_N")
	)
	(segment
		(start 60.281312 -1.5748)
		(end 21.5392 -1.5748)
		(width 0.254)
		(layer "B.Cu")
		(net "HBA_PRSNT2_N")
	)
	(segment
		(start 122.606054 -35.905948)
		(end 121.750074 -35.049968)
		(width 0.254)
		(layer "F.Cu")
		(net "HBA_PRSNT1_N")
	)
	(segment
		(start 127.728472 -40.522144)
		(end 127.728472 -39.653972)
		(width 0.254)
		(layer "F.Cu")
		(net "HBA_PRSNT1_N")
	)
	(segment
		(start 52.8828 -23.7998)
		(end 69.288152 -23.7998)
		(width 0.254)
		(layer "F.Cu")
		(net "HBA_PRSNT1_N")
	)
	(segment
		(start 51.943 -22.86)
		(end 52.8828 -23.7998)
		(width 0.254)
		(layer "F.Cu")
		(net "HBA_PRSNT1_N")
	)
	(segment
		(start 128.744472 -40.522144)
		(end 127.728472 -40.522144)
		(width 0.254)
		(layer "F.Cu")
		(net "HBA_PRSNT1_N")
	)
	(segment
		(start 70.4088 -30.097476)
		(end 70.976998 -30.665674)
		(width 0.254)
		(layer "F.Cu")
		(net "HBA_PRSNT1_N")
	)
	(segment
		(start 69.288152 -23.7998)
		(end 70.4088 -24.920448)
		(width 0.254)
		(layer "F.Cu")
		(net "HBA_PRSNT1_N")
	)
	(segment
		(start 127.728472 -39.653972)
		(end 123.980448 -35.905948)
		(width 0.254)
		(layer "F.Cu")
		(net "HBA_PRSNT1_N")
	)
	(segment
		(start 123.980448 -35.905948)
		(end 122.606054 -35.905948)
		(width 0.254)
		(layer "F.Cu")
		(net "HBA_PRSNT1_N")
	)
	(segment
		(start 70.4088 -24.920448)
		(end 70.4088 -30.097476)
		(width 0.254)
		(layer "F.Cu")
		(net "HBA_PRSNT1_N")
	)
	(via
		(at 70.976998 -30.665674)
		(size 0.508)
		(drill 0.254)
		(layers "F.Cu" "B.Cu")
		(net "HBA_PRSNT1_N")
	)
	(via
		(at 51.943 -22.86)
		(size 0.508)
		(drill 0.254)
		(layers "F.Cu" "B.Cu")
		(net "HBA_PRSNT1_N")
	)
	(via
		(at 73.278492 -52.621688)
		(size 0.7112)
		(drill 0.3556)
		(layers "F.Cu" "B.Cu")
		(net "HBA_PRSNT1_N")
	)
	(segment
		(start 108.869734 -49.915318)
		(end 101.135942 -57.64911)
		(width 0.254)
		(layer "B.Cu")
		(net "HBA_PRSNT1_N")
	)
	(segment
		(start 81.28 -55.8165)
		(end 81.28 -53.603906)
		(width 0.254)
		(layer "B.Cu")
		(net "HBA_PRSNT1_N")
	)
	(segment
		(start 82.427064 -57.64911)
		(end 81.28 -56.502046)
		(width 0.254)
		(layer "B.Cu")
		(net "HBA_PRSNT1_N")
	)
	(segment
		(start 80.803496 -53.127402)
		(end 73.784206 -53.127402)
		(width 0.254)
		(layer "B.Cu")
		(net "HBA_PRSNT1_N")
	)
	(segment
		(start 16.375888 -18.299938)
		(end 13.899896 -18.299938)
		(width 0.254)
		(layer "B.Cu")
		(net "HBA_PRSNT1_N")
	)
	(segment
		(start 51.943 -22.86)
		(end 51.261264 -22.86)
		(width 0.254)
		(layer "B.Cu")
		(net "HBA_PRSNT1_N")
	)
	(segment
		(start 121.750074 -35.049968)
		(end 121.750074 -37.902388)
		(width 0.254)
		(layer "B.Cu")
		(net "HBA_PRSNT1_N")
	)
	(segment
		(start 18.69186 -20.61591)
		(end 16.375888 -18.299938)
		(width 0.254)
		(layer "B.Cu")
		(net "HBA_PRSNT1_N")
	)
	(segment
		(start 121.750074 -37.902388)
		(end 125.324616 -41.47693)
		(width 0.254)
		(layer "B.Cu")
		(net "HBA_PRSNT1_N")
	)
	(segment
		(start 81.28 -53.603906)
		(end 80.803496 -53.127402)
		(width 0.254)
		(layer "B.Cu")
		(net "HBA_PRSNT1_N")
	)
	(segment
		(start 49.017174 -20.61591)
		(end 18.69186 -20.61591)
		(width 0.254)
		(layer "B.Cu")
		(net "HBA_PRSNT1_N")
	)
	(segment
		(start 125.324616 -41.47693)
		(end 125.324616 -46.539912)
		(width 0.254)
		(layer "B.Cu")
		(net "HBA_PRSNT1_N")
	)
	(segment
		(start 125.324616 -46.539912)
		(end 121.94921 -49.915318)
		(width 0.254)
		(layer "B.Cu")
		(net "HBA_PRSNT1_N")
	)
	(segment
		(start 70.976998 -41.589198)
		(end 73.278492 -43.890692)
		(width 0.254)
		(layer "B.Cu")
		(net "HBA_PRSNT1_N")
	)
	(segment
		(start 73.784206 -53.127402)
		(end 73.278492 -52.621688)
		(width 0.254)
		(layer "B.Cu")
		(net "HBA_PRSNT1_N")
	)
	(segment
		(start 81.28 -56.502046)
		(end 81.28 -55.8165)
		(width 0.254)
		(layer "B.Cu")
		(net "HBA_PRSNT1_N")
	)
	(segment
		(start 101.135942 -57.64911)
		(end 82.427064 -57.64911)
		(width 0.254)
		(layer "B.Cu")
		(net "HBA_PRSNT1_N")
	)
	(segment
		(start 70.976998 -30.665674)
		(end 70.976998 -41.589198)
		(width 0.254)
		(layer "B.Cu")
		(net "HBA_PRSNT1_N")
	)
	(segment
		(start 51.261264 -22.86)
		(end 49.017174 -20.61591)
		(width 0.254)
		(layer "B.Cu")
		(net "HBA_PRSNT1_N")
	)
	(segment
		(start 73.278492 -43.890692)
		(end 73.278492 -52.621688)
		(width 0.254)
		(layer "B.Cu")
		(net "HBA_PRSNT1_N")
	)
	(segment
		(start 121.94921 -49.915318)
		(end 108.869734 -49.915318)
		(width 0.254)
		(layer "B.Cu")
		(net "HBA_PRSNT1_N")
	)
	(segment
		(start 52.832 -22.86)
		(end 53.213 -23.241)
		(width 0.254)
		(layer "F.Cu")
		(net "HBA_PRSNT0_N")
	)
	(segment
		(start 122.8598 -56.8325)
		(end 121.8946 -56.8325)
		(width 0.254)
		(layer "F.Cu")
		(net "HBA_PRSNT0_N")
	)
	(segment
		(start 121.8946 -56.8325)
		(end 121.750074 -56.687974)
		(width 0.254)
		(layer "F.Cu")
		(net "HBA_PRSNT0_N")
	)
	(segment
		(start 121.750074 -56.687974)
		(end 121.750074 -51.74996)
		(width 0.254)
		(layer "F.Cu")
		(net "HBA_PRSNT0_N")
	)
	(segment
		(start 53.213 -23.241)
		(end 69.5198 -23.241)
		(width 0.254)
		(layer "F.Cu")
		(net "HBA_PRSNT0_N")
	)
	(segment
		(start 70.993 -24.7142)
		(end 70.993 -29.6926)
		(width 0.254)
		(layer "F.Cu")
		(net "HBA_PRSNT0_N")
	)
	(segment
		(start 69.5198 -23.241)
		(end 70.993 -24.7142)
		(width 0.254)
		(layer "F.Cu")
		(net "HBA_PRSNT0_N")
	)
	(via
		(at 52.832 -22.86)
		(size 0.508)
		(drill 0.254)
		(layers "F.Cu" "B.Cu")
		(net "HBA_PRSNT0_N")
	)
	(via
		(at 70.993 -29.6926)
		(size 0.508)
		(drill 0.254)
		(layers "F.Cu" "B.Cu")
		(net "HBA_PRSNT0_N")
	)
	(via
		(at 74.200766 -54.73319)
		(size 0.7112)
		(drill 0.3556)
		(layers "F.Cu" "B.Cu")
		(net "HBA_PRSNT0_N")
	)
	(segment
		(start 80.62976 -55.8165)
		(end 79.164688 -55.8165)
		(width 0.254)
		(layer "B.Cu")
		(net "HBA_PRSNT0_N")
	)
	(segment
		(start 70.993 -29.6926)
		(end 70.418198 -30.267402)
		(width 0.254)
		(layer "B.Cu")
		(net "HBA_PRSNT0_N")
	)
	(segment
		(start 52.197 -23.495)
		(end 51.034696 -23.495)
		(width 0.254)
		(layer "B.Cu")
		(net "HBA_PRSNT0_N")
	)
	(segment
		(start 119.135144 -54.36489)
		(end 112.897412 -54.36489)
		(width 0.254)
		(layer "B.Cu")
		(net "HBA_PRSNT0_N")
	)
	(segment
		(start 80.62976 -56.998616)
		(end 80.62976 -55.8165)
		(width 0.254)
		(layer "B.Cu")
		(net "HBA_PRSNT0_N")
	)
	(segment
		(start 112.897412 -54.36489)
		(end 108.98124 -58.281062)
		(width 0.254)
		(layer "B.Cu")
		(net "HBA_PRSNT0_N")
	)
	(segment
		(start 78.081378 -54.73319)
		(end 74.200766 -54.73319)
		(width 0.254)
		(layer "B.Cu")
		(net "HBA_PRSNT0_N")
	)
	(segment
		(start 79.164688 -55.8165)
		(end 78.081378 -54.73319)
		(width 0.254)
		(layer "B.Cu")
		(net "HBA_PRSNT0_N")
	)
	(segment
		(start 121.750074 -51.74996)
		(end 119.135144 -54.36489)
		(width 0.254)
		(layer "B.Cu")
		(net "HBA_PRSNT0_N")
	)
	(segment
		(start 108.98124 -58.281062)
		(end 81.912206 -58.281062)
		(width 0.254)
		(layer "B.Cu")
		(net "HBA_PRSNT0_N")
	)
	(segment
		(start 72.643492 -53.175916)
		(end 74.200766 -54.73319)
		(width 0.254)
		(layer "B.Cu")
		(net "HBA_PRSNT0_N")
	)
	(segment
		(start 70.418198 -41.919398)
		(end 72.643492 -44.144692)
		(width 0.254)
		(layer "B.Cu")
		(net "HBA_PRSNT0_N")
	)
	(segment
		(start 48.714406 -21.17471)
		(end 18.460212 -21.17471)
		(width 0.254)
		(layer "B.Cu")
		(net "HBA_PRSNT0_N")
	)
	(segment
		(start 16.585438 -19.299936)
		(end 13.899896 -19.299936)
		(width 0.254)
		(layer "B.Cu")
		(net "HBA_PRSNT0_N")
	)
	(segment
		(start 51.034696 -23.495)
		(end 48.714406 -21.17471)
		(width 0.254)
		(layer "B.Cu")
		(net "HBA_PRSNT0_N")
	)
	(segment
		(start 72.643492 -44.144692)
		(end 72.643492 -53.175916)
		(width 0.254)
		(layer "B.Cu")
		(net "HBA_PRSNT0_N")
	)
	(segment
		(start 52.832 -22.86)
		(end 52.197 -23.495)
		(width 0.254)
		(layer "B.Cu")
		(net "HBA_PRSNT0_N")
	)
	(segment
		(start 18.460212 -21.17471)
		(end 16.585438 -19.299936)
		(width 0.254)
		(layer "B.Cu")
		(net "HBA_PRSNT0_N")
	)
	(segment
		(start 81.912206 -58.281062)
		(end 80.62976 -56.998616)
		(width 0.254)
		(layer "B.Cu")
		(net "HBA_PRSNT0_N")
	)
	(segment
		(start 70.418198 -30.267402)
		(end 70.418198 -41.919398)
		(width 0.254)
		(layer "B.Cu")
		(net "HBA_PRSNT0_N")
	)
	(segment
		(start 55.34152 -20.158456)
		(end 55.34152 -21.2344)
		(width 0.508)
		(layer "F.Cu")
		(net "GND")
	)
	(segment
		(start 104.744774 -54.384702)
		(end 104.744774 -55.15991)
		(width 0.508)
		(layer "F.Cu")
		(net "GND")
	)
	(segment
		(start 104.071166 -55.15991)
		(end 104.744774 -55.15991)
		(width 0.508)
		(layer "F.Cu")
		(net "GND")
	)
	(segment
		(start 127.728472 -41.411144)
		(end 127.728472 -42.277792)
		(width 0.508)
		(layer "F.Cu")
		(net "GND")
	)
	(segment
		(start 121.8946 -57.7215)
		(end 121.0564 -57.7215)
		(width 0.508)
		(layer "F.Cu")
		(net "GND")
	)
	(segment
		(start 109.545374 -54.384702)
		(end 109.545374 -55.15991)
		(width 0.508)
		(layer "F.Cu")
		(net "GND")
	)
	(segment
		(start 104.744774 -55.15991)
		(end 104.744774 -55.935118)
		(width 0.508)
		(layer "F.Cu")
		(net "GND")
	)
	(segment
		(start 109.545374 -55.15991)
		(end 109.545374 -55.935118)
		(width 0.508)
		(layer "F.Cu")
		(net "GND")
	)
	(segment
		(start 80.4545 -8.128)
		(end 80.4545 -6.5913)
		(width 0.508)
		(layer "F.Cu")
		(net "GND")
	)
	(segment
		(start 56.440324 -9.727946)
		(end 56.440324 -10.541)
		(width 0.508)
		(layer "F.Cu")
		(net "GND")
	)
	(segment
		(start 109.545374 -55.15991)
		(end 110.218982 -55.15991)
		(width 0.508)
		(layer "F.Cu")
		(net "GND")
	)
	(segment
		(start 81.1784 -5.8674)
		(end 83.328764 -5.8674)
		(width 0.508)
		(layer "F.Cu")
		(net "GND")
	)
	(segment
		(start 83.328764 -5.8674)
		(end 84.497164 -7.0358)
		(width 0.508)
		(layer "F.Cu")
		(net "GND")
	)
	(segment
		(start 80.4545 -6.5913)
		(end 81.1784 -5.8674)
		(width 0.508)
		(layer "F.Cu")
		(net "GND")
	)
	(via
		(at 77.148436 -22.830028)
		(size 0.508)
		(drill 0.254)
		(layers "F.Cu" "B.Cu")
		(net "GND")
	)
	(via
		(at 122.464068 -63.803022)
		(size 0.5588)
		(drill 0.3048)
		(layers "F.Cu" "B.Cu")
		(net "GND")
	)
	(via
		(at 142.103094 -52.962048)
		(size 0.5588)
		(drill 0.3048)
		(layers "F.Cu" "B.Cu")
		(net "GND")
	)
	(via
		(at 62.738 -12.065)
		(size 0.5588)
		(drill 0.3048)
		(layers "F.Cu" "B.Cu")
		(net "GND")
	)
	(via
		(at 87.80526 -5.1562)
		(size 0.5588)
		(drill 0.3048)
		(layers "F.Cu" "B.Cu")
		(net "GND")
	)
	(via
		(at 11.256264 -7.284974)
		(size 0.5588)
		(drill 0.3048)
		(layers "F.Cu" "B.Cu")
		(net "GND")
	)
	(via
		(at 84.536788 -26.19756)
		(size 0.508)
		(drill 0.254)
		(layers "F.Cu" "B.Cu")
		(net "GND")
	)
	(via
		(at 63.197994 -20.389088)
		(size 0.5588)
		(drill 0.3048)
		(layers "F.Cu" "B.Cu")
		(net "GND")
	)
	(via
		(at 112.304068 -63.803022)
		(size 0.5588)
		(drill 0.3048)
		(layers "F.Cu" "B.Cu")
		(net "GND")
	)
	(via
		(at 12.531344 -13.316204)
		(size 0.5588)
		(drill 0.3048)
		(layers "F.Cu" "B.Cu")
		(net "GND")
	)
	(via
		(at 119.74703 -23.709884)
		(size 0.5588)
		(drill 0.3048)
		(layers "F.Cu" "B.Cu")
		(net "GND")
	)
	(via
		(at 86.904068 -63.803022)
		(size 0.5588)
		(drill 0.3048)
		(layers "F.Cu" "B.Cu")
		(net "GND")
	)
	(via
		(at 61.595 -6.858)
		(size 0.5588)
		(drill 0.3048)
		(layers "F.Cu" "B.Cu")
		(net "GND")
	)
	(via
		(at 87.793068 -22.894036)
		(size 0.508)
		(drill 0.254)
		(layers "F.Cu" "B.Cu")
		(net "GND")
	)
	(via
		(at 12.540996 -14.32306)
		(size 0.5588)
		(drill 0.3048)
		(layers "F.Cu" "B.Cu")
		(net "GND")
	)
	(via
		(at 53.679598 -9.896602)
		(size 0.5588)
		(drill 0.3048)
		(layers "F.Cu" "B.Cu")
		(net "GND")
	)
	(via
		(at 75.65136 -50.642774)
		(size 0.5588)
		(drill 0.3048)
		(layers "F.Cu" "B.Cu")
		(net "GND")
	)
	(via
		(at 72.338692 -38.782498)
		(size 0.5588)
		(drill 0.3048)
		(layers "F.Cu" "B.Cu")
		(net "GND")
	)
	(via
		(at 91.984068 -63.803022)
		(size 0.5588)
		(drill 0.3048)
		(layers "F.Cu" "B.Cu")
		(net "GND")
	)
	(via
		(at 132.07492 -57.47893)
		(size 0.5588)
		(drill 0.3048)
		(layers "F.Cu" "B.Cu")
		(net "GND")
	)
	(via
		(at 83.030568 -20.160234)
		(size 0.508)
		(drill 0.254)
		(layers "F.Cu" "B.Cu")
		(net "GND")
	)
	(via
		(at 75.64247 -51.572414)
		(size 0.5588)
		(drill 0.3048)
		(layers "F.Cu" "B.Cu")
		(net "GND")
	)
	(via
		(at 1.397 -12.267946)
		(size 0.5588)
		(drill 0.3048)
		(layers "F.Cu" "B.Cu")
		(net "GND")
	)
	(via
		(at 11.524996 -14.32306)
		(size 0.5588)
		(drill 0.3048)
		(layers "F.Cu" "B.Cu")
		(net "GND")
	)
	(via
		(at 136.89711 -15.745968)
		(size 0.5588)
		(drill 0.3048)
		(layers "F.Cu" "B.Cu")
		(net "GND")
	)
	(via
		(at 54.586124 -10.031476)
		(size 0.5588)
		(drill 0.3048)
		(layers "F.Cu" "B.Cu")
		(net "GND")
	)
	(via
		(at 85.76818 -23.107904)
		(size 0.508)
		(drill 0.254)
		(layers "F.Cu" "B.Cu")
		(net "GND")
	)
	(via
		(at 102.144068 -63.803022)
		(size 0.5588)
		(drill 0.3048)
		(layers "F.Cu" "B.Cu")
		(net "GND")
	)
	(via
		(at 32.50184 -21.803106)
		(size 0.5588)
		(drill 0.3048)
		(layers "F.Cu" "B.Cu")
		(net "GND")
	)
	(via
		(at 78.284832 -25.89403)
		(size 0.508)
		(drill 0.254)
		(layers "F.Cu" "B.Cu")
		(net "GND")
	)
	(via
		(at 52.74945 -9.882378)
		(size 0.5588)
		(drill 0.3048)
		(layers "F.Cu" "B.Cu")
		(net "GND")
	)
	(via
		(at 142.103094 -27.562048)
		(size 0.5588)
		(drill 0.3048)
		(layers "F.Cu" "B.Cu")
		(net "GND")
	)
	(via
		(at 77.1398 -35.7378)
		(size 0.5588)
		(drill 0.3048)
		(layers "F.Cu" "B.Cu")
		(net "GND")
	)
	(via
		(at 7.10184 -21.803106)
		(size 0.5588)
		(drill 0.3048)
		(layers "F.Cu" "B.Cu")
		(net "GND")
	)
	(via
		(at 97.064068 -63.803022)
		(size 0.5588)
		(drill 0.3048)
		(layers "F.Cu" "B.Cu")
		(net "GND")
	)
	(via
		(at 76.391516 -52.312824)
		(size 0.5588)
		(drill 0.3048)
		(layers "F.Cu" "B.Cu")
		(net "GND")
	)
	(via
		(at 142.103094 -47.882048)
		(size 0.5588)
		(drill 0.3048)
		(layers "F.Cu" "B.Cu")
		(net "GND")
	)
	(via
		(at 47.74184 -21.803106)
		(size 0.5588)
		(drill 0.3048)
		(layers "F.Cu" "B.Cu")
		(net "GND")
	)
	(via
		(at 11.246612 -6.278118)
		(size 0.5588)
		(drill 0.3048)
		(layers "F.Cu" "B.Cu")
		(net "GND")
	)
	(via
		(at 84.497164 -7.0358)
		(size 0.5588)
		(drill 0.3048)
		(layers "F.Cu" "B.Cu")
		(net "GND")
	)
	(via
		(at 10.846054 -1.397)
		(size 0.5588)
		(drill 0.3048)
		(layers "F.Cu" "B.Cu")
		(net "GND")
	)
	(via
		(at 121.0564 -57.7215)
		(size 0.5588)
		(drill 0.3048)
		(layers "F.Cu" "B.Cu")
		(net "GND")
	)
	(via
		(at 127.728472 -42.277792)
		(size 0.5588)
		(drill 0.3048)
		(layers "F.Cu" "B.Cu")
		(net "GND")
	)
	(via
		(at 72.36587 -40.777414)
		(size 0.5588)
		(drill 0.3048)
		(layers "F.Cu" "B.Cu")
		(net "GND")
	)
	(via
		(at 70.896988 -54.410102)
		(size 0.5588)
		(drill 0.3048)
		(layers "F.Cu" "B.Cu")
		(net "GND")
	)
	(via
		(at 85.88883 -25.07996)
		(size 0.508)
		(drill 0.254)
		(layers "F.Cu" "B.Cu")
		(net "GND")
	)
	(via
		(at 74.457814 -24.891238)
		(size 0.508)
		(drill 0.254)
		(layers "F.Cu" "B.Cu")
		(net "GND")
	)
	(via
		(at 61.722 -12.065)
		(size 0.5588)
		(drill 0.3048)
		(layers "F.Cu" "B.Cu")
		(net "GND")
	)
	(via
		(at 11.515344 -13.316204)
		(size 0.5588)
		(drill 0.3048)
		(layers "F.Cu" "B.Cu")
		(net "GND")
	)
	(via
		(at 79.658718 -20.579842)
		(size 0.508)
		(drill 0.254)
		(layers "F.Cu" "B.Cu")
		(net "GND")
	)
	(via
		(at 62.19698 -20.41398)
		(size 0.5588)
		(drill 0.3048)
		(layers "F.Cu" "B.Cu")
		(net "GND")
	)
	(via
		(at 63.211964 -19.421856)
		(size 0.5588)
		(drill 0.3048)
		(layers "F.Cu" "B.Cu")
		(net "GND")
	)
	(via
		(at 82.804 -55.245)
		(size 0.5588)
		(drill 0.3048)
		(layers "F.Cu" "B.Cu")
		(net "GND")
	)
	(via
		(at 142.103094 -22.482048)
		(size 0.5588)
		(drill 0.3048)
		(layers "F.Cu" "B.Cu")
		(net "GND")
	)
	(via
		(at 72.338692 -37.862002)
		(size 0.5588)
		(drill 0.3048)
		(layers "F.Cu" "B.Cu")
		(net "GND")
	)
	(via
		(at 62.160658 -19.454114)
		(size 0.5588)
		(drill 0.3048)
		(layers "F.Cu" "B.Cu")
		(net "GND")
	)
	(via
		(at 71.430134 -8.628634)
		(size 0.5588)
		(drill 0.3048)
		(layers "F.Cu" "B.Cu")
		(net "GND")
	)
	(via
		(at 139.097766 -54.691026)
		(size 0.7112)
		(drill 0.3556)
		(layers "F.Cu" "B.Cu")
		(net "GND")
	)
	(via
		(at 72.37476 -39.847774)
		(size 0.5588)
		(drill 0.3048)
		(layers "F.Cu" "B.Cu")
		(net "GND")
	)
	(via
		(at 10.414 -20.193)
		(size 0.5588)
		(drill 0.3048)
		(layers "F.Cu" "B.Cu")
		(net "GND")
	)
	(via
		(at 22.34184 -21.803106)
		(size 0.5588)
		(drill 0.3048)
		(layers "F.Cu" "B.Cu")
		(net "GND")
	)
	(via
		(at 51.816 -21.844)
		(size 0.5588)
		(drill 0.3048)
		(layers "F.Cu" "B.Cu")
		(net "GND")
	)
	(via
		(at 10.414 -19.177)
		(size 0.5588)
		(drill 0.3048)
		(layers "F.Cu" "B.Cu")
		(net "GND")
	)
	(via
		(at 142.103094 -37.722048)
		(size 0.5588)
		(drill 0.3048)
		(layers "F.Cu" "B.Cu")
		(net "GND")
	)
	(via
		(at 107.224068 -63.803022)
		(size 0.5588)
		(drill 0.3048)
		(layers "F.Cu" "B.Cu")
		(net "GND")
	)
	(via
		(at 81.966054 -1.397)
		(size 0.5588)
		(drill 0.3048)
		(layers "F.Cu" "B.Cu")
		(net "GND")
	)
	(via
		(at 142.103094 -42.802048)
		(size 0.5588)
		(drill 0.3048)
		(layers "F.Cu" "B.Cu")
		(net "GND")
	)
	(via
		(at 142.103094 -17.402048)
		(size 0.5588)
		(drill 0.3048)
		(layers "F.Cu" "B.Cu")
		(net "GND")
	)
	(via
		(at 55.34152 -21.2344)
		(size 0.508)
		(drill 0.254)
		(layers "F.Cu" "B.Cu")
		(net "GND")
	)
	(via
		(at 70.896988 -49.330102)
		(size 0.5588)
		(drill 0.3048)
		(layers "F.Cu" "B.Cu")
		(net "GND")
	)
	(via
		(at 80.022192 -33.8582)
		(size 0.5588)
		(drill 0.3048)
		(layers "F.Cu" "B.Cu")
		(net "GND")
	)
	(via
		(at 90.848688 -1.168908)
		(size 0.5588)
		(drill 0.3048)
		(layers "F.Cu" "B.Cu")
		(net "GND")
	)
	(via
		(at 142.103094 -32.642048)
		(size 0.5588)
		(drill 0.3048)
		(layers "F.Cu" "B.Cu")
		(net "GND")
	)
	(via
		(at 62.611 -6.858)
		(size 0.5588)
		(drill 0.3048)
		(layers "F.Cu" "B.Cu")
		(net "GND")
	)
	(via
		(at 51.816 -20.828)
		(size 0.5588)
		(drill 0.3048)
		(layers "F.Cu" "B.Cu")
		(net "GND")
	)
	(via
		(at 85.701124 -20.21205)
		(size 0.508)
		(drill 0.254)
		(layers "F.Cu" "B.Cu")
		(net "GND")
	)
	(via
		(at 71.664068 -63.803022)
		(size 0.5588)
		(drill 0.3048)
		(layers "F.Cu" "B.Cu")
		(net "GND")
	)
	(via
		(at 9.398 -19.177)
		(size 0.5588)
		(drill 0.3048)
		(layers "F.Cu" "B.Cu")
		(net "GND")
	)
	(via
		(at 132.624068 -63.803022)
		(size 0.5588)
		(drill 0.3048)
		(layers "F.Cu" "B.Cu")
		(net "GND")
	)
	(via
		(at 12.540996 -15.300706)
		(size 0.5588)
		(drill 0.3048)
		(layers "F.Cu" "B.Cu")
		(net "GND")
	)
	(via
		(at 9.398 -20.193)
		(size 0.5588)
		(drill 0.3048)
		(layers "F.Cu" "B.Cu")
		(net "GND")
	)
	(via
		(at 86.647782 -20.395692)
		(size 0.508)
		(drill 0.254)
		(layers "F.Cu" "B.Cu")
		(net "GND")
	)
	(via
		(at 27.42184 -21.803106)
		(size 0.5588)
		(drill 0.3048)
		(layers "F.Cu" "B.Cu")
		(net "GND")
	)
	(via
		(at 52.832 -20.828)
		(size 0.5588)
		(drill 0.3048)
		(layers "F.Cu" "B.Cu")
		(net "GND")
	)
	(via
		(at 11.524996 -15.300706)
		(size 0.5588)
		(drill 0.3048)
		(layers "F.Cu" "B.Cu")
		(net "GND")
	)
	(via
		(at 83.810348 -14.402562)
		(size 0.508)
		(drill 0.254)
		(layers "F.Cu" "B.Cu")
		(net "GND")
	)
	(via
		(at 117.384068 -63.803022)
		(size 0.5588)
		(drill 0.3048)
		(layers "F.Cu" "B.Cu")
		(net "GND")
	)
	(via
		(at 127.544068 -63.803022)
		(size 0.5588)
		(drill 0.3048)
		(layers "F.Cu" "B.Cu")
		(net "GND")
	)
	(via
		(at 133.005068 -57.493154)
		(size 0.5588)
		(drill 0.3048)
		(layers "F.Cu" "B.Cu")
		(net "GND")
	)
	(via
		(at 56.440324 -10.541)
		(size 0.508)
		(drill 0.254)
		(layers "F.Cu" "B.Cu")
		(net "GND")
	)
	(via
		(at 81.628742 -14.402562)
		(size 0.5588)
		(drill 0.3048)
		(layers "F.Cu" "B.Cu")
		(net "GND")
	)
	(via
		(at 132.084318 -58.43778)
		(size 0.5588)
		(drill 0.3048)
		(layers "F.Cu" "B.Cu")
		(net "GND")
	)
	(via
		(at 77.216 -54.102)
		(size 0.5588)
		(drill 0.3048)
		(layers "F.Cu" "B.Cu")
		(net "GND")
	)
	(via
		(at 12.272264 -8.26262)
		(size 0.5588)
		(drill 0.3048)
		(layers "F.Cu" "B.Cu")
		(net "GND")
	)
	(via
		(at 70.896988 -59.490102)
		(size 0.5588)
		(drill 0.3048)
		(layers "F.Cu" "B.Cu")
		(net "GND")
	)
	(via
		(at 81.64576 -25.799034)
		(size 0.508)
		(drill 0.254)
		(layers "F.Cu" "B.Cu")
		(net "GND")
	)
	(via
		(at 68.894452 -17.070832)
		(size 0.7112)
		(drill 0.3556)
		(layers "F.Cu" "B.Cu")
		(net "GND")
	)
	(via
		(at 12.272264 -7.284974)
		(size 0.5588)
		(drill 0.3048)
		(layers "F.Cu" "B.Cu")
		(net "GND")
	)
	(via
		(at 84.287614 -59.262518)
		(size 0.7112)
		(drill 0.3556)
		(layers "F.Cu" "B.Cu")
		(net "GND")
	)
	(via
		(at 74.459084 -20.579842)
		(size 0.508)
		(drill 0.254)
		(layers "F.Cu" "B.Cu")
		(net "GND")
	)
	(via
		(at 83.072478 -23.099522)
		(size 0.508)
		(drill 0.254)
		(layers "F.Cu" "B.Cu")
		(net "GND")
	)
	(via
		(at 37.58184 -21.803106)
		(size 0.5588)
		(drill 0.3048)
		(layers "F.Cu" "B.Cu")
		(net "GND")
	)
	(via
		(at 12.262612 -6.278118)
		(size 0.5588)
		(drill 0.3048)
		(layers "F.Cu" "B.Cu")
		(net "GND")
	)
	(via
		(at 82.911442 -46.642528)
		(size 0.5588)
		(drill 0.3048)
		(layers "F.Cu" "B.Cu")
		(net "GND")
	)
	(via
		(at 75.615292 -49.577498)
		(size 0.5588)
		(drill 0.3048)
		(layers "F.Cu" "B.Cu")
		(net "GND")
	)
	(via
		(at 81.824068 -63.803022)
		(size 0.5588)
		(drill 0.3048)
		(layers "F.Cu" "B.Cu")
		(net "GND")
	)
	(via
		(at 2.02184 -21.803106)
		(size 0.5588)
		(drill 0.3048)
		(layers "F.Cu" "B.Cu")
		(net "GND")
	)
	(via
		(at 11.256264 -8.26262)
		(size 0.5588)
		(drill 0.3048)
		(layers "F.Cu" "B.Cu")
		(net "GND")
	)
	(via
		(at 133.005068 -58.423556)
		(size 0.5588)
		(drill 0.3048)
		(layers "F.Cu" "B.Cu")
		(net "GND")
	)
	(via
		(at 136.89711 -10.665968)
		(size 0.5588)
		(drill 0.3048)
		(layers "F.Cu" "B.Cu")
		(net "GND")
	)
	(via
		(at 52.832 -21.844)
		(size 0.5588)
		(drill 0.3048)
		(layers "F.Cu" "B.Cu")
		(net "GND")
	)
	(via
		(at 17.26184 -21.803106)
		(size 0.5588)
		(drill 0.3048)
		(layers "F.Cu" "B.Cu")
		(net "GND")
	)
	(via
		(at 75.615292 -48.657002)
		(size 0.5588)
		(drill 0.3048)
		(layers "F.Cu" "B.Cu")
		(net "GND")
	)
	(via
		(at 73.6092 -41.91)
		(size 0.5588)
		(drill 0.3048)
		(layers "F.Cu" "B.Cu")
		(net "GND")
	)
	(via
		(at 42.66184 -21.803106)
		(size 0.5588)
		(drill 0.3048)
		(layers "F.Cu" "B.Cu")
		(net "GND")
	)
	(via
		(at 70.896988 -44.250102)
		(size 0.5588)
		(drill 0.3048)
		(layers "F.Cu" "B.Cu")
		(net "GND")
	)
	(via
		(at 139.650978 -22.847554)
		(size 0.7112)
		(drill 0.3556)
		(layers "F.Cu" "B.Cu")
		(net "GND")
	)
	(segment
		(start 82.802984 -22.830028)
		(end 81.814924 -22.830028)
		(width 0.254)
		(layer "B.Cu")
		(net "GND")
	)
	(segment
		(start 83.030568 -20.160234)
		(end 82.61096 -20.579842)
		(width 0.254)
		(layer "B.Cu")
		(net "GND")
	)
	(segment
		(start 84.514944 -25.07996)
		(end 85.88883 -25.07996)
		(width 0.254)
		(layer "B.Cu")
		(net "GND")
	)
	(segment
		(start 85.701124 -20.21205)
		(end 85.333332 -20.579842)
		(width 0.254)
		(layer "B.Cu")
		(net "GND")
	)
	(segment
		(start 78.0288 -11.7602)
		(end 77.84084 -11.57224)
		(width 0.381)
		(layer "B.Cu")
		(net "GND")
	)
	(segment
		(start 77.96276 -35.7378)
		(end 77.1398 -35.7378)
		(width 0.381)
		(layer "B.Cu")
		(net "GND")
	)
	(segment
		(start 75.584812 -22.830028)
		(end 77.148436 -22.830028)
		(width 0.3048)
		(layer "B.Cu")
		(net "GND")
	)
	(segment
		(start 85.76818 -23.107904)
		(end 85.490304 -22.830028)
		(width 0.254)
		(layer "B.Cu")
		(net "GND")
	)
	(segment
		(start 82.068416 -46.134274)
		(end 82.57667 -46.642528)
		(width 0.508)
		(layer "B.Cu")
		(net "GND")
	)
	(segment
		(start 87.01024 -5.1562)
		(end 87.80526 -5.1562)
		(width 0.381)
		(layer "B.Cu")
		(net "GND")
	)
	(segment
		(start 77.148436 -22.830028)
		(end 78.284832 -22.830028)
		(width 0.3048)
		(layer "B.Cu")
		(net "GND")
	)
	(segment
		(start 81.64576 -25.799034)
		(end 81.814924 -25.62987)
		(width 0.254)
		(layer "B.Cu")
		(net "GND")
	)
	(segment
		(start 82.804 -55.245)
		(end 82.804 -55.4355)
		(width 0.381)
		(layer "B.Cu")
		(net "GND")
	)
	(segment
		(start 70.128384 -7.574026)
		(end 70.16877 -7.614412)
		(width 0.508)
		(layer "B.Cu")
		(net "GND")
	)
	(segment
		(start 126.179834 -20.779486)
		(end 126.179834 -22.049994)
		(width 0.508)
		(layer "B.Cu")
		(net "GND")
	)
	(segment
		(start 129.180082 -22.049994)
		(end 129.180082 -23.320502)
		(width 0.508)
		(layer "B.Cu")
		(net "GND")
	)
	(segment
		(start 82.068416 -45.832776)
		(end 82.068416 -46.134274)
		(width 0.508)
		(layer "B.Cu")
		(net "GND")
	)
	(segment
		(start 82.804 -55.4355)
		(end 82.423 -55.8165)
		(width 0.381)
		(layer "B.Cu")
		(net "GND")
	)
	(segment
		(start 74.457814 -24.891238)
		(end 74.646536 -25.07996)
		(width 0.254)
		(layer "B.Cu")
		(net "GND")
	)
	(segment
		(start 74.646536 -25.07996)
		(end 75.584812 -25.07996)
		(width 0.254)
		(layer "B.Cu")
		(net "GND")
	)
	(segment
		(start 75.584812 -20.579842)
		(end 74.459084 -20.579842)
		(width 0.254)
		(layer "B.Cu")
		(net "GND")
	)
	(segment
		(start 71.395082 -7.614412)
		(end 71.395082 -8.593582)
		(width 0.508)
		(layer "B.Cu")
		(net "GND")
	)
	(segment
		(start 85.70976 -7.0358)
		(end 84.497164 -7.0358)
		(width 0.381)
		(layer "B.Cu")
		(net "GND")
	)
	(segment
		(start 71.395082 -8.593582)
		(end 71.430134 -8.628634)
		(width 0.508)
		(layer "B.Cu")
		(net "GND")
	)
	(segment
		(start 85.333332 -20.579842)
		(end 84.514944 -20.579842)
		(width 0.254)
		(layer "B.Cu")
		(net "GND")
	)
	(segment
		(start 126.179834 -22.049994)
		(end 126.179834 -23.320502)
		(width 0.508)
		(layer "B.Cu")
		(net "GND")
	)
	(segment
		(start 83.072478 -23.099522)
		(end 82.802984 -22.830028)
		(width 0.254)
		(layer "B.Cu")
		(net "GND")
	)
	(segment
		(start 82.423 -55.8165)
		(end 81.93024 -55.8165)
		(width 0.381)
		(layer "B.Cu")
		(net "GND")
	)
	(segment
		(start 85.490304 -22.830028)
		(end 84.514944 -22.830028)
		(width 0.254)
		(layer "B.Cu")
		(net "GND")
	)
	(segment
		(start 70.16877 -7.614412)
		(end 71.395082 -7.614412)
		(width 0.508)
		(layer "B.Cu")
		(net "GND")
	)
	(segment
		(start 82.911442 -46.642528)
		(end 83.320636 -46.233334)
		(width 0.508)
		(layer "B.Cu")
		(net "GND")
	)
	(segment
		(start 77.84084 -11.57224)
		(end 77.84084 -10.0203)
		(width 0.381)
		(layer "B.Cu")
		(net "GND")
	)
	(segment
		(start 78.284832 -20.579842)
		(end 79.658718 -20.579842)
		(width 0.254)
		(layer "B.Cu")
		(net "GND")
	)
	(segment
		(start 129.180082 -20.779486)
		(end 129.180082 -22.049994)
		(width 0.508)
		(layer "B.Cu")
		(net "GND")
	)
	(segment
		(start 82.61096 -20.579842)
		(end 81.814924 -20.579842)
		(width 0.254)
		(layer "B.Cu")
		(net "GND")
	)
	(segment
		(start 79.26324 -33.8582)
		(end 80.022192 -33.8582)
		(width 0.3048)
		(layer "B.Cu")
		(net "GND")
	)
	(segment
		(start 82.57667 -46.642528)
		(end 82.911442 -46.642528)
		(width 0.508)
		(layer "B.Cu")
		(net "GND")
	)
	(segment
		(start 78.284832 -25.07996)
		(end 78.284832 -25.89403)
		(width 0.254)
		(layer "B.Cu")
		(net "GND")
	)
	(segment
		(start 80.3656 -8.382)
		(end 80.3656 -6.192774)
		(width 0.381)
		(layer "B.Cu")
		(net "GND")
	)
	(segment
		(start 81.814924 -25.62987)
		(end 81.814924 -25.07996)
		(width 0.254)
		(layer "B.Cu")
		(net "GND")
	)
	(segment
		(start 83.320636 -46.233334)
		(end 83.320636 -45.665136)
		(width 0.508)
		(layer "B.Cu")
		(net "GND")
	)
	(segment
		(start 124.290074 -51.74996)
		(end 124.290074 -52.550568)
		(width 0.508)
		(layer "In2.Cu")
		(net "GND")
	)
	(segment
		(start 124.290074 -50.949352)
		(end 124.290074 -51.74996)
		(width 0.508)
		(layer "In2.Cu")
		(net "GND")
	)
	(segment
		(start 124.290074 -34.24936)
		(end 124.290074 -35.049968)
		(width 0.508)
		(layer "In2.Cu")
		(net "GND")
	)
	(segment
		(start 124.290074 -35.049968)
		(end 124.290074 -35.850576)
		(width 0.508)
		(layer "In2.Cu")
		(net "GND")
	)
	(segment
		(start 30.819598 -5.184648)
		(end 30.819598 -5.959856)
		(width 0.508)
		(layer "In3.Cu")
		(net "GND")
	)
	(segment
		(start 40.204898 -13.049504)
		(end 40.204898 -13.850112)
		(width 0.508)
		(layer "In3.Cu")
		(net "GND")
	)
	(segment
		(start 35.620198 -16.484854)
		(end 35.620198 -17.260062)
		(width 0.508)
		(layer "In3.Cu")
		(net "GND")
	)
	(segment
		(start 42.744898 -13.049504)
		(end 42.744898 -13.850112)
		(width 0.508)
		(layer "In3.Cu")
		(net "GND")
	)
	(segment
		(start 30.044898 -13.850112)
		(end 30.044898 -14.65072)
		(width 0.508)
		(layer "In3.Cu")
		(net "GND")
	)
	(segment
		(start 50.364898 -13.049504)
		(end 50.364898 -13.850112)
		(width 0.508)
		(layer "In3.Cu")
		(net "GND")
	)
	(segment
		(start 35.620198 -5.959856)
		(end 35.620198 -6.735064)
		(width 0.508)
		(layer "In3.Cu")
		(net "GND")
	)
	(segment
		(start 30.044898 -13.049504)
		(end 30.044898 -13.850112)
		(width 0.508)
		(layer "In3.Cu")
		(net "GND")
	)
	(segment
		(start 22.424898 -13.850112)
		(end 22.424898 -14.65072)
		(width 0.508)
		(layer "In3.Cu")
		(net "GND")
	)
	(segment
		(start 49.735232 -1.92024)
		(end 50.364898 -2.549906)
		(width 0.508)
		(layer "In3.Cu")
		(net "GND")
	)
	(segment
		(start 26.234898 -13.850112)
		(end 26.234898 -14.65072)
		(width 0.508)
		(layer "In3.Cu")
		(net "GND")
	)
	(segment
		(start 41.474898 -13.850112)
		(end 41.474898 -14.65072)
		(width 0.508)
		(layer "In3.Cu")
		(net "GND")
	)
	(segment
		(start 30.819598 -5.959856)
		(end 30.819598 -6.735064)
		(width 0.508)
		(layer "In3.Cu")
		(net "GND")
	)
	(segment
		(start 26.234898 -13.049504)
		(end 26.234898 -13.850112)
		(width 0.508)
		(layer "In3.Cu")
		(net "GND")
	)
	(segment
		(start 30.044898 -13.850112)
		(end 30.845506 -13.850112)
		(width 0.508)
		(layer "In3.Cu")
		(net "GND")
	)
	(segment
		(start 30.044898 -2.549906)
		(end 30.044898 -3.350514)
		(width 0.508)
		(layer "In3.Cu")
		(net "GND")
	)
	(segment
		(start 30.14599 -16.484854)
		(end 30.819598 -17.260062)
		(width 0.508)
		(layer "In3.Cu")
		(net "GND")
	)
	(segment
		(start 40.204898 -2.549906)
		(end 40.204898 -3.350514)
		(width 0.508)
		(layer "In3.Cu")
		(net "GND")
	)
	(segment
		(start 30.14599 -5.959856)
		(end 30.819598 -5.959856)
		(width 0.508)
		(layer "In3.Cu")
		(net "GND")
	)
	(segment
		(start 30.819598 -16.484854)
		(end 30.819598 -17.260062)
		(width 0.508)
		(layer "In3.Cu")
		(net "GND")
	)
	(segment
		(start 21.62429 -2.549906)
		(end 22.424898 -2.549906)
		(width 0.508)
		(layer "In3.Cu")
		(net "GND")
	)
	(segment
		(start 41.474898 -2.549906)
		(end 41.474898 -3.350514)
		(width 0.508)
		(layer "In3.Cu")
		(net "GND")
	)
	(segment
		(start 22.424898 -2.549906)
		(end 22.424898 -3.350514)
		(width 0.508)
		(layer "In3.Cu")
		(net "GND")
	)
	(segment
		(start 49.735232 -13.220446)
		(end 50.364898 -13.850112)
		(width 0.508)
		(layer "In3.Cu")
		(net "GND")
	)
	(segment
		(start 42.744898 -2.549906)
		(end 42.744898 -3.350514)
		(width 0.508)
		(layer "In3.Cu")
		(net "GND")
	)
	(segment
		(start 26.234898 -2.549906)
		(end 26.5938 -3.364992)
		(width 0.508)
		(layer "In3.Cu")
		(net "GND")
	)
	(segment
		(start 39.575232 -1.92024)
		(end 40.204898 -2.549906)
		(width 0.508)
		(layer "In3.Cu")
		(net "GND")
	)
	(segment
		(start 35.620198 -5.184648)
		(end 35.620198 -5.959856)
		(width 0.508)
		(layer "In3.Cu")
		(net "GND")
	)
	(segment
		(start 30.044898 -2.549906)
		(end 30.845506 -2.549906)
		(width 0.508)
		(layer "In3.Cu")
		(net "GND")
	)
	(segment
		(start 50.364898 -2.549906)
		(end 50.364898 -3.350514)
		(width 0.508)
		(layer "In3.Cu")
		(net "GND")
	)
	(segment
		(start 21.62429 -13.850112)
		(end 22.424898 -13.850112)
		(width 0.508)
		(layer "In3.Cu")
		(net "GND")
	)
	(segment
		(start 42.744898 -13.850112)
		(end 42.744898 -14.65072)
		(width 0.508)
		(layer "In3.Cu")
		(net "GND")
	)
	(segment
		(start 22.424898 -13.049504)
		(end 22.424898 -13.850112)
		(width 0.508)
		(layer "In3.Cu")
		(net "GND")
	)
	(segment
		(start 40.204898 -13.850112)
		(end 40.204898 -14.65072)
		(width 0.508)
		(layer "In3.Cu")
		(net "GND")
	)
	(segment
		(start 42.115232 -1.92024)
		(end 42.744898 -2.549906)
		(width 0.508)
		(layer "In3.Cu")
		(net "GND")
	)
	(segment
		(start 40.845232 -1.92024)
		(end 41.474898 -2.549906)
		(width 0.508)
		(layer "In3.Cu")
		(net "GND")
	)
	(segment
		(start 26.234898 -2.549906)
		(end 26.234898 -3.350514)
		(width 0.508)
		(layer "In3.Cu")
		(net "GND")
	)
	(segment
		(start 35.620198 -17.260062)
		(end 36.293806 -16.484854)
		(width 0.508)
		(layer "In3.Cu")
		(net "GND")
	)
	(segment
		(start 41.474898 -13.049504)
		(end 41.474898 -13.850112)
		(width 0.508)
		(layer "In3.Cu")
		(net "GND")
	)
	(segment
		(start 35.620198 -5.959856)
		(end 36.293806 -5.959856)
		(width 0.508)
		(layer "In3.Cu")
		(net "GND")
	)
	(segment
		(start 44.014898 -2.549906)
		(end 44.014898 -3.350514)
		(width 0.508)
		(layer "F.Cu")
		(net "5V_PRE_3")
	)
	(segment
		(start 44.014898 -2.549906)
		(end 44.3738 -3.364992)
		(width 0.508)
		(layer "F.Cu")
		(net "5V_PRE_3")
	)
	(segment
		(start 44.014898 -13.850112)
		(end 44.014898 -14.65072)
		(width 0.508)
		(layer "F.Cu")
		(net "5V_PRE_2")
	)
	(segment
		(start 44.014898 -13.850112)
		(end 44.3738 -14.665198)
		(width 0.508)
		(layer "F.Cu")
		(net "5V_PRE_2")
	)
	(segment
		(start 117.940074 -35.049968)
		(end 117.940074 -35.850576)
		(width 0.508)
		(layer "F.Cu")
		(net "5V_PRE_1")
	)
	(segment
		(start 117.940074 -35.049968)
		(end 118.298976 -35.865054)
		(width 0.508)
		(layer "F.Cu")
		(net "5V_PRE_1")
	)
	(segment
		(start 117.940074 -51.74996)
		(end 117.940074 -52.550568)
		(width 0.508)
		(layer "F.Cu")
		(net "5V_PRE_0")
	)
	(segment
		(start 117.310408 -52.379626)
		(end 117.940074 -51.74996)
		(width 0.508)
		(layer "F.Cu")
		(net "5V_PRE_0")
	)
	(segment
		(start 51.005232 -3.179572)
		(end 51.634898 -2.549906)
		(width 0.508)
		(layer "F.Cu")
		(net "12V_PRE_3")
	)
	(segment
		(start 51.634898 -2.549906)
		(end 51.634898 -3.350514)
		(width 0.508)
		(layer "F.Cu")
		(net "12V_PRE_3")
	)
	(segment
		(start 51.005232 -14.479778)
		(end 51.634898 -13.850112)
		(width 0.508)
		(layer "F.Cu")
		(net "12V_PRE_2")
	)
	(segment
		(start 51.634898 -13.850112)
		(end 51.634898 -14.65072)
		(width 0.508)
		(layer "F.Cu")
		(net "12V_PRE_2")
	)
	(segment
		(start 125.560074 -35.049968)
		(end 126.18974 -35.679634)
		(width 0.508)
		(layer "F.Cu")
		(net "12V_PRE_1")
	)
	(segment
		(start 125.560074 -35.049968)
		(end 125.560074 -35.850576)
		(width 0.508)
		(layer "F.Cu")
		(net "12V_PRE_1")
	)
	(segment
		(start 124.930408 -52.379626)
		(end 125.560074 -51.74996)
		(width 0.508)
		(layer "F.Cu")
		(net "12V_PRE_0")
	)
	(segment
		(start 125.560074 -51.74996)
		(end 125.560074 -52.550568)
		(width 0.508)
		(layer "F.Cu")
		(net "12V_PRE_0")
	)
	(zone
		(layer "F.Cu")
		(hatch none 0.5)
		(connect_pads
			(clearance 0)
		)
		(min_thickness 0.25)
		(keepout
			(tracks allowed)
			(vias allowed)
			(pads allowed)
			(copperpour allowed)
			(footprints not_allowed)
		)
		(placement
			(enabled no)
			(sheetname "")
		)
		(fill
			(thermal_gap 0.5)
			(thermal_bridge_width 0.5)
			(island_removal_mode 0)
		)
		(polygon
			(pts
				(arc
					(start 79.749904 -3.50012)
					(mid 77.0001 -6.249924)
					(end 74.250042 -3.50012)
				)
				(arc
					(start 74.250042 -3.50012)
					(mid 77.0001 -0.750062)
					(end 79.749904 -3.50012)
				)
			)
		)
	)
	(zone
		(layer "F.Cu")
		(hatch none 0.5)
		(connect_pads
			(clearance 0)
		)
		(min_thickness 0.25)
		(keepout
			(tracks allowed)
			(vias allowed)
			(pads allowed)
			(copperpour allowed)
			(footprints not_allowed)
		)
		(placement
			(enabled no)
			(sheetname "")
		)
		(fill
			(thermal_gap 0.5)
			(thermal_bridge_width 0.5)
			(island_removal_mode 0)
		)
		(polygon
			(pts
				(arc
					(start 1.249934 -4.020058)
					(mid 3.999992 -1.27)
					(end 6.75005 -4.020058)
				)
				(arc
					(start 6.75005 -4.020058)
					(mid 3.999992 -6.770116)
					(end 1.249934 -4.020058)
				)
			)
		)
	)
	(zone
		(net "P5V")
		(layer "F.Cu")
		(hatch none 0.5)
		(connect_pads
			(clearance 0.5)
		)
		(min_thickness 0.25)
		(fill yes
			(thermal_gap 0.5)
			(thermal_bridge_width 0.5)
			(island_removal_mode 0)
		)
		(polygon
			(pts
				(xy 12.167362 -19.003772) (xy 11.968734 -19.2024) (xy 11.968734 -21.311362) (xy 12.254992 -21.59762)
				(xy 15.488666 -21.59762) (xy 15.665958 -21.420328) (xy 15.665958 -19.24304) (xy 15.42669 -19.003772)
			)
		)
		(polygon
			(pts
				(xy 12.6746 -20.3962) (xy 12.4714 -20.3962) (xy 12.4714 -20.5994) (xy 12.6746 -20.5994)
			)
		)
		(polygon
			(pts
				(xy 12.6746 -19.5072) (xy 12.4714 -19.5072) (xy 12.4714 -19.9898) (xy 12.6746 -19.9898)
			)
		)
	)
	(zone
		(net "GND")
		(layer "F.Cu")
		(hatch none 0.5)
		(connect_pads
			(clearance 0.5)
		)
		(min_thickness 0.25)
		(fill yes
			(thermal_gap 0.5)
			(thermal_bridge_width 0.5)
			(island_removal_mode 0)
		)
		(polygon
			(pts
				(xy 50.717958 -18.835116) (xy 50.619152 -18.933922) (xy 50.619152 -21.917152) (xy 50.927 -22.225)
				(xy 52.9209 -22.225) (xy 53.0479 -22.098) (xy 53.0479 -19.862292) (xy 52.82311 -19.637502) (xy 52.117498 -19.637502)
				(xy 51.98364 -19.503644) (xy 51.98364 -18.969482) (xy 51.849274 -18.835116)
			)
		)
		(polygon
			(pts
				(xy 51.31562 -20.996656) (xy 51.11242 -20.996656) (xy 51.11242 -21.199856) (xy 51.31562 -21.199856)
			)
		)
		(polygon
			(pts
				(xy 51.31562 -20.387056) (xy 51.11242 -20.387056) (xy 51.11242 -20.590256) (xy 51.31562 -20.590256)
			)
		)
		(polygon
			(pts
				(xy 52.5018 -20.0914) (xy 52.2986 -20.0914) (xy 52.2986 -20.2946) (xy 52.5018 -20.2946)
			)
		)
	)
	(zone
		(layer "F.Cu")
		(hatch none 0.5)
		(connect_pads
			(clearance 0)
		)
		(min_thickness 0.25)
		(keepout
			(tracks allowed)
			(vias allowed)
			(pads allowed)
			(copperpour allowed)
			(footprints not_allowed)
		)
		(placement
			(enabled no)
			(sheetname "")
		)
		(fill
			(thermal_gap 0.5)
			(thermal_bridge_width 0.5)
			(island_removal_mode 0)
		)
		(polygon
			(pts
				(arc
					(start 6.75005 -17.020032)
					(mid 3.999992 -19.77009)
					(end 1.249934 -17.020032)
				)
				(arc
					(start 1.249934 -17.020032)
					(mid 3.999992 -14.269974)
					(end 6.75005 -17.020032)
				)
			)
		)
	)
	(zone
		(layer "F.Cu")
		(hatch none 0.5)
		(connect_pads
			(clearance 0)
		)
		(min_thickness 0.25)
		(keepout
			(tracks allowed)
			(vias allowed)
			(pads allowed)
			(copperpour allowed)
			(footprints not_allowed)
		)
		(placement
			(enabled no)
			(sheetname "")
		)
		(fill
			(thermal_gap 0.5)
			(thermal_bridge_width 0.5)
			(island_removal_mode 0)
		)
		(polygon
			(pts
				(arc
					(start 6.75005 -4.020058)
					(mid 3.999992 -6.770116)
					(end 1.249934 -4.020058)
				)
				(arc
					(start 1.249934 -4.020058)
					(mid 3.999992 -1.27)
					(end 6.75005 -4.020058)
				)
			)
		)
	)
	(zone
		(net "GND")
		(layer "F.Cu")
		(hatch none 0.5)
		(connect_pads
			(clearance 0.5)
		)
		(min_thickness 0.25)
		(fill yes
			(thermal_gap 0.5)
			(thermal_bridge_width 0.5)
			(island_removal_mode 0)
		)
		(polygon
			(pts
				(arc
					(start 0.999998 -0.763016)
					(mid 0.832426 -0.832426)
					(end 0.763016 -0.999998)
				)
				(arc
					(start 0.763016 -22.200108)
					(mid 0.832426 -22.36768)
					(end 0.999998 -22.43709)
				)
				(xy 47.772066 -22.43709) (xy 48.099472 -22.109684) (xy 48.099472 -20.701) (xy 47.624492 -20.22602)
				(xy 44.976034 -20.22602) (xy 42.75963 -18.009616) (xy 16.593566 -18.009616) (xy 16.133318 -18.469864)
				(xy 16.133318 -21.418042) (xy 15.661132 -21.890228) (xy 11.952478 -21.890228) (xy 11.65479 -21.59254)
				(xy 11.65479 -18.861532) (xy 11.870436 -18.645886) (xy 13.716 -18.645886) (xy 14.097 -18.264886)
				(xy 14.097 -1.0922) (xy 13.767816 -0.763016)
			)
		)
		(polygon
			(pts
				(xy 11.1506 -20.3962) (xy 10.9474 -20.3962) (xy 10.9474 -20.5994) (xy 11.1506 -20.5994)
			)
		)
		(polygon
			(pts
				(xy 11.1506 -19.5072) (xy 10.9474 -19.5072) (xy 10.9474 -19.9898) (xy 11.1506 -19.9898)
			)
		)
		(polygon
			(pts
				(xy 11.1506 -18.8976) (xy 10.9474 -18.8976) (xy 10.9474 -19.1008) (xy 11.1506 -19.1008)
			)
		)
	)
	(zone
		(layer "F.Cu")
		(hatch none 0.5)
		(connect_pads
			(clearance 0)
		)
		(min_thickness 0.25)
		(keepout
			(tracks allowed)
			(vias allowed)
			(pads allowed)
			(copperpour allowed)
			(footprints not_allowed)
		)
		(placement
			(enabled no)
			(sheetname "")
		)
		(fill
			(thermal_gap 0.5)
			(thermal_bridge_width 0.5)
			(island_removal_mode 0)
		)
		(polygon
			(pts
				(arc
					(start 75.350116 -3.50012)
					(mid 77.0001 -1.850136)
					(end 78.650084 -3.50012)
				)
				(arc
					(start 78.650084 -3.50012)
					(mid 77.0001 -5.150104)
					(end 75.350116 -3.50012)
				)
			)
		)
	)
	(zone
		(net "12V_PRE_2")
		(layer "F.Cu")
		(hatch none 0.5)
		(connect_pads
			(clearance 0.5)
		)
		(min_thickness 0.25)
		(fill yes
			(thermal_gap 0.5)
			(thermal_bridge_width 0.5)
			(island_removal_mode 0)
		)
		(polygon
			(pts
				(xy 51.45024 -13.431012) (xy 51.19751 -13.683742) (xy 51.19751 -13.897102) (xy 50.74539 -14.349222)
				(xy 50.74539 -15.068804) (xy 54.31028 -18.633694) (xy 54.31028 -19.25066) (xy 54.533292 -19.473672)
				(xy 55.363872 -19.473672) (xy 55.44693 -19.390614) (xy 55.44693 -18.07464) (xy 52.157884 -14.785594)
				(xy 52.157884 -14.17574) (xy 52.06746 -14.085316) (xy 52.06746 -13.691108) (xy 51.807364 -13.431012)
			)
		)
		(polygon
			(pts
				(xy 54.684676 -18.506948) (xy 54.481476 -18.506948) (xy 54.481476 -18.710148) (xy 54.684676 -18.710148)
			)
		)
	)
	(zone
		(net "P12V_SW_R")
		(layer "F.Cu")
		(hatch none 0.5)
		(connect_pads
			(clearance 0.5)
		)
		(min_thickness 0.25)
		(fill yes
			(thermal_gap 0.5)
			(thermal_bridge_width 0.5)
			(island_removal_mode 0)
		)
		(polygon
			(pts
				(xy 75.2856 -36.322) (xy 75.0824 -36.5252) (xy 75.0824 -42.1132) (xy 75.1586 -42.1894) (xy 79.562198 -42.1894)
				(xy 79.612236 -42.139362) (xy 83.022948 -42.139362) (xy 83.281774 -41.880536) (xy 83.281774 -40.523922)
				(xy 82.43824 -39.680388) (xy 82.43824 -38.5445) (xy 81.469738 -37.575998) (xy 78.647798 -37.575998)
				(xy 77.3938 -36.322)
			)
		)
		(polygon
			(pts
				(xy 75.7682 -41.4528) (xy 75.565 -41.4528) (xy 75.565 -41.656) (xy 75.7682 -41.656)
			)
		)
	)
	(zone
		(net "GND")
		(layer "F.Cu")
		(hatch none 0.5)
		(connect_pads
			(clearance 0.5)
		)
		(min_thickness 0.25)
		(fill yes
			(thermal_gap 0.5)
			(thermal_bridge_width 0.5)
			(island_removal_mode 0)
		)
		(polygon
			(pts
				(xy 80.864456 -11.502136) (xy 80.711548 -11.655044) (xy 80.711548 -14.508734) (xy 81.124298 -14.921484)
				(xy 84.24164 -14.921484) (xy 84.382102 -14.781022) (xy 84.382102 -14.056614) (xy 84.316062 -13.990574)
				(xy 82.993992 -13.990574) (xy 82.884772 -13.881608) (xy 82.770726 -13.767562) (xy 82.770726 -11.564112)
				(xy 82.70875 -11.502136)
			)
		)
		(polygon
			(pts
				(xy 81.317084 -11.996166) (xy 81.113884 -11.996166) (xy 81.113884 -12.199366) (xy 81.317084 -12.199366)
			)
		)
		(polygon
			(pts
				(xy 82.200242 -11.994896) (xy 81.997042 -11.994896) (xy 81.926684 -11.996166) (xy 81.723484 -11.996166)
				(xy 81.723484 -12.199366) (xy 81.926684 -12.199366) (xy 81.997042 -12.198096) (xy 82.200242 -12.198096)
			)
		)
	)
	(zone
		(net "P12V_SW_R")
		(layer "F.Cu")
		(hatch none 0.5)
		(connect_pads
			(clearance 0.5)
		)
		(min_thickness 0.25)
		(fill yes
			(thermal_gap 0.5)
			(thermal_bridge_width 0.5)
			(island_removal_mode 0)
		)
		(polygon
			(pts
				(xy 126.657862 -34.597086) (xy 126.408688 -34.84626) (xy 126.408688 -35.251644) (xy 130.96494 -39.807896)
				(xy 130.96494 -45.550836) (xy 126.4158 -50.099976) (xy 126.4158 -55.0164) (xy 125.8824 -55.5498)
				(xy 125.8824 -57.265824) (xy 126.031498 -57.414922) (xy 128.60401 -57.414922) (xy 128.7018 -57.317132)
				(xy 128.7018 -55.534814) (xy 129.978912 -54.257702) (xy 129.978912 -51.518058) (xy 133.760972 -47.735998)
				(xy 133.760972 -39.908226) (xy 128.449832 -34.597086)
			)
		)
		(polygon
			(pts
				(xy 126.884684 -56.375808) (xy 126.681484 -56.375808) (xy 126.681484 -56.579008) (xy 126.884684 -56.579008)
			)
		)
		(polygon
			(pts
				(xy 131.9276 -40.5892) (xy 131.7244 -40.5892) (xy 131.7244 -40.7924) (xy 131.9276 -40.7924)
			)
		)
		(polygon
			(pts
				(xy 131.9276 -39.7256) (xy 131.7244 -39.7256) (xy 131.7244 -39.9288) (xy 131.9276 -39.9288)
			)
		)
	)
	(zone
		(net "5V_PRE_1")
		(layer "F.Cu")
		(hatch none 0.5)
		(connect_pads
			(clearance 0.5)
		)
		(min_thickness 0.25)
		(fill yes
			(thermal_gap 0.5)
			(thermal_bridge_width 0.5)
			(island_removal_mode 0)
		)
		(polygon
			(pts
				(xy 117.745002 -34.628582) (xy 117.503194 -34.87039) (xy 117.503194 -35.211766) (xy 117.295168 -35.419792)
				(xy 117.295168 -36.933378) (xy 120.817894 -40.456104) (xy 121.02846 -40.666416) (xy 124.432568 -40.666416)
				(xy 124.549916 -40.549068) (xy 124.549916 -39.853108) (xy 123.26366 -38.566852) (xy 121.309384 -38.566852)
				(xy 120.269 -37.526468) (xy 120.26011 -37.526468) (xy 118.665752 -35.93211) (xy 118.665752 -35.151568)
				(xy 118.142766 -34.628582)
			)
		)
		(polygon
			(pts
				(xy 123.7996 -39.6748) (xy 123.5964 -39.6748) (xy 123.5964 -39.878) (xy 123.7996 -39.878)
			)
		)
	)
	(zone
		(net "P3V3")
		(layer "F.Cu")
		(hatch none 0.5)
		(connect_pads
			(clearance 0.5)
		)
		(min_thickness 0.25)
		(fill yes
			(thermal_gap 0.5)
			(thermal_bridge_width 0.5)
			(island_removal_mode 0)
		)
		(polygon
			(pts
				(xy 70.902576 -15.098776) (xy 70.685914 -15.315438) (xy 70.685914 -22.649434) (xy 70.589902 -22.745446)
				(xy 70.589902 -34.335466) (xy 70.896734 -34.642298) (xy 77.546708 -34.642298) (xy 77.933296 -34.25571)
				(xy 77.933296 -33.348676) (xy 77.115416 -32.530796) (xy 73.787 -32.530796) (xy 73.279 -32.022796)
				(xy 73.279 -17.731486) (xy 72.948292 -17.400778) (xy 72.948292 -15.378176) (xy 72.668892 -15.098776)
			)
		)
		(polygon
			(pts
				(xy 77.4954 -34.0868) (xy 77.2922 -34.0868) (xy 77.2922 -34.29) (xy 77.4954 -34.29)
			)
		)
		(polygon
			(pts
				(xy 77.4954 -33.528) (xy 77.2922 -33.528) (xy 77.2922 -33.7312) (xy 77.4954 -33.7312)
			)
		)
	)
	(zone
		(net "5V_PRE_2")
		(layer "F.Cu")
		(hatch none 0.5)
		(connect_pads
			(clearance 0.5)
		)
		(min_thickness 0.25)
		(fill yes
			(thermal_gap 0.5)
			(thermal_bridge_width 0.5)
			(island_removal_mode 0)
		)
		(polygon
			(pts
				(xy 43.847258 -13.423392) (xy 43.582844 -13.687806) (xy 43.582844 -15.004796) (xy 43.221148 -15.366492)
				(xy 43.221148 -17.097502) (xy 45.708316 -19.58467) (xy 46.987206 -19.58467) (xy 46.987206 -17.655794)
				(xy 44.456604 -15.125192) (xy 44.456604 -13.682472) (xy 44.197524 -13.423392)
			)
		)
		(polygon
			(pts
				(xy 46.0756 -18.5166) (xy 45.8724 -18.5166) (xy 45.8724 -18.7198) (xy 46.0756 -18.7198)
			)
		)
	)
	(zone
		(net "P5V")
		(layer "F.Cu")
		(hatch none 0.5)
		(connect_pads
			(clearance 0.5)
		)
		(min_thickness 0.25)
		(fill yes
			(thermal_gap 0.5)
			(thermal_bridge_width 0.5)
			(island_removal_mode 0)
		)
		(polygon
			(pts
				(xy 82.931 -48.641) (xy 82.804 -48.768) (xy 82.804 -49.628044) (xy 83.08086 -49.904904) (xy 83.08086 -51.724814)
				(xy 83.426046 -52.07) (xy 86.36 -52.07) (xy 86.487 -51.943) (xy 86.487 -48.895) (xy 86.233 -48.641)
			)
		)
	)
	(zone
		(layer "F.Cu")
		(hatch none 0.5)
		(connect_pads
			(clearance 0)
		)
		(min_thickness 0.25)
		(keepout
			(tracks allowed)
			(vias allowed)
			(pads allowed)
			(copperpour allowed)
			(footprints not_allowed)
		)
		(placement
			(enabled no)
			(sheetname "")
		)
		(fill
			(thermal_gap 0.5)
			(thermal_bridge_width 0.5)
			(island_removal_mode 0)
		)
		(polygon
			(pts
				(arc
					(start 79.749904 -61.699902)
					(mid 77.0001 -64.449706)
					(end 74.250042 -61.699902)
				)
				(arc
					(start 74.250042 -61.699902)
					(mid 77.0001 -58.949844)
					(end 79.749904 -61.699902)
				)
			)
		)
	)
	(zone
		(net "P5V")
		(layer "F.Cu")
		(hatch none 0.5)
		(connect_pads
			(clearance 0.5)
		)
		(min_thickness 0.25)
		(fill yes
			(thermal_gap 0.5)
			(thermal_bridge_width 0.5)
			(island_removal_mode 0)
		)
		(polygon
			(pts
				(xy 69.49567 -9.701276) (xy 68.979542 -10.217404) (xy 68.979542 -14.547342) (xy 69.1388 -14.7066)
				(xy 72.7202 -14.7066) (xy 73.1012 -14.3256) (xy 73.1012 -10.16) (xy 72.642476 -9.701276)
			)
		)
	)
	(zone
		(net "P12V")
		(layer "F.Cu")
		(hatch none 0.5)
		(connect_pads
			(clearance 0.5)
		)
		(min_thickness 0.25)
		(fill yes
			(thermal_gap 0.5)
			(thermal_bridge_width 0.5)
			(island_removal_mode 0)
		)
		(polygon
			(pts
				(xy 87.220552 -10.16) (xy 86.906862 -10.47369) (xy 86.906862 -13.761974) (xy 87.042498 -13.89761)
				(xy 92.1385 -13.89761) (xy 92.202 -13.83411) (xy 92.202 -10.414) (xy 91.948 -10.16)
			)
		)
		(polygon
			(pts
				(xy 91.4908 -10.6934) (xy 91.2876 -10.6934) (xy 91.2876 -10.8966) (xy 91.4908 -10.8966)
			)
		)
		(polygon
			(pts
				(xy 91.059 -10.6426) (xy 90.8558 -10.6426) (xy 90.8558 -10.8458) (xy 91.059 -10.8458)
			)
		)
		(polygon
			(pts
				(xy 90.5002 -10.6426) (xy 90.297 -10.6426) (xy 90.297 -10.8458) (xy 90.5002 -10.8458)
			)
		)
	)
	(zone
		(layer "F.Cu")
		(hatch none 0.5)
		(connect_pads
			(clearance 0)
		)
		(min_thickness 0.25)
		(keepout
			(tracks allowed)
			(vias allowed)
			(pads allowed)
			(copperpour allowed)
			(footprints not_allowed)
		)
		(placement
			(enabled no)
			(sheetname "")
		)
		(fill
			(thermal_gap 0.5)
			(thermal_bridge_width 0.5)
			(island_removal_mode 0)
		)
		(polygon
			(pts
				(arc
					(start 75.350116 -61.699902)
					(mid 77.0001 -60.049918)
					(end 78.650084 -61.699902)
				)
				(arc
					(start 78.650084 -61.699902)
					(mid 77.0001 -63.349886)
					(end 75.350116 -61.699902)
				)
			)
		)
	)
	(zone
		(net "P12V_SW_L")
		(layer "F.Cu")
		(hatch none 0.5)
		(connect_pads
			(clearance 0.5)
		)
		(min_thickness 0.25)
		(fill yes
			(thermal_gap 0.5)
			(thermal_bridge_width 0.5)
			(island_removal_mode 0)
		)
		(polygon
			(pts
				(xy 83.13928 -10.406888) (xy 83.13928 -13.494258) (xy 83.31073 -13.665708) (xy 86.02472 -13.665708)
				(xy 86.187788 -13.50264) (xy 86.187788 -10.478262) (xy 85.957156 -10.24763) (xy 83.298538 -10.24763)
			)
		)
	)
	(zone
		(net "GND")
		(layer "F.Cu")
		(hatch none 0.5)
		(connect_pads
			(clearance 0.5)
		)
		(min_thickness 0.25)
		(fill yes
			(thermal_gap 0.5)
			(thermal_bridge_width 0.5)
			(island_removal_mode 0)
		)
		(polygon
			(pts
				(xy 51.66741 -7.751064) (xy 51.575208 -7.843266) (xy 51.575208 -10.19937) (xy 51.728116 -10.352278)
				(xy 54.733952 -10.352278) (xy 54.873652 -10.212578) (xy 54.873652 -9.75487) (xy 54.746144 -9.627362)
				(xy 54.177946 -9.627362) (xy 53.980588 -9.430004) (xy 53.980588 -8.840724) (xy 53.872384 -8.73252)
				(xy 53.063394 -8.73252) (xy 52.901596 -8.570722) (xy 52.901596 -7.776718) (xy 52.875942 -7.751064)
			)
		)
		(polygon
			(pts
				(xy 52.291996 -9.484614) (xy 52.088796 -9.484614) (xy 52.088796 -9.687814) (xy 52.291996 -9.687814)
			)
		)
		(polygon
			(pts
				(xy 53.4162 -9.2456) (xy 53.213 -9.2456) (xy 53.213 -9.4488) (xy 53.4162 -9.4488)
			)
		)
	)
	(zone
		(net "P5V_SW_L")
		(layer "F.Cu")
		(hatch none 0.5)
		(connect_pads
			(clearance 0.5)
		)
		(min_thickness 0.25)
		(fill yes
			(thermal_gap 0.5)
			(thermal_bridge_width 0.5)
			(island_removal_mode 0)
		)
		(polygon
			(pts
				(xy 65.413382 -9.381236) (xy 65.202308 -9.59231) (xy 65.202308 -13.38834) (xy 65.470786 -13.656818)
				(xy 67.982592 -13.656818) (xy 68.203064 -13.436346) (xy 68.203064 -9.592056) (xy 67.992244 -9.381236)
			)
		)
	)
	(zone
		(layer "F.Cu")
		(hatch none 0.5)
		(connect_pads
			(clearance 0)
		)
		(min_thickness 0.25)
		(keepout
			(tracks not_allowed)
			(vias allowed)
			(pads allowed)
			(copperpour not_allowed)
			(footprints allowed)
		)
		(placement
			(enabled no)
			(sheetname "")
		)
		(fill
			(thermal_gap 0.5)
			(thermal_bridge_width 0.5)
			(island_removal_mode 0)
		)
		(polygon
			(pts
				(arc
					(start 128.250188 -21.79193)
					(mid 129.178208 -21.080978)
					(end 130.109214 -21.787866)
				)
				(arc
					(start 130.249676 -21.787866)
					(mid 129.178017 -20.943309)
					(end 128.109726 -21.79193)
				)
			)
		)
	)
	(zone
		(layer "F.Cu")
		(hatch none 0.5)
		(connect_pads
			(clearance 0)
		)
		(min_thickness 0.25)
		(keepout
			(tracks allowed)
			(vias allowed)
			(pads allowed)
			(copperpour allowed)
			(footprints not_allowed)
		)
		(placement
			(enabled no)
			(sheetname "")
		)
		(fill
			(thermal_gap 0.5)
			(thermal_bridge_width 0.5)
			(island_removal_mode 0)
		)
		(polygon
			(pts
				(arc
					(start 138.34999 -61.699902)
					(mid 139.999974 -60.049918)
					(end 141.649958 -61.699902)
				)
				(arc
					(start 141.649958 -61.699902)
					(mid 139.999974 -63.349886)
					(end 138.34999 -61.699902)
				)
			)
		)
	)
	(zone
		(net "GND")
		(layer "F.Cu")
		(hatch none 0.5)
		(connect_pads
			(clearance 0.5)
		)
		(min_thickness 0.25)
		(fill yes
			(thermal_gap 0.5)
			(thermal_bridge_width 0.5)
			(island_removal_mode 0)
		)
		(polygon
			(pts
				(xy 61.435742 -1.931416) (xy 61.149738 -2.21742) (xy 61.149738 -15.948914) (xy 60.04306 -17.055592)
				(xy 60.04306 -22.467062) (xy 60.100464 -22.524466) (xy 69.804026 -22.524466) (xy 70.30085 -22.027642)
				(xy 70.30085 -16.51) (xy 67.891406 -14.100556) (xy 65.227708 -14.100556) (xy 64.859662 -13.73251)
				(xy 64.859662 -2.17551) (xy 64.615568 -1.931416)
			)
		)
	)
	(zone
		(net "P5V_SW_L")
		(layer "F.Cu")
		(hatch none 0.5)
		(connect_pads
			(clearance 0.5)
		)
		(min_thickness 0.25)
		(fill yes
			(thermal_gap 0.5)
			(thermal_bridge_width 0.5)
			(island_removal_mode 0)
		)
		(polygon
			(pts
				(xy 45.0977 -2.121662) (xy 44.840398 -2.378964) (xy 44.840398 -2.925318) (xy 45.136816 -3.221736)
				(xy 45.136816 -4.844796) (xy 47.016924 -6.724904) (xy 48.006 -6.724904) (xy 48.4632 -7.182104) (xy 48.4632 -8.8138)
				(xy 49.873154 -10.223754) (xy 51.188874 -10.223754) (xy 51.27625 -10.136378) (xy 51.27625 -6.061456)
				(xy 49.788826 -4.574032) (xy 48.680878 -4.574032) (xy 46.985682 -2.878836) (xy 46.985682 -2.35585)
				(xy 46.751494 -2.121662)
			)
		)
		(polygon
			(pts
				(xy 50.767996 -9.484614) (xy 50.564796 -9.484614) (xy 50.564796 -9.687814) (xy 50.767996 -9.687814)
			)
		)
		(polygon
			(pts
				(xy 49.4284 -8.4836) (xy 49.2252 -8.4836) (xy 49.2252 -8.6868) (xy 49.4284 -8.6868)
			)
		)
		(polygon
			(pts
				(xy 49.4284 -7.62) (xy 49.2252 -7.62) (xy 49.2252 -7.8232) (xy 49.4284 -7.8232)
			)
		)
	)
	(zone
		(net "5V_PRE_3")
		(layer "F.Cu")
		(hatch none 0.5)
		(connect_pads
			(clearance 0.5)
		)
		(min_thickness 0.25)
		(fill yes
			(thermal_gap 0.5)
			(thermal_bridge_width 0.5)
			(island_removal_mode 0)
		)
		(polygon
			(pts
				(xy 43.836336 -2.128012) (xy 43.5864 -2.377948) (xy 43.5864 -3.07594) (xy 43.227498 -3.434842) (xy 43.227498 -7.44474)
				(xy 43.5864 -7.803642) (xy 43.5864 -7.81939) (xy 44.741084 -8.974074) (xy 47.7774 -8.974074) (xy 47.9298 -8.821674)
				(xy 47.9298 -7.384796) (xy 47.8028 -7.257796) (xy 46.699678 -7.257796) (xy 46.681644 -7.239762)
				(xy 46.677326 -7.239762) (xy 44.66082 -5.223256) (xy 44.66082 -3.241294) (xy 44.436792 -3.017266)
				(xy 44.436792 -2.381504) (xy 44.1833 -2.128012)
			)
		)
		(polygon
			(pts
				(xy 47.1424 -8.4836) (xy 46.9392 -8.4836) (xy 46.9392 -8.6868) (xy 47.1424 -8.6868)
			)
		)
		(polygon
			(pts
				(xy 47.1424 -7.62) (xy 46.9392 -7.62) (xy 46.9392 -7.8232) (xy 47.1424 -7.8232)
			)
		)
	)
	(zone
		(layer "F.Cu")
		(hatch none 0.5)
		(connect_pads
			(clearance 0)
		)
		(min_thickness 0.25)
		(keepout
			(tracks allowed)
			(vias allowed)
			(pads allowed)
			(copperpour allowed)
			(footprints not_allowed)
		)
		(placement
			(enabled no)
			(sheetname "")
		)
		(fill
			(thermal_gap 0.5)
			(thermal_bridge_width 0.5)
			(island_removal_mode 0)
		)
		(polygon
			(pts
				(arc
					(start 143.500094 -64.200024)
					(mid 143.207201 -64.907129)
					(end 142.500096 -65.200022)
				)
				(arc
					(start 70.499986 -65.200022)
					(mid 69.792881 -64.907129)
					(end 69.499988 -64.200024)
				)
				(arc
					(start 69.499988 -25.699974)
					(mid 69.207095 -24.992869)
					(end 68.49999 -24.699976)
				)
				(arc
					(start 49.9999 -24.699976)
					(mid 49.646437 -24.553567)
					(end 49.500028 -24.200104)
				)
				(arc
					(start 49.500028 -23.699978)
					(mid 49.353439 -23.34659)
					(end 48.999902 -23.200106)
				)
				(arc
					(start 0.999998 -23.200106)
					(mid 0.292893 -22.907213)
					(end 0 -22.200108)
				)
				(arc
					(start 0 -0.999998)
					(mid 0.292893 -0.292893)
					(end 0.999998 0)
				)
				(arc
					(start 94.499938 0)
					(mid 95.207043 -0.292893)
					(end 95.499936 -0.999998)
				)
				(arc
					(start 95.499936 -23.999952)
					(mid 95.792829 -24.707057)
					(end 96.499934 -24.99995)
				)
				(arc
					(start 117.350032 -24.99995)
					(mid 118.057137 -24.707057)
					(end 118.35003 -23.999952)
				)
				(arc
					(start 118.35003 -20.049998)
					(mid 118.642923 -19.342893)
					(end 119.350028 -19.05)
				)
				(arc
					(start 134.500112 -19.05)
					(mid 135.207217 -18.757107)
					(end 135.50011 -18.050002)
				)
				(arc
					(start 135.50011 -0.999998)
					(mid 135.793003 -0.292893)
					(end 136.500108 0)
				)
				(arc
					(start 142.500096 0)
					(mid 143.207201 -0.292893)
					(end 143.500094 -0.999998)
				)
			)
		)
	)
	(zone
		(layer "F.Cu")
		(hatch none 0.5)
		(connect_pads
			(clearance 0)
		)
		(min_thickness 0.25)
		(keepout
			(tracks allowed)
			(vias allowed)
			(pads allowed)
			(copperpour allowed)
			(footprints not_allowed)
		)
		(placement
			(enabled no)
			(sheetname "")
		)
		(fill
			(thermal_gap 0.5)
			(thermal_bridge_width 0.5)
			(island_removal_mode 0)
		)
		(polygon
			(pts
				(arc
					(start 74.250042 -3.50012)
					(mid 77.0001 -0.750062)
					(end 79.749904 -3.50012)
				)
				(arc
					(start 79.749904 -3.50012)
					(mid 77.0001 -6.249924)
					(end 74.250042 -3.50012)
				)
			)
		)
	)
	(zone
		(net "12V_PRE_0")
		(layer "F.Cu")
		(hatch none 0.5)
		(connect_pads
			(clearance 0.5)
		)
		(min_thickness 0.25)
		(fill yes
			(thermal_gap 0.5)
			(thermal_bridge_width 0.5)
			(island_removal_mode 0)
		)
		(polygon
			(pts
				(xy 125.349 -51.308) (xy 125.0696 -51.5874) (xy 125.0696 -51.9938) (xy 124.2187 -52.8447) (xy 124.2187 -53.5051)
				(xy 124.206 -53.5178) (xy 124.206 -57.334658) (xy 124.299472 -57.42813) (xy 125.261624 -57.42813)
				(xy 125.3744 -57.315354) (xy 125.3744 -54.7878) (xy 126.025148 -54.137052) (xy 126.025148 -51.628548)
				(xy 125.7046 -51.308)
			)
		)
		(polygon
			(pts
				(xy 124.598684 -56.375808) (xy 124.395484 -56.375808) (xy 124.395484 -56.579008) (xy 124.598684 -56.579008)
			)
		)
	)
	(zone
		(layer "F.Cu")
		(hatch none 0.5)
		(connect_pads
			(clearance 0)
		)
		(min_thickness 0.25)
		(keepout
			(tracks allowed)
			(vias allowed)
			(pads allowed)
			(copperpour allowed)
			(footprints not_allowed)
		)
		(placement
			(enabled no)
			(sheetname "")
		)
		(fill
			(thermal_gap 0.5)
			(thermal_bridge_width 0.5)
			(island_removal_mode 0)
		)
		(polygon
			(pts
				(arc
					(start 1.249934 -17.020032)
					(mid 3.999992 -14.269974)
					(end 6.75005 -17.020032)
				)
				(arc
					(start 6.75005 -17.020032)
					(mid 3.999992 -19.77009)
					(end 1.249934 -17.020032)
				)
			)
		)
	)
	(zone
		(layer "F.Cu")
		(hatch none 0.5)
		(connect_pads
			(clearance 0)
		)
		(min_thickness 0.25)
		(keepout
			(tracks allowed)
			(vias allowed)
			(pads allowed)
			(copperpour allowed)
			(footprints not_allowed)
		)
		(placement
			(enabled no)
			(sheetname "")
		)
		(fill
			(thermal_gap 0.5)
			(thermal_bridge_width 0.5)
			(island_removal_mode 0)
		)
		(polygon
			(pts
				(arc
					(start 2.350008 -17.020032)
					(mid 3.999992 -15.370048)
					(end 5.649976 -17.020032)
				)
				(arc
					(start 5.649976 -17.020032)
					(mid 3.999992 -18.670016)
					(end 2.350008 -17.020032)
				)
			)
		)
	)
	(zone
		(layer "F.Cu")
		(hatch none 0.5)
		(connect_pads
			(clearance 0)
		)
		(min_thickness 0.25)
		(keepout
			(tracks not_allowed)
			(vias allowed)
			(pads allowed)
			(copperpour not_allowed)
			(footprints allowed)
		)
		(placement
			(enabled no)
			(sheetname "")
		)
		(fill
			(thermal_gap 0.5)
			(thermal_bridge_width 0.5)
			(island_removal_mode 0)
		)
		(polygon
			(pts
				(arc
					(start 83.597496 -21.166836)
					(mid 83.086956 -20.656296)
					(end 82.576416 -21.166836)
				)
				(xy 82.576416 -21.418042) (xy 82.824066 -21.418042)
				(arc
					(start 82.892646 -21.349462)
					(mid 83.160306 -20.91046)
					(end 83.155282 -21.424646)
				)
				(xy 83.136486 -21.443442) (xy 82.992976 -21.586952) (xy 82.923126 -21.656802) (xy 82.824066 -21.656802)
				(xy 82.576416 -21.656802) (xy 82.576416 -21.860002) (xy 82.833972 -21.860002) (xy 82.933032 -21.860002)
				(arc
					(start 83.002628 -21.929852)
					(mid 83.275604 -22.371314)
					(end 82.833972 -22.098762)
				)
				(xy 82.576416 -22.098762)
				(arc
					(start 82.576416 -22.182582)
					(mid 83.086829 -22.693376)
					(end 83.597496 -22.182836)
				)
			)
		)
	)
	(zone
		(net "P12V_SW_L")
		(layer "F.Cu")
		(hatch none 0.5)
		(connect_pads
			(clearance 0.5)
		)
		(min_thickness 0.25)
		(fill yes
			(thermal_gap 0.5)
			(thermal_bridge_width 0.5)
			(island_removal_mode 0)
		)
		(polygon
			(pts
				(xy 52.727606 -2.118106) (xy 52.468272 -2.37744) (xy 52.468272 -3.212592) (xy 54.961028 -5.705348)
				(xy 55.21706 -5.705348) (xy 57.05475 -7.543038) (xy 57.05475 -10.292588) (xy 55.4355 -11.911838)
				(xy 53.391816 -11.911838) (xy 52.473606 -12.830048) (xy 52.473606 -14.432534) (xy 55.924196 -17.883124)
				(xy 55.924196 -22.135846) (xy 56.359806 -22.571456) (xy 58.660792 -22.571456) (xy 58.775092 -22.457156)
				(xy 58.775092 -18.142712) (xy 56.169052 -15.536672) (xy 56.169052 -14.725396) (xy 58.744104 -12.150344)
				(xy 59.695588 -12.150344) (xy 60.123324 -11.722608) (xy 60.123324 -7.281672) (xy 59.135264 -6.293612)
				(xy 58.130694 -6.293612) (xy 55.54853 -3.711448) (xy 55.54853 -2.361692) (xy 55.304944 -2.118106)
			)
		)
		(polygon
			(pts
				(xy 56.64962 -20.361656) (xy 56.44642 -20.361656) (xy 56.44642 -20.564856) (xy 56.64962 -20.564856)
			)
		)
		(polygon
			(pts
				(xy 56.64962 -19.752056) (xy 56.44642 -19.752056) (xy 56.44642 -19.955256) (xy 56.64962 -19.955256)
			)
		)
		(polygon
			(pts
				(xy 56.970676 -19.370548) (xy 56.767476 -19.370548) (xy 56.767476 -19.573748) (xy 56.970676 -19.573748)
			)
		)
		(polygon
			(pts
				(xy 56.970676 -18.506948) (xy 56.767476 -18.506948) (xy 56.767476 -18.710148) (xy 56.970676 -18.710148)
			)
		)
		(polygon
			(pts
				(xy 57.748424 -9.931146) (xy 57.545224 -9.931146) (xy 57.545224 -10.134346) (xy 57.748424 -10.134346)
			)
		)
		(polygon
			(pts
				(xy 57.748424 -9.321546) (xy 57.545224 -9.321546) (xy 57.545224 -9.524746) (xy 57.748424 -9.524746)
			)
		)
		(polygon
			(pts
				(xy 58.06948 -8.940038) (xy 57.86628 -8.940038) (xy 57.86628 -9.143238) (xy 58.06948 -9.143238)
			)
		)
		(polygon
			(pts
				(xy 58.06948 -8.076438) (xy 57.86628 -8.076438) (xy 57.86628 -8.279638) (xy 58.06948 -8.279638)
			)
		)
	)
	(zone
		(layer "F.Cu")
		(hatch none 0.5)
		(connect_pads
			(clearance 0)
		)
		(min_thickness 0.25)
		(keepout
			(tracks allowed)
			(vias allowed)
			(pads allowed)
			(copperpour allowed)
			(footprints not_allowed)
		)
		(placement
			(enabled no)
			(sheetname "")
		)
		(fill
			(thermal_gap 0.5)
			(thermal_bridge_width 0.5)
			(island_removal_mode 0)
		)
		(polygon
			(pts
				(arc
					(start 142.750032 -3.50012)
					(mid 139.999974 -6.250178)
					(end 137.249916 -3.50012)
				)
				(arc
					(start 137.249916 -3.50012)
					(mid 139.999974 -0.750062)
					(end 142.750032 -3.50012)
				)
			)
		)
	)
	(zone
		(layer "F.Cu")
		(hatch none 0.5)
		(connect_pads
			(clearance 0)
		)
		(min_thickness 0.25)
		(keepout
			(tracks allowed)
			(vias allowed)
			(pads allowed)
			(copperpour allowed)
			(footprints not_allowed)
		)
		(placement
			(enabled no)
			(sheetname "")
		)
		(fill
			(thermal_gap 0.5)
			(thermal_bridge_width 0.5)
			(island_removal_mode 0)
		)
		(polygon
			(pts
				(arc
					(start 137.249916 -3.50012)
					(mid 139.999974 -0.750062)
					(end 142.750032 -3.50012)
				)
				(arc
					(start 142.750032 -3.50012)
					(mid 139.999974 -6.250178)
					(end 137.249916 -3.50012)
				)
			)
		)
	)
	(zone
		(layer "F.Cu")
		(hatch none 0.5)
		(connect_pads
			(clearance 0)
		)
		(min_thickness 0.25)
		(keepout
			(tracks allowed)
			(vias allowed)
			(pads allowed)
			(copperpour allowed)
			(footprints not_allowed)
		)
		(placement
			(enabled no)
			(sheetname "")
		)
		(fill
			(thermal_gap 0.5)
			(thermal_bridge_width 0.5)
			(island_removal_mode 0)
		)
		(polygon
			(pts
				(arc
					(start 137.249916 -61.699902)
					(mid 139.999974 -58.949844)
					(end 142.750032 -61.699902)
				)
				(arc
					(start 142.750032 -61.699902)
					(mid 139.999974 -64.44996)
					(end 137.249916 -61.699902)
				)
			)
		)
	)
	(zone
		(net "P5V_SW_L")
		(layer "F.Cu")
		(hatch none 0.5)
		(connect_pads
			(clearance 0.5)
		)
		(min_thickness 0.25)
		(fill yes
			(thermal_gap 0.5)
			(thermal_bridge_width 0.5)
			(island_removal_mode 0)
		)
		(polygon
			(pts
				(xy 45.110146 -13.42009) (xy 44.841922 -13.688314) (xy 44.841922 -15.098014) (xy 47.320454 -17.576546)
				(xy 47.320454 -19.380454) (xy 49.149 -21.209) (xy 50.29581 -21.209) (xy 50.29581 -17.497298) (xy 46.994826 -14.196314)
				(xy 46.994826 -13.683742) (xy 46.731174 -13.42009)
			)
		)
		(polygon
			(pts
				(xy 49.79162 -20.387056) (xy 49.58842 -20.387056) (xy 49.58842 -20.590256) (xy 49.79162 -20.590256)
			)
		)
		(polygon
			(pts
				(xy 48.3616 -19.3802) (xy 48.1584 -19.3802) (xy 48.1584 -19.5834) (xy 48.3616 -19.5834)
			)
		)
		(polygon
			(pts
				(xy 48.3616 -18.5166) (xy 48.1584 -18.5166) (xy 48.1584 -18.7198) (xy 48.3616 -18.7198)
			)
		)
	)
	(zone
		(layer "F.Cu")
		(hatch none 0.5)
		(connect_pads
			(clearance 0)
		)
		(min_thickness 0.25)
		(keepout
			(tracks allowed)
			(vias allowed)
			(pads allowed)
			(copperpour allowed)
			(footprints not_allowed)
		)
		(placement
			(enabled no)
			(sheetname "")
		)
		(fill
			(thermal_gap 0.5)
			(thermal_bridge_width 0.5)
			(island_removal_mode 0)
		)
		(polygon
			(pts
				(arc
					(start 2.350008 -4.020058)
					(mid 3.999992 -2.370074)
					(end 5.649976 -4.020058)
				)
				(arc
					(start 5.649976 -4.020058)
					(mid 3.999992 -5.670042)
					(end 2.350008 -4.020058)
				)
			)
		)
	)
	(zone
		(layer "F.Cu")
		(hatch none 0.5)
		(connect_pads
			(clearance 0)
		)
		(min_thickness 0.25)
		(keepout
			(tracks allowed)
			(vias allowed)
			(pads allowed)
			(copperpour allowed)
			(footprints not_allowed)
		)
		(placement
			(enabled no)
			(sheetname "")
		)
		(fill
			(thermal_gap 0.5)
			(thermal_bridge_width 0.5)
			(island_removal_mode 0)
		)
		(polygon
			(pts
				(arc
					(start 74.250042 -61.699902)
					(mid 77.0001 -58.949844)
					(end 79.749904 -61.699902)
				)
				(arc
					(start 79.749904 -61.699902)
					(mid 77.0001 -64.449706)
					(end 74.250042 -61.699902)
				)
			)
		)
	)
	(zone
		(layer "F.Cu")
		(hatch none 0.5)
		(connect_pads
			(clearance 0)
		)
		(min_thickness 0.25)
		(keepout
			(tracks not_allowed)
			(vias allowed)
			(pads allowed)
			(copperpour not_allowed)
			(footprints allowed)
		)
		(placement
			(enabled no)
			(sheetname "")
		)
		(fill
			(thermal_gap 0.5)
			(thermal_bridge_width 0.5)
			(island_removal_mode 0)
		)
		(polygon
			(pts
				(arc
					(start 125.24994 -21.79193)
					(mid 126.17796 -21.080978)
					(end 127.108966 -21.787866)
				)
				(arc
					(start 127.249428 -21.787866)
					(mid 126.177769 -20.943309)
					(end 125.109478 -21.79193)
				)
			)
		)
	)
	(zone
		(net "P5V_SW_R")
		(layer "F.Cu")
		(hatch none 0.5)
		(connect_pads
			(clearance 0.5)
		)
		(min_thickness 0.25)
		(fill yes
			(thermal_gap 0.5)
			(thermal_bridge_width 0.5)
			(island_removal_mode 0)
		)
		(polygon
			(pts
				(xy 122.591068 -49.727612) (xy 124.445522 -49.727612) (xy 127.59944 -46.57344) (xy 127.59944 -43.226482)
				(xy 127.018288 -42.64533) (xy 127.018288 -39.581836) (xy 123.825508 -36.389056) (xy 121.775728 -36.389056)
				(xy 120.889268 -35.502596) (xy 120.889268 -34.847276) (xy 120.655334 -34.613342) (xy 119.032274 -34.613342)
				(xy 118.767098 -34.878518) (xy 118.767098 -35.643312) (xy 121.44502 -38.321234) (xy 123.448826 -38.321234)
				(xy 125.118622 -39.99103) (xy 125.118622 -45.550836) (xy 123.19 -47.479458) (xy 119.742712 -47.479458)
				(xy 118.759478 -48.462692) (xy 118.759478 -56.545734) (xy 118.720362 -56.58485) (xy 118.720362 -57.416954)
				(xy 118.815104 -57.511696) (xy 120.005094 -57.511696) (xy 120.140476 -57.376314) (xy 120.140476 -56.4896)
				(xy 120.9294 -55.700676) (xy 120.9294 -51.38928)
			)
		)
		(polygon
			(pts
				(xy 119.82069 -56.429402) (xy 119.61749 -56.429402) (xy 119.61749 -56.632602) (xy 119.82069 -56.632602)
			)
		)
		(polygon
			(pts
				(xy 126.0856 -40.5384) (xy 125.8824 -40.5384) (xy 125.8824 -40.7416) (xy 126.0856 -40.7416)
			)
		)
		(polygon
			(pts
				(xy 126.0856 -39.6748) (xy 125.8824 -39.6748) (xy 125.8824 -39.878) (xy 126.0856 -39.878)
			)
		)
	)
	(zone
		(net "12V_PRE_1")
		(layer "F.Cu")
		(hatch none 0.5)
		(connect_pads
			(clearance 0.5)
		)
		(min_thickness 0.25)
		(fill yes
			(thermal_gap 0.5)
			(thermal_bridge_width 0.5)
			(island_removal_mode 0)
		)
		(polygon
			(pts
				(xy 125.341126 -34.636202) (xy 125.131068 -34.84626) (xy 125.131068 -35.92957) (xy 129.516378 -40.315134)
				(xy 129.516378 -40.61968) (xy 129.601976 -40.705278) (xy 130.333496 -40.705278) (xy 130.414522 -40.624252)
				(xy 130.414522 -39.714424) (xy 130.050032 -39.349934) (xy 130.047238 -39.349934) (xy 127.818896 -37.121592)
				(xy 127.780288 -37.121592) (xy 126.43231 -35.773614) (xy 126.416562 -35.773614) (xy 125.988064 -35.345116)
				(xy 125.988064 -34.916872) (xy 125.707394 -34.636202)
			)
		)
		(polygon
			(pts
				(xy 129.6416 -39.7256) (xy 129.4384 -39.7256) (xy 129.4384 -39.9288) (xy 129.6416 -39.9288)
			)
		)
	)
	(zone
		(net "P5V_SW_R")
		(layer "F.Cu")
		(hatch none 0.5)
		(connect_pads
			(clearance 0.5)
		)
		(min_thickness 0.25)
		(fill yes
			(thermal_gap 0.5)
			(thermal_bridge_width 0.5)
			(island_removal_mode 0)
		)
		(polygon
			(pts
				(xy 78.231492 -47.498508) (xy 77.851 -47.879) (xy 77.851 -53.467) (xy 77.978 -53.594) (xy 80.646524 -53.594)
				(xy 82.802476 -51.438048) (xy 82.802476 -50.16373) (xy 82.409538 -49.770792) (xy 82.409538 -48.562768)
				(xy 81.345278 -47.498508)
			)
		)
		(polygon
			(pts
				(xy 78.5876 -52.5272) (xy 78.3844 -52.5272) (xy 78.3844 -53.0098) (xy 78.5876 -53.0098)
			)
		)
		(polygon
			(pts
				(xy 78.5876 -51.9176) (xy 78.3844 -51.9176) (xy 78.3844 -52.1208) (xy 78.5876 -52.1208)
			)
		)
	)
	(zone
		(layer "F.Cu")
		(hatch none 0.5)
		(connect_pads
			(clearance 0)
		)
		(min_thickness 0.25)
		(keepout
			(tracks allowed)
			(vias allowed)
			(pads allowed)
			(copperpour allowed)
			(footprints not_allowed)
		)
		(placement
			(enabled no)
			(sheetname "")
		)
		(fill
			(thermal_gap 0.5)
			(thermal_bridge_width 0.5)
			(island_removal_mode 0)
		)
		(polygon
			(pts
				(arc
					(start 138.34999 -3.50012)
					(mid 139.999974 -1.850136)
					(end 141.649958 -3.50012)
				)
				(arc
					(start 141.649958 -3.50012)
					(mid 139.999974 -5.150104)
					(end 138.34999 -3.50012)
				)
			)
		)
	)
	(zone
		(net "GND")
		(layer "F.Cu")
		(hatch none 0.5)
		(connect_pads
			(clearance 0.5)
		)
		(min_thickness 0.25)
		(fill yes
			(thermal_gap 0.5)
			(thermal_bridge_width 0.5)
			(island_removal_mode 0)
		)
		(polygon
			(pts
				(arc
					(start 134.249414 -19.957288)
					(mid 134.219663 -19.85606)
					(end 134.123684 -19.812254)
				)
				(arc
					(start 121.236232 -19.812254)
					(mid 121.140266 -19.856071)
					(end 121.110502 -19.957288)
				)
				(arc
					(start 121.110502 -19.957288)
					(mid 120.811818 -20.786103)
					(end 119.958104 -21.003768)
				)
				(xy 119.661432 -21.003768) (xy 119.112284 -21.552916)
				(arc
					(start 119.112284 -23.999952)
					(mid 118.596132 -25.246052)
					(end 117.350032 -25.762204)
				)
				(xy 96.93656 -25.762204) (xy 96.93656 -25.762966)
				(arc
					(start 96.499934 -25.762966)
					(mid 95.253295 -25.246591)
					(end 94.73692 -23.999952)
				)
				(xy 94.73692 -7.750048) (xy 94.737682 -7.75081)
				(arc
					(start 94.737682 -0.999998)
					(mid 94.668048 -0.831888)
					(end 94.499938 -0.762254)
				)
				(xy 73.050146 -0.762254) (xy 72.815196 -0.997204) (xy 72.815196 -3.892804) (xy 74.97445 -6.052312)
				(xy 78.486 -6.052312) (xy 80.956912 -3.5814) (xy 82.931 -3.5814) (xy 83.654646 -4.305046) (xy 85.636608 -4.305046)
				(arc
					(start 85.64753 -4.315968)
					(mid 85.785751 -4.343381)
					(end 85.864192 -4.226306)
				)
				(xy 85.864192 -4.16306)
				(arc
					(start 85.849714 -4.145534)
					(mid 86.455562 -3.071387)
					(end 86.728808 -4.274058)
				)
				(arc
					(start 86.728808 -4.595368)
					(mid 86.831915 -4.733638)
					(end 86.868508 -4.9022)
				)
				(arc
					(start 86.868508 -5.2578)
					(mid 86.858151 -5.34902)
					(end 86.827614 -5.4356)
				)
				(xy 86.807802 -5.47624) (xy 87.13851 -5.806948) (xy 88.86698 -5.806948) (xy 89.326974 -5.346954)
				(xy 92.333826 -5.346954) (xy 93.467936 -6.481064)
				(arc
					(start 93.467936 -23.999952)
					(mid 93.718779 -25.20756)
					(end 94.429834 -26.21534)
				)
				(xy 99.350576 -31.136082) (xy 99.350576 -32.656018) (xy 100.373434 -33.678876) (xy 130.607562 -33.678876)
				(xy 132.184648 -35.255962)
				(arc
					(start 132.229606 -35.21583)
					(mid 134.275472 -35.26902)
					(end 134.328662 -37.314886)
				)
				(xy 134.28853 -37.359844) (xy 134.839964 -37.911278) (xy 134.839964 -53.86705) (xy 133.755638 -54.951376)
				(xy 131.056126 -54.951376) (xy 129.716276 -56.291226) (xy 129.716276 -57.343802) (xy 129.00533 -58.054748)
				(xy 124.565156 -58.054748) (xy 123.382024 -59.23788) (xy 117.895878 -59.23788) (xy 115.960906 -57.302908)
				(xy 115.960906 -54.380638) (xy 114.774472 -53.194204) (xy 95.709486 -53.194204) (xy 93.188282 -50.673)
				(xy 87.884 -50.673) (xy 87.122 -51.435) (xy 87.122 -51.43881) (xy 86.792308 -51.768756) (xy 86.792308 -52.069492)
				(xy 86.486492 -52.375308) (xy 86.185756 -52.375308) (xy 86.104984 -52.455826) (xy 82.48269 -52.455826)
				(xy 79.96936 -54.969156) (xy 77.978 -54.969156) (xy 77.597 -54.588156) (xy 77.597 -53.644546) (xy 77.545692 -53.593492)
				(xy 77.545692 -47.752508) (xy 77.597 -47.701454) (xy 77.597 -45.593) (xy 74.7776 -42.7736) (xy 74.7776 -42.239946)
				(xy 74.777092 -42.239692) (xy 74.777092 -42.214546) (xy 74.774298 -42.196258)
				(arc
					(start 74.77252 -42.190924)
					(mid 74.756954 -42.127755)
					(end 74.751692 -42.062908)
				)
				(arc
					(start 74.751692 -41.655492)
					(mid 74.757187 -41.589055)
					(end 74.773536 -41.524428)
				)
				(xy 74.777092 -41.514268) (xy 74.777092 -36.398708) (xy 74.7776 -36.398454) (xy 74.7776 -35.7124)
				(xy 74.355452 -35.290252) (xy 70.575678 -35.290252) (xy 70.263004 -35.602926) (xy 70.263004 -43.455082)
				(xy 70.262242 -43.455082)
				(arc
					(start 70.262242 -64.200024)
					(mid 70.331876 -64.368134)
					(end 70.499986 -64.437768)
				)
				(arc
					(start 142.500096 -64.437768)
					(mid 142.668206 -64.368134)
					(end 142.73784 -64.200024)
				)
				(arc
					(start 142.73784 -0.999998)
					(mid 142.668206 -0.831888)
					(end 142.500096 -0.762254)
				)
				(arc
					(start 136.500108 -0.762254)
					(mid 136.331998 -0.831888)
					(end 136.262364 -0.999998)
				)
				(arc
					(start 136.262364 -18.050002)
					(mid 136.146342 -18.678905)
					(end 135.813546 -19.225006)
				)
				(arc
					(start 135.813546 -19.225006)
					(mid 135.781171 -19.315412)
					(end 135.82142 -19.402552)
				)
				(arc
					(start 135.82142 -19.402552)
					(mid 135.492896 -20.976377)
					(end 134.249414 -19.957288)
				)
			)
		)
		(polygon
			(pts
				(xy 77.0636 -53.4162) (xy 76.8604 -53.4162) (xy 76.8604 -53.6194) (xy 77.0636 -53.6194)
			)
		)
		(polygon
			(pts
				(xy 77.0636 -52.5272) (xy 76.8604 -52.5272) (xy 76.8604 -53.0098) (xy 77.0636 -53.0098)
			)
		)
		(polygon
			(pts
				(xy 77.0636 -51.9176) (xy 76.8604 -51.9176) (xy 76.8604 -52.1208) (xy 77.0636 -52.1208)
			)
		)
		(polygon
			(pts
				(xy 74.2442 -42.0624) (xy 74.041 -42.0624) (xy 74.041 -42.2656) (xy 74.2442 -42.2656)
			)
		)
		(polygon
			(pts
				(xy 74.2442 -41.4528) (xy 74.041 -41.4528) (xy 74.041 -41.656) (xy 74.2442 -41.656)
			)
		)
	)
	(zone
		(layer "F.Cu")
		(hatch none 0.5)
		(connect_pads
			(clearance 0)
		)
		(min_thickness 0.25)
		(keepout
			(tracks allowed)
			(vias allowed)
			(pads allowed)
			(copperpour allowed)
			(footprints not_allowed)
		)
		(placement
			(enabled no)
			(sheetname "")
		)
		(fill
			(thermal_gap 0.5)
			(thermal_bridge_width 0.5)
			(island_removal_mode 0)
		)
		(polygon
			(pts
				(arc
					(start 142.750032 -61.699902)
					(mid 139.999974 -64.44996)
					(end 137.249916 -61.699902)
				)
				(arc
					(start 137.249916 -61.699902)
					(mid 139.999974 -58.949844)
					(end 142.750032 -61.699902)
				)
			)
		)
	)
	(zone
		(net "P3V3")
		(layer "F.Cu")
		(hatch none 0.5)
		(connect_pads
			(clearance 0.5)
		)
		(min_thickness 0.25)
		(fill yes
			(thermal_gap 0.5)
			(thermal_bridge_width 0.5)
			(island_removal_mode 0)
		)
		(polygon
			(pts
				(xy 83.82889 -8.186166) (xy 83.266788 -8.748268) (xy 81.088992 -8.748268) (xy 80.913224 -8.924036)
				(xy 80.913224 -11.077702) (xy 81.013554 -11.178032) (xy 82.675984 -11.178032) (xy 82.724752 -11.129264)
				(xy 82.724752 -10.352532) (xy 82.897726 -10.179558) (xy 83.170014 -9.90727) (xy 84.557362 -9.90727)
				(xy 84.768182 -9.69645) (xy 84.768182 -8.432038) (xy 84.52231 -8.186166)
			)
		)
		(polygon
			(pts
				(xy 81.317084 -10.472166) (xy 81.113884 -10.472166) (xy 81.113884 -10.675366) (xy 81.317084 -10.675366)
			)
		)
		(polygon
			(pts
				(xy 82.200242 -10.470896) (xy 81.997042 -10.470896) (xy 81.926684 -10.472166) (xy 81.723484 -10.472166)
				(xy 81.723484 -10.675366) (xy 81.926684 -10.675366) (xy 81.997042 -10.674096) (xy 82.200242 -10.674096)
			)
		)
		(polygon
			(pts
				(xy 81.90611 -9.1948) (xy 81.70291 -9.1948) (xy 81.70291 -9.398) (xy 81.90611 -9.398)
			)
		)
		(polygon
			(pts
				(xy 81.34731 -9.1948) (xy 81.14411 -9.1948) (xy 81.14411 -9.398) (xy 81.34731 -9.398)
			)
		)
		(polygon
			(pts
				(xy 82.969608 -9.19353) (xy 82.766408 -9.19353) (xy 82.766408 -9.39673) (xy 82.969608 -9.39673)
			)
		)
		(polygon
			(pts
				(xy 82.410808 -9.19353) (xy 82.207608 -9.19353) (xy 82.207608 -9.39673) (xy 82.410808 -9.39673)
			)
		)
	)
	(zone
		(layer "F.Cu")
		(hatch none 0.5)
		(connect_pads
			(clearance 0)
		)
		(min_thickness 0.25)
		(keepout
			(tracks not_allowed)
			(vias allowed)
			(pads allowed)
			(copperpour not_allowed)
			(footprints allowed)
		)
		(placement
			(enabled no)
			(sheetname "")
		)
		(fill
			(thermal_gap 0.5)
			(thermal_bridge_width 0.5)
			(island_removal_mode 0)
		)
		(polygon
			(pts
				(arc
					(start 98.00717 -51.53152)
					(mid 97.305782 -52.064252)
					(end 97.838514 -51.362864)
				)
				(xy 97.967038 -51.234086) (xy 97.967038 -51.06162)
				(arc
					(start 97.620074 -51.06162)
					(mid 96.931734 -51.74996)
					(end 97.620074 -52.4383)
				)
				(arc
					(start 98.890074 -52.4383)
					(mid 99.578414 -51.74996)
					(end 98.890074 -51.06162)
				)
				(xy 98.647758 -51.06162) (xy 98.647758 -51.338734)
				(arc
					(start 98.671634 -51.362864)
					(mid 99.204366 -52.064252)
					(end 98.502978 -51.53152)
				)
				(xy 98.478848 -51.507644) (xy 98.408998 -51.437794) (xy 98.408998 -51.338734) (xy 98.408998 -51.06162)
				(xy 98.205798 -51.06162) (xy 98.205798 -51.234086) (xy 98.205798 -51.333146) (xy 98.135948 -51.402996)
			)
		)
	)
	(zone
		(net "5V_PRE_0")
		(layer "F.Cu")
		(hatch none 0.5)
		(connect_pads
			(clearance 0.5)
		)
		(min_thickness 0.25)
		(fill yes
			(thermal_gap 0.5)
			(thermal_bridge_width 0.5)
			(island_removal_mode 0)
		)
		(polygon
			(pts
				(xy 117.729508 -51.349402) (xy 117.479826 -51.599084) (xy 117.479826 -51.856386) (xy 117.011704 -52.324508)
				(xy 117.011704 -57.3024) (xy 117.197124 -57.48782) (xy 118.176294 -57.48782) (xy 118.338092 -57.326022)
				(xy 118.338092 -51.583336) (xy 118.104158 -51.349402)
			)
		)
		(polygon
			(pts
				(xy 117.53469 -56.429402) (xy 117.33149 -56.429402) (xy 117.33149 -56.632602) (xy 117.53469 -56.632602)
			)
		)
	)
	(zone
		(net "P12V")
		(layer "F.Cu")
		(hatch none 0.5)
		(connect_pads
			(clearance 0.5)
		)
		(min_thickness 0.25)
		(fill yes
			(thermal_gap 0.5)
			(thermal_bridge_width 0.5)
			(island_removal_mode 0)
		)
		(polygon
			(pts
				(xy 82.897726 -38.721284) (xy 82.770726 -38.848284) (xy 82.770726 -39.567358) (xy 83.579208 -40.37584)
				(xy 83.579208 -43.258486) (xy 83.96224 -43.641518) (xy 87.124032 -43.641518) (xy 87.272876 -43.492674)
				(xy 87.272876 -38.984936) (xy 87.009224 -38.721284)
			)
		)
		(polygon
			(pts
				(xy 84.518754 -39.22776) (xy 84.315554 -39.22776) (xy 84.315554 -39.43096) (xy 84.518754 -39.43096)
			)
		)
		(polygon
			(pts
				(xy 83.909154 -39.22776) (xy 83.705954 -39.22776) (xy 83.705954 -39.43096) (xy 83.909154 -39.43096)
			)
		)
		(polygon
			(pts
				(xy 83.477354 -39.17696) (xy 83.274154 -39.17696) (xy 83.274154 -39.38016) (xy 83.477354 -39.38016)
			)
		)
	)
	(zone
		(layer "F.Cu")
		(hatch none 0.5)
		(connect_pads
			(clearance 0)
		)
		(min_thickness 0.25)
		(keepout
			(tracks not_allowed)
			(vias allowed)
			(pads allowed)
			(copperpour not_allowed)
			(footprints allowed)
		)
		(placement
			(enabled no)
			(sheetname "")
		)
		(fill
			(thermal_gap 0.5)
			(thermal_bridge_width 0.5)
			(island_removal_mode 0)
		)
		(polygon
			(pts
				(arc
					(start 98.00717 -34.831528)
					(mid 97.305782 -35.36426)
					(end 97.838514 -34.662872)
				)
				(xy 98.055938 -34.445194) (xy 98.055938 -34.361628)
				(arc
					(start 97.620074 -34.361628)
					(mid 96.931734 -35.049968)
					(end 97.620074 -35.738308)
				)
				(arc
					(start 98.890074 -35.738308)
					(mid 99.578414 -35.049968)
					(end 98.890074 -34.361628)
				)
				(xy 98.736658 -34.361628)
				(arc
					(start 98.736658 -34.6329)
					(mid 99.177972 -35.388489)
					(end 98.502978 -34.831528)
				)
				(xy 98.497898 -34.826702) (xy 98.497898 -34.727642) (xy 98.497898 -34.361628) (xy 98.294698 -34.361628)
				(xy 98.294698 -34.445194) (xy 98.294698 -34.544254) (xy 98.224848 -34.614104)
			)
		)
	)
	(zone
		(net "12V_PRE_3")
		(layer "F.Cu")
		(hatch none 0.5)
		(connect_pads
			(clearance 0.5)
		)
		(min_thickness 0.25)
		(fill yes
			(thermal_gap 0.5)
			(thermal_bridge_width 0.5)
			(island_removal_mode 0)
		)
		(polygon
			(pts
				(xy 51.45024 -2.130806) (xy 51.19751 -2.383536) (xy 51.19751 -2.596896) (xy 50.74539 -3.049016)
				(xy 50.74539 -3.768598) (xy 54.31028 -7.333488) (xy 54.767734 -7.333488) (xy 55.41137 -7.977124)
				(xy 55.41137 -8.706358) (xy 55.778146 -9.073134) (xy 56.44896 -9.073134) (xy 56.55818 -8.963914)
				(xy 56.55818 -7.477252) (xy 55.221378 -6.14045) (xy 54.947566 -6.14045) (xy 52.157884 -3.350768)
				(xy 52.157884 -2.875534) (xy 52.06746 -2.78511) (xy 52.06746 -2.390902) (xy 51.807364 -2.130806)
			)
		)
		(polygon
			(pts
				(xy 55.78348 -8.076438) (xy 55.58028 -8.076438) (xy 55.58028 -8.279638) (xy 55.78348 -8.279638)
			)
		)
	)
	(zone
		(layers "F.Cu" "B.Cu")
		(hatch none 0.5)
		(connect_pads
			(clearance 0)
		)
		(min_thickness 0.25)
		(keepout
			(tracks not_allowed)
			(vias allowed)
			(pads allowed)
			(copperpour not_allowed)
			(footprints allowed)
		)
		(placement
			(enabled no)
			(sheetname "")
		)
		(fill yes
			(thermal_gap 0.5)
			(thermal_bridge_width 0.5)
			(island_removal_mode 0)
		)
		(polygon
			(pts
				(arc
					(start 87.639652 -21.195538)
					(mid 87.129112 -20.684998)
					(end 86.618572 -21.195538)
				)
				(xy 86.618572 -21.363178) (xy 86.792562 -21.363178)
				(arc
					(start 86.876128 -21.279866)
					(mid 87.317675 -21.006975)
					(end 87.044784 -21.448522)
				)
				(xy 86.961472 -21.532088) (xy 86.891622 -21.601938) (xy 86.792562 -21.601938) (xy 86.618572 -21.601938)
				(xy 86.618572 -21.805138) (xy 86.792562 -21.805138) (xy 86.891622 -21.805138) (xy 86.961472 -21.874988)
				(arc
					(start 87.044784 -21.958554)
					(mid 87.317675 -22.400101)
					(end 86.876128 -22.12721)
				)
				(xy 86.792562 -22.043898) (xy 86.618572 -22.043898)
				(arc
					(start 86.618572 -22.211284)
					(mid 87.128985 -22.722078)
					(end 87.639652 -22.211538)
				)
			)
		)
	)
	(zone
		(layers "F.Cu" "B.Cu" "In1.Cu" "In2.Cu" "In3.Cu" "In4.Cu")
		(hatch none 0.5)
		(connect_pads
			(clearance 0)
		)
		(min_thickness 0.25)
		(keepout
			(tracks not_allowed)
			(vias allowed)
			(pads allowed)
			(copperpour not_allowed)
			(footprints allowed)
		)
		(placement
			(enabled no)
			(sheetname "")
		)
		(fill yes
			(thermal_gap 0.5)
			(thermal_bridge_width 0.5)
			(island_removal_mode 0)
		)
		(polygon
			(pts
				(arc
					(start 48.000158 -12.761976)
					(mid 48.892362 -12.392308)
					(end 49.26203 -11.500104)
				)
				(arc
					(start 49.26203 -10.999978)
					(mid 48.892436 -10.1077)
					(end 48.000158 -9.738106)
				)
				(arc
					(start 20.999958 -9.738106)
					(mid 20.10768 -10.1077)
					(end 19.738086 -10.999978)
				)
				(arc
					(start 19.738086 -11.500104)
					(mid 20.10768 -12.392382)
					(end 20.999958 -12.761976)
				)
			)
		)
	)
	(zone
		(layers "F.Cu" "B.Cu" "In1.Cu" "In2.Cu" "In3.Cu" "In4.Cu")
		(name "Package Keepin")
		(hatch none 0.5)
		(connect_pads
			(clearance 0)
		)
		(min_thickness 0.25)
		(keepout
			(tracks allowed)
			(vias allowed)
			(pads allowed)
			(copperpour allowed)
			(footprints allowed)
		)
		(placement
			(enabled no)
			(sheetname "")
		)
		(fill
			(thermal_gap 0.5)
			(thermal_bridge_width 0.5)
			(island_removal_mode 0)
		)
		(polygon
			(pts
				(xy 2.54 -20.660106)
				(arc
					(start 49.00041 -20.660106)
					(mid 50.510016 -21.061725)
					(end 51.620928 -22.159976)
				)
				(arc
					(start 68.49999 -22.159976)
					(mid 71.003147 -23.196817)
					(end 72.039988 -25.699974)
				)
				(xy 72.039988 -62.660022) (xy 140.960094 -62.660022) (xy 140.960094 -2.54) (xy 138.04011 -2.54)
				(arc
					(start 138.04011 -18.050002)
					(mid 137.003269 -20.553159)
					(end 134.500112 -21.59)
				)
				(xy 120.89003 -21.59)
				(arc
					(start 120.89003 -23.999952)
					(mid 119.853189 -26.503109)
					(end 117.350032 -27.53995)
				)
				(arc
					(start 96.499934 -27.53995)
					(mid 93.996777 -26.503109)
					(end 92.959936 -23.999952)
				)
				(xy 92.959936 -2.54) (xy 2.54 -2.54)
			)
		)
	)
	(zone
		(layers "F.Cu" "B.Cu" "In1.Cu" "In2.Cu" "In3.Cu" "In4.Cu")
		(name "Route Keepin")
		(hatch none 0.5)
		(connect_pads
			(clearance 0)
		)
		(min_thickness 0.25)
		(keepout
			(tracks allowed)
			(vias allowed)
			(pads allowed)
			(copperpour allowed)
			(footprints allowed)
		)
		(placement
			(enabled no)
			(sheetname "")
		)
		(fill
			(thermal_gap 0.5)
			(thermal_bridge_width 0.5)
			(island_removal_mode 0)
		)
		(polygon
			(pts
				(arc
					(start 0.762 -22.200108)
					(mid 0.831708 -22.368398)
					(end 0.999998 -22.438106)
				)
				(arc
					(start 49.000156 -22.438106)
					(mid 49.892524 -22.807684)
					(end 50.262028 -23.699978)
				)
				(xy 50.262028 -23.937976)
				(arc
					(start 68.49999 -23.937976)
					(mid 69.745911 -24.454053)
					(end 70.261988 -25.699974)
				)
				(arc
					(start 70.261988 -64.200024)
					(mid 70.331696 -64.368314)
					(end 70.499986 -64.438022)
				)
				(arc
					(start 142.500096 -64.438022)
					(mid 142.668386 -64.368314)
					(end 142.738094 -64.200024)
				)
				(arc
					(start 142.738094 -0.999998)
					(mid 142.668386 -0.831708)
					(end 142.500096 -0.762)
				)
				(arc
					(start 136.500108 -0.762)
					(mid 136.331818 -0.831708)
					(end 136.26211 -0.999998)
				)
				(arc
					(start 136.26211 -18.050002)
					(mid 135.746033 -19.295923)
					(end 134.500112 -19.812)
				)
				(arc
					(start 119.350028 -19.812)
					(mid 119.181738 -19.881708)
					(end 119.11203 -20.049998)
				)
				(arc
					(start 119.11203 -23.999952)
					(mid 118.595953 -25.245873)
					(end 117.350032 -25.76195)
				)
				(arc
					(start 96.499934 -25.76195)
					(mid 95.254013 -25.245873)
					(end 94.737936 -23.999952)
				)
				(arc
					(start 94.737936 -0.999998)
					(mid 94.668228 -0.831708)
					(end 94.499938 -0.762)
				)
				(arc
					(start 0.999998 -0.762)
					(mid 0.831708 -0.831708)
					(end 0.762 -0.999998)
				)
			)
		)
	)
	(zone
		(layers "F.Cu" "B.Cu" "In2.Cu")
		(hatch none 0.5)
		(connect_pads
			(clearance 0)
		)
		(min_thickness 0.25)
		(keepout
			(tracks not_allowed)
			(vias allowed)
			(pads allowed)
			(copperpour not_allowed)
			(footprints allowed)
		)
		(placement
			(enabled no)
			(sheetname "")
		)
		(fill yes
			(thermal_gap 0.5)
			(thermal_bridge_width 0.5)
			(island_removal_mode 0)
		)
		(polygon
			(pts
				(arc
					(start 132.43814 -21.1201)
					(mid 133.149092 -22.04812)
					(end 132.442204 -22.979126)
				)
				(arc
					(start 132.442204 -23.119588)
					(mid 133.286761 -22.047929)
					(end 132.43814 -20.979638)
				)
			)
		)
	)
	(zone
		(layers "F.Cu" "B.Cu" "In2.Cu")
		(hatch none 0.5)
		(connect_pads
			(clearance 0)
		)
		(min_thickness 0.25)
		(keepout
			(tracks not_allowed)
			(vias allowed)
			(pads allowed)
			(copperpour not_allowed)
			(footprints allowed)
		)
		(placement
			(enabled no)
			(sheetname "")
		)
		(fill yes
			(thermal_gap 0.5)
			(thermal_bridge_width 0.5)
			(island_removal_mode 0)
		)
		(polygon
			(pts
				(arc
					(start 131.922012 -22.979888)
					(mid 131.21106 -22.051868)
					(end 131.917948 -21.120862)
				)
				(arc
					(start 131.917948 -20.9804)
					(mid 131.073391 -22.052059)
					(end 131.922012 -23.12035)
				)
			)
		)
	)
	(zone
		(layers "F.Cu" "B.Cu" "In2.Cu" "In3.Cu")
		(hatch none 0.5)
		(connect_pads
			(clearance 0)
		)
		(min_thickness 0.25)
		(keepout
			(tracks not_allowed)
			(vias allowed)
			(pads allowed)
			(copperpour not_allowed)
			(footprints allowed)
		)
		(placement
			(enabled no)
			(sheetname "")
		)
		(fill yes
			(thermal_gap 0.5)
			(thermal_bridge_width 0.5)
			(island_removal_mode 0)
		)
		(polygon
			(pts
				(arc
					(start 126.437898 -21.1201)
					(mid 127.14885 -22.04812)
					(end 126.441962 -22.979126)
				)
				(arc
					(start 126.441962 -23.119588)
					(mid 127.286519 -22.047929)
					(end 126.437898 -20.979638)
				)
			)
		)
	)
	(zone
		(layers "F.Cu" "B.Cu" "In2.Cu" "In3.Cu")
		(hatch none 0.5)
		(connect_pads
			(clearance 0)
		)
		(min_thickness 0.25)
		(keepout
			(tracks not_allowed)
			(vias allowed)
			(pads allowed)
			(copperpour not_allowed)
			(footprints allowed)
		)
		(placement
			(enabled no)
			(sheetname "")
		)
		(fill yes
			(thermal_gap 0.5)
			(thermal_bridge_width 0.5)
			(island_removal_mode 0)
		)
		(polygon
			(pts
				(arc
					(start 95.999554 -40.682164)
					(mid 94.891914 -41.141121)
					(end 94.433136 -42.248836)
				)
				(arc
					(start 94.433136 -45.748956)
					(mid 94.892078 -46.856686)
					(end 95.999808 -47.315628)
				)
				(arc
					(start 123.000008 -47.315628)
					(mid 124.107812 -46.85676)
					(end 124.56668 -45.748956)
				)
				(arc
					(start 124.56668 -42.248836)
					(mid 124.107812 -41.141032)
					(end 123.000008 -40.682164)
				)
			)
		)
	)
	(zone
		(layers "F.Cu" "B.Cu" "In2.Cu" "In3.Cu")
		(hatch none 0.5)
		(connect_pads
			(clearance 0)
		)
		(min_thickness 0.25)
		(keepout
			(tracks not_allowed)
			(vias allowed)
			(pads allowed)
			(copperpour not_allowed)
			(footprints allowed)
		)
		(placement
			(enabled no)
			(sheetname "")
		)
		(fill yes
			(thermal_gap 0.5)
			(thermal_bridge_width 0.5)
			(island_removal_mode 0)
		)
		(polygon
			(pts
				(arc
					(start 128.922018 -22.979888)
					(mid 128.211066 -22.051868)
					(end 128.917954 -21.120862)
				)
				(arc
					(start 128.917954 -20.9804)
					(mid 128.073397 -22.052059)
					(end 128.922018 -23.12035)
				)
			)
		)
	)
	(zone
		(layers "F.Cu" "B.Cu" "In2.Cu" "In3.Cu")
		(hatch none 0.5)
		(connect_pads
			(clearance 0)
		)
		(min_thickness 0.25)
		(keepout
			(tracks not_allowed)
			(vias allowed)
			(pads allowed)
			(copperpour not_allowed)
			(footprints allowed)
		)
		(placement
			(enabled no)
			(sheetname "")
		)
		(fill yes
			(thermal_gap 0.5)
			(thermal_bridge_width 0.5)
			(island_removal_mode 0)
		)
		(polygon
			(pts
				(arc
					(start 125.92177 -22.979888)
					(mid 125.210818 -22.051868)
					(end 125.917706 -21.120862)
				)
				(arc
					(start 125.917706 -20.9804)
					(mid 125.073149 -22.052059)
					(end 125.92177 -23.12035)
				)
			)
		)
	)
	(zone
		(layers "F.Cu" "B.Cu" "In2.Cu" "In3.Cu")
		(hatch none 0.5)
		(connect_pads
			(clearance 0)
		)
		(min_thickness 0.25)
		(keepout
			(tracks not_allowed)
			(vias allowed)
			(pads allowed)
			(copperpour not_allowed)
			(footprints allowed)
		)
		(placement
			(enabled no)
			(sheetname "")
		)
		(fill yes
			(thermal_gap 0.5)
			(thermal_bridge_width 0.5)
			(island_removal_mode 0)
		)
		(polygon
			(pts
				(arc
					(start 129.438146 -21.1201)
					(mid 130.149098 -22.04812)
					(end 129.44221 -22.979126)
				)
				(arc
					(start 129.44221 -23.119588)
					(mid 130.286767 -22.047929)
					(end 129.438146 -20.979638)
				)
			)
		)
	)
	(zone
		(layers "F.Cu" "B.Cu" "In3.Cu")
		(hatch none 0.5)
		(connect_pads
			(clearance 0)
		)
		(min_thickness 0.25)
		(keepout
			(tracks not_allowed)
			(vias allowed)
			(pads allowed)
			(copperpour not_allowed)
			(footprints allowed)
		)
		(placement
			(enabled no)
			(sheetname "")
		)
		(fill yes
			(thermal_gap 0.5)
			(thermal_bridge_width 0.5)
			(island_removal_mode 0)
		)
		(polygon
			(pts
				(arc
					(start 122.921776 -22.979888)
					(mid 122.210824 -22.051868)
					(end 122.917712 -21.120862)
				)
				(arc
					(start 122.917712 -20.9804)
					(mid 122.073155 -22.052059)
					(end 122.921776 -23.12035)
				)
			)
		)
	)
	(zone
		(layers "F.Cu" "B.Cu" "In3.Cu")
		(hatch none 0.5)
		(connect_pads
			(clearance 0)
		)
		(min_thickness 0.25)
		(keepout
			(tracks not_allowed)
			(vias allowed)
			(pads allowed)
			(copperpour not_allowed)
			(footprints allowed)
		)
		(placement
			(enabled no)
			(sheetname "")
		)
		(fill yes
			(thermal_gap 0.5)
			(thermal_bridge_width 0.5)
			(island_removal_mode 0)
		)
		(polygon
			(pts
				(arc
					(start 23.694898 -1.861566)
					(mid 23.006558 -2.549906)
					(end 23.694898 -3.238246)
				)
				(arc
					(start 24.964898 -3.238246)
					(mid 25.450729 -3.037533)
					(end 25.653238 -2.552446)
				)
				(arc
					(start 25.409398 -2.552446)
					(mid 24.964898 -2.994413)
					(end 24.520398 -2.552446)
				)
				(arc
					(start 24.139398 -2.552446)
					(mid 23.694898 -2.994413)
					(end 23.250398 -2.552446)
				)
				(arc
					(start 23.250398 -2.549906)
					(mid 23.694898 -2.105406)
					(end 24.139398 -2.549906)
				)
				(arc
					(start 24.520398 -2.549906)
					(mid 24.964898 -2.105406)
					(end 25.409398 -2.549906)
				)
				(arc
					(start 25.653238 -2.549906)
					(mid 25.451628 -2.063176)
					(end 24.964898 -1.861566)
				)
			)
		)
	)
	(zone
		(layers "F.Cu" "B.Cu" "In3.Cu")
		(hatch none 0.5)
		(connect_pads
			(clearance 0)
		)
		(min_thickness 0.25)
		(keepout
			(tracks not_allowed)
			(vias allowed)
			(pads allowed)
			(copperpour not_allowed)
			(footprints allowed)
		)
		(placement
			(enabled no)
			(sheetname "")
		)
		(fill yes
			(thermal_gap 0.5)
			(thermal_bridge_width 0.5)
			(island_removal_mode 0)
		)
		(polygon
			(pts
				(arc
					(start 123.437904 -21.1201)
					(mid 124.148856 -22.04812)
					(end 123.441968 -22.979126)
				)
				(arc
					(start 123.441968 -23.119588)
					(mid 124.286525 -22.047929)
					(end 123.437904 -20.979638)
				)
			)
		)
	)
	(zone
		(layers "F.Cu" "B.Cu" "In3.Cu")
		(hatch none 0.5)
		(connect_pads
			(clearance 0)
		)
		(min_thickness 0.25)
		(keepout
			(tracks not_allowed)
			(vias allowed)
			(pads allowed)
			(copperpour not_allowed)
			(footprints allowed)
		)
		(placement
			(enabled no)
			(sheetname "")
		)
		(fill yes
			(thermal_gap 0.5)
			(thermal_bridge_width 0.5)
			(island_removal_mode 0)
		)
		(polygon
			(pts
				(arc
					(start 23.694898 -13.161772)
					(mid 23.006558 -13.850112)
					(end 23.694898 -14.538452)
				)
				(arc
					(start 24.964898 -14.538452)
					(mid 25.450729 -14.337739)
					(end 25.653238 -13.852652)
				)
				(arc
					(start 25.409398 -13.852652)
					(mid 24.964898 -14.294619)
					(end 24.520398 -13.852652)
				)
				(arc
					(start 24.139398 -13.852652)
					(mid 23.694898 -14.294619)
					(end 23.250398 -13.852652)
				)
				(arc
					(start 23.250398 -13.850112)
					(mid 23.694898 -13.405612)
					(end 24.139398 -13.850112)
				)
				(arc
					(start 24.520398 -13.850112)
					(mid 24.964898 -13.405612)
					(end 25.409398 -13.850112)
				)
				(arc
					(start 25.653238 -13.850112)
					(mid 25.451628 -13.363382)
					(end 24.964898 -13.161772)
				)
			)
		)
	)
	(zone
		(layers "F.Cu" "In2.Cu" "In3.Cu")
		(hatch none 0.5)
		(connect_pads
			(clearance 0)
		)
		(min_thickness 0.25)
		(keepout
			(tracks not_allowed)
			(vias allowed)
			(pads allowed)
			(copperpour not_allowed)
			(footprints allowed)
		)
		(placement
			(enabled no)
			(sheetname "")
		)
		(fill yes
			(thermal_gap 0.5)
			(thermal_bridge_width 0.5)
			(island_removal_mode 0)
		)
		(polygon
			(pts
				(arc
					(start 101.430074 -34.361628)
					(mid 100.741734 -35.049968)
					(end 101.430074 -35.738308)
				)
				(arc
					(start 102.700074 -35.738308)
					(mid 103.185905 -35.537595)
					(end 103.388414 -35.052508)
				)
				(arc
					(start 103.144574 -35.052508)
					(mid 102.700074 -35.494475)
					(end 102.255574 -35.052508)
				)
				(arc
					(start 101.874574 -35.052508)
					(mid 101.430074 -35.494475)
					(end 100.985574 -35.052508)
				)
				(arc
					(start 100.985574 -35.049968)
					(mid 101.430074 -34.605468)
					(end 101.874574 -35.049968)
				)
				(arc
					(start 102.255574 -35.049968)
					(mid 102.700074 -34.605468)
					(end 103.144574 -35.049968)
				)
				(arc
					(start 103.388414 -35.049968)
					(mid 103.186804 -34.563238)
					(end 102.700074 -34.361628)
				)
			)
		)
	)
	(zone
		(layers "F.Cu" "In2.Cu" "In3.Cu")
		(hatch none 0.5)
		(connect_pads
			(clearance 0)
		)
		(min_thickness 0.25)
		(keepout
			(tracks not_allowed)
			(vias allowed)
			(pads allowed)
			(copperpour not_allowed)
			(footprints allowed)
		)
		(placement
			(enabled no)
			(sheetname "")
		)
		(fill yes
			(thermal_gap 0.5)
			(thermal_bridge_width 0.5)
			(island_removal_mode 0)
		)
		(polygon
			(pts
				(arc
					(start 27.504898 -1.861566)
					(mid 26.816558 -2.549906)
					(end 27.504898 -3.238246)
				)
				(arc
					(start 28.774898 -3.238246)
					(mid 29.260729 -3.037533)
					(end 29.463238 -2.552446)
				)
				(arc
					(start 29.219398 -2.552446)
					(mid 28.774898 -2.994413)
					(end 28.330398 -2.552446)
				)
				(arc
					(start 27.949398 -2.552446)
					(mid 27.504898 -2.994413)
					(end 27.060398 -2.552446)
				)
				(arc
					(start 27.060398 -2.549906)
					(mid 27.504898 -2.105406)
					(end 27.949398 -2.549906)
				)
				(arc
					(start 28.330398 -2.549906)
					(mid 28.774898 -2.105406)
					(end 29.219398 -2.549906)
				)
				(arc
					(start 29.463238 -2.549906)
					(mid 29.261628 -2.063176)
					(end 28.774898 -1.861566)
				)
			)
		)
	)
	(zone
		(layers "F.Cu" "In2.Cu" "In3.Cu")
		(hatch none 0.5)
		(connect_pads
			(clearance 0)
		)
		(min_thickness 0.25)
		(keepout
			(tracks not_allowed)
			(vias allowed)
			(pads allowed)
			(copperpour not_allowed)
			(footprints allowed)
		)
		(placement
			(enabled no)
			(sheetname "")
		)
		(fill yes
			(thermal_gap 0.5)
			(thermal_bridge_width 0.5)
			(island_removal_mode 0)
		)
		(polygon
			(pts
				(arc
					(start 101.430074 -51.06162)
					(mid 100.741734 -51.74996)
					(end 101.430074 -52.4383)
				)
				(arc
					(start 102.700074 -52.4383)
					(mid 103.185905 -52.237587)
					(end 103.388414 -51.7525)
				)
				(arc
					(start 103.144574 -51.7525)
					(mid 102.700074 -52.194467)
					(end 102.255574 -51.7525)
				)
				(arc
					(start 101.874574 -51.7525)
					(mid 101.430074 -52.194467)
					(end 100.985574 -51.7525)
				)
				(arc
					(start 100.985574 -51.74996)
					(mid 101.430074 -51.30546)
					(end 101.874574 -51.74996)
				)
				(arc
					(start 102.255574 -51.74996)
					(mid 102.700074 -51.30546)
					(end 103.144574 -51.74996)
				)
				(arc
					(start 103.388414 -51.74996)
					(mid 103.186804 -51.26323)
					(end 102.700074 -51.06162)
				)
			)
		)
	)
	(zone
		(layers "F.Cu" "In2.Cu" "In3.Cu")
		(hatch none 0.5)
		(connect_pads
			(clearance 0)
		)
		(min_thickness 0.25)
		(keepout
			(tracks not_allowed)
			(vias allowed)
			(pads allowed)
			(copperpour not_allowed)
			(footprints allowed)
		)
		(placement
			(enabled no)
			(sheetname "")
		)
		(fill yes
			(thermal_gap 0.5)
			(thermal_bridge_width 0.5)
			(island_removal_mode 0)
		)
		(polygon
			(pts
				(arc
					(start 27.504898 -13.161772)
					(mid 26.816558 -13.850112)
					(end 27.504898 -14.538452)
				)
				(arc
					(start 28.774898 -14.538452)
					(mid 29.260729 -14.337739)
					(end 29.463238 -13.852652)
				)
				(arc
					(start 29.219398 -13.852652)
					(mid 28.774898 -14.294619)
					(end 28.330398 -13.852652)
				)
				(arc
					(start 27.949398 -13.852652)
					(mid 27.504898 -14.294619)
					(end 27.060398 -13.852652)
				)
				(arc
					(start 27.060398 -13.850112)
					(mid 27.504898 -13.405612)
					(end 27.949398 -13.850112)
				)
				(arc
					(start 28.330398 -13.850112)
					(mid 28.774898 -13.405612)
					(end 29.219398 -13.850112)
				)
				(arc
					(start 29.463238 -13.850112)
					(mid 29.261628 -13.363382)
					(end 28.774898 -13.161772)
				)
			)
		)
	)
	(zone
		(layers "F.Cu" "In3.Cu")
		(hatch none 0.5)
		(connect_pads
			(clearance 0)
		)
		(min_thickness 0.25)
		(keepout
			(tracks not_allowed)
			(vias allowed)
			(pads allowed)
			(copperpour not_allowed)
			(footprints allowed)
		)
		(placement
			(enabled no)
			(sheetname "")
		)
		(fill yes
			(thermal_gap 0.5)
			(thermal_bridge_width 0.5)
			(island_removal_mode 0)
		)
		(polygon
			(pts
				(arc
					(start 87.092536 -23.446994)
					(mid 86.581996 -22.936454)
					(end 86.071456 -23.446994)
				)
				(arc
					(start 86.071456 -24.46274)
					(mid 86.580599 -24.973532)
					(end 87.092536 -24.465534)
				)
				(arc
					(start 86.848696 -24.465534)
					(mid 86.581996 -24.729706)
					(end 86.315296 -24.465534)
				)
				(arc
					(start 86.315296 -24.462994)
					(mid 86.581996 -24.196294)
					(end 86.848696 -24.462994)
				)
				(xy 87.092536 -24.462994) (xy 87.092536 -23.449534)
				(arc
					(start 86.848696 -23.449534)
					(mid 86.581996 -23.713706)
					(end 86.315296 -23.449534)
				)
				(arc
					(start 86.315296 -23.446994)
					(mid 86.581996 -23.180294)
					(end 86.848696 -23.446994)
				)
			)
		)
	)
	(zone
		(layers "F.Cu" "In3.Cu")
		(hatch none 0.5)
		(connect_pads
			(clearance 0)
		)
		(min_thickness 0.25)
		(keepout
			(tracks not_allowed)
			(vias allowed)
			(pads allowed)
			(copperpour not_allowed)
			(footprints allowed)
		)
		(placement
			(enabled no)
			(sheetname "")
		)
		(fill yes
			(thermal_gap 0.5)
			(thermal_bridge_width 0.5)
			(island_removal_mode 0)
		)
		(polygon
			(pts
				(arc
					(start 82.65287 -25.19807)
					(mid 82.142076 -25.708483)
					(end 82.652616 -26.21915)
				)
				(arc
					(start 83.668616 -26.21915)
					(mid 84.028723 -26.070513)
					(end 84.179156 -25.71115)
				)
				(arc
					(start 83.935316 -25.71115)
					(mid 83.668616 -25.975322)
					(end 83.401916 -25.71115)
				)
				(arc
					(start 82.919316 -25.71115)
					(mid 82.652616 -25.975322)
					(end 82.385916 -25.71115)
				)
				(arc
					(start 82.385916 -25.70861)
					(mid 82.652616 -25.44191)
					(end 82.919316 -25.70861)
				)
				(arc
					(start 83.401916 -25.70861)
					(mid 83.668616 -25.44191)
					(end 83.935316 -25.70861)
				)
				(arc
					(start 84.179156 -25.70861)
					(mid 84.029622 -25.347604)
					(end 83.668616 -25.19807)
				)
			)
		)
	)
	(zone
		(layer "B.Cu")
		(hatch none 0.5)
		(connect_pads
			(clearance 0)
		)
		(min_thickness 0.25)
		(keepout
			(tracks not_allowed)
			(vias allowed)
			(pads allowed)
			(copperpour not_allowed)
			(footprints allowed)
		)
		(placement
			(enabled no)
			(sheetname "")
		)
		(fill
			(thermal_gap 0.5)
			(thermal_bridge_width 0.5)
			(island_removal_mode 0)
		)
		(polygon
			(pts
				(arc
					(start 83.597496 -21.166836)
					(mid 83.086956 -20.656296)
					(end 82.576416 -21.166836)
				)
				(xy 82.576416 -21.334476) (xy 82.750406 -21.334476)
				(arc
					(start 82.833972 -21.251164)
					(mid 83.275519 -20.978273)
					(end 83.002628 -21.41982)
				)
				(xy 82.919316 -21.503386) (xy 82.849466 -21.573236) (xy 82.750406 -21.573236) (xy 82.576416 -21.573236)
				(xy 82.576416 -21.776436) (xy 82.750406 -21.776436) (xy 82.849466 -21.776436) (xy 82.919316 -21.846286)
				(arc
					(start 83.002628 -21.929852)
					(mid 83.275519 -22.371399)
					(end 82.833972 -22.098508)
				)
				(xy 82.750406 -22.015196) (xy 82.576416 -22.015196)
				(arc
					(start 82.576416 -22.182582)
					(mid 83.086829 -22.693376)
					(end 83.597496 -22.182836)
				)
			)
		)
	)
	(zone
		(layer "B.Cu")
		(hatch none 0.5)
		(connect_pads
			(clearance 0)
		)
		(min_thickness 0.25)
		(keepout
			(tracks not_allowed)
			(vias allowed)
			(pads allowed)
			(copperpour not_allowed)
			(footprints allowed)
		)
		(placement
			(enabled no)
			(sheetname "")
		)
		(fill
			(thermal_gap 0.5)
			(thermal_bridge_width 0.5)
			(island_removal_mode 0)
		)
		(polygon
			(pts
				(arc
					(start 28.387802 -14.068552)
					(mid 29.08919 -13.53582)
					(end 28.556458 -14.237208)
				)
				(xy 28.480258 -14.313662) (xy 28.480258 -14.538452)
				(arc
					(start 28.774898 -14.538452)
					(mid 29.463238 -13.850112)
					(end 28.774898 -13.161772)
				)
				(arc
					(start 27.504898 -13.161772)
					(mid 26.816558 -13.850112)
					(end 27.504898 -14.538452)
				)
				(xy 27.799538 -14.538452) (xy 27.799538 -14.313662)
				(arc
					(start 27.723338 -14.237208)
					(mid 27.190606 -13.53582)
					(end 27.891994 -14.068552)
				)
				(xy 27.968448 -14.144752) (xy 28.038298 -14.214602) (xy 28.038298 -14.313662) (xy 28.038298 -14.538452)
				(xy 28.241498 -14.538452) (xy 28.241498 -14.313662) (xy 28.241498 -14.214602) (xy 28.311348 -14.144752)
			)
		)
	)
	(zone
		(layer "B.Cu")
		(hatch none 0.5)
		(connect_pads
			(clearance 0)
		)
		(min_thickness 0.25)
		(keepout
			(tracks allowed)
			(vias allowed)
			(pads allowed)
			(copperpour allowed)
			(footprints not_allowed)
		)
		(placement
			(enabled no)
			(sheetname "")
		)
		(fill
			(thermal_gap 0.5)
			(thermal_bridge_width 0.5)
			(island_removal_mode 0)
		)
		(polygon
			(pts
				(arc
					(start 80.000094 -3.50012)
					(mid 77.0001 -0.500126)
					(end 74.000106 -3.50012)
				)
				(arc
					(start 74.000106 -3.50012)
					(mid 77.0001 -6.500114)
					(end 80.000094 -3.50012)
				)
			)
		)
	)
	(zone
		(layer "B.Cu")
		(hatch none 0.5)
		(connect_pads
			(clearance 0)
		)
		(min_thickness 0.25)
		(keepout
			(tracks allowed)
			(vias allowed)
			(pads allowed)
			(copperpour allowed)
			(footprints not_allowed)
		)
		(placement
			(enabled no)
			(sheetname "")
		)
		(fill
			(thermal_gap 0.5)
			(thermal_bridge_width 0.5)
			(island_removal_mode 0)
		)
		(polygon
			(pts
				(arc
					(start 0.999998 -17.020032)
					(mid 3.999992 -20.020026)
					(end 6.999986 -17.020032)
				)
				(arc
					(start 6.999986 -17.020032)
					(mid 3.999992 -14.020038)
					(end 0.999998 -17.020032)
				)
			)
		)
	)
	(zone
		(net "GND")
		(layer "B.Cu")
		(hatch none 0.5)
		(connect_pads
			(clearance 0.5)
		)
		(min_thickness 0.25)
		(fill yes
			(thermal_gap 0.5)
			(thermal_bridge_width 0.5)
			(island_removal_mode 0)
		)
		(polygon
			(pts
				(arc
					(start 0.999998 -0.762254)
					(mid 0.831888 -0.831888)
					(end 0.762254 -0.999998)
				)
				(arc
					(start 0.762254 -22.200108)
					(mid 0.831888 -22.368218)
					(end 0.999998 -22.437852)
				)
				(xy 12.275312 -22.437852) (xy 12.276582 -22.436582) (xy 16.387064 -22.436582) (xy 16.388334 -22.437852)
				(xy 48.689006 -22.437852) (xy 48.689006 -21.888196) (xy 47.747174 -20.946364) (xy 17.976342 -20.946364)
				(xy 17.97431 -20.944332) (xy 17.086072 -20.944332) (xy 17.084802 -20.945602) (xy 16.570198 -20.945602)
				(xy 15.517114 -21.998686) (xy 12.968986 -21.998686) (xy 12.567666 -21.597366) (xy 12.567666 -15.769082)
				(xy 12.723622 -15.613126) (xy 14.795754 -15.613126) (xy 14.89075 -15.51813) (xy 14.89075 -13.135356)
				(xy 14.7701 -13.014706) (xy 12.708128 -13.014706) (xy 12.47902 -12.785598) (xy 12.47902 -8.8265)
				(xy 12.663932 -8.641588) (xy 14.740382 -8.641588) (xy 14.951202 -8.430768) (xy 14.951202 -1.133602)
				(xy 14.579854 -0.762254)
			)
		)
	)
	(zone
		(layer "B.Cu")
		(hatch none 0.5)
		(connect_pads
			(clearance 0)
		)
		(min_thickness 0.25)
		(keepout
			(tracks allowed)
			(vias allowed)
			(pads allowed)
			(copperpour allowed)
			(footprints not_allowed)
		)
		(placement
			(enabled no)
			(sheetname "")
		)
		(fill
			(thermal_gap 0.5)
			(thermal_bridge_width 0.5)
			(island_removal_mode 0)
		)
		(polygon
			(pts
				(arc
					(start 142.999968 -3.50012)
					(mid 139.999974 -0.500126)
					(end 136.99998 -3.50012)
				)
				(arc
					(start 136.99998 -3.50012)
					(mid 139.999974 -6.500114)
					(end 142.999968 -3.50012)
				)
			)
		)
	)
	(zone
		(layer "B.Cu")
		(hatch none 0.5)
		(connect_pads
			(clearance 0)
		)
		(min_thickness 0.25)
		(keepout
			(tracks allowed)
			(vias allowed)
			(pads allowed)
			(copperpour allowed)
			(footprints not_allowed)
		)
		(placement
			(enabled no)
			(sheetname "")
		)
		(fill
			(thermal_gap 0.5)
			(thermal_bridge_width 0.5)
			(island_removal_mode 0)
		)
		(polygon
			(pts
				(arc
					(start 75.350116 -3.50012)
					(mid 77.0001 -5.150104)
					(end 78.650084 -3.50012)
				)
				(arc
					(start 78.650084 -3.50012)
					(mid 77.0001 -1.850136)
					(end 75.350116 -3.50012)
				)
			)
		)
	)
	(zone
		(layer "B.Cu")
		(hatch none 0.5)
		(connect_pads
			(clearance 0)
		)
		(min_thickness 0.25)
		(keepout
			(tracks allowed)
			(vias allowed)
			(pads allowed)
			(copperpour allowed)
			(footprints not_allowed)
		)
		(placement
			(enabled no)
			(sheetname "")
		)
		(fill
			(thermal_gap 0.5)
			(thermal_bridge_width 0.5)
			(island_removal_mode 0)
		)
		(polygon
			(pts
				(arc
					(start 142.999968 -61.699902)
					(mid 139.999974 -58.699908)
					(end 136.99998 -61.699902)
				)
				(arc
					(start 136.99998 -61.699902)
					(mid 139.999974 -64.699896)
					(end 142.999968 -61.699902)
				)
			)
		)
	)
	(zone
		(net "P12V_SW_R")
		(layer "B.Cu")
		(hatch none 0.5)
		(connect_pads
			(clearance 0.5)
		)
		(min_thickness 0.25)
		(fill yes
			(thermal_gap 0.5)
			(thermal_bridge_width 0.5)
			(island_removal_mode 0)
		)
		(polygon
			(pts
				(xy 75.438 -36.3982) (xy 75.057 -36.7792) (xy 75.057 -42.164) (xy 75.311 -42.418) (xy 78.232 -42.418)
				(xy 78.47457 -42.17543) (xy 81.673192 -42.17543) (xy 81.901284 -41.947338) (xy 81.901284 -37.825172)
				(xy 81.65846 -37.582348) (xy 78.232 -37.582348) (xy 77.047852 -36.3982)
			)
		)
		(polygon
			(pts
				(xy 75.7682 -42.0624) (xy 75.565 -42.0624) (xy 75.565 -42.2656) (xy 75.7682 -42.2656)
			)
		)
		(polygon
			(pts
				(xy 75.7682 -41.4528) (xy 75.565 -41.4528) (xy 75.565 -41.656) (xy 75.7682 -41.656)
			)
		)
	)
	(zone
		(layer "B.Cu")
		(hatch none 0.5)
		(connect_pads
			(clearance 0)
		)
		(min_thickness 0.25)
		(keepout
			(tracks allowed)
			(vias allowed)
			(pads allowed)
			(copperpour allowed)
			(footprints allowed)
		)
		(placement
			(enabled no)
			(sheetname "")
		)
		(fill
			(thermal_gap 0.5)
			(thermal_bridge_width 0.5)
			(island_removal_mode 0)
		)
		(polygon
			(pts
				(xy 81.510886 -24.89962) (xy 82.104484 -24.89962) (xy 82.104484 -26.281888) (xy 81.510886 -26.281888)
			)
		)
	)
	(zone
		(layer "B.Cu")
		(hatch none 0.5)
		(connect_pads
			(clearance 0)
		)
		(min_thickness 0.25)
		(keepout
			(tracks allowed)
			(vias allowed)
			(pads allowed)
			(copperpour allowed)
			(footprints allowed)
		)
		(placement
			(enabled no)
			(sheetname "")
		)
		(fill
			(thermal_gap 0.5)
			(thermal_bridge_width 0.5)
			(island_removal_mode 0)
		)
		(polygon
			(pts
				(xy 80.68691 -10.954766) (xy 80.68691 -10.48639) (xy 82.300572 -10.48639) (xy 82.300572 -10.954766)
			)
		)
	)
	(zone
		(layer "B.Cu")
		(hatch none 0.5)
		(connect_pads
			(clearance 0)
		)
		(min_thickness 0.25)
		(keepout
			(tracks not_allowed)
			(vias allowed)
			(pads allowed)
			(copperpour not_allowed)
			(footprints allowed)
		)
		(placement
			(enabled no)
			(sheetname "")
		)
		(fill
			(thermal_gap 0.5)
			(thermal_bridge_width 0.5)
			(island_removal_mode 0)
		)
		(polygon
			(pts
				(xy 102.405434 -51.06162) (xy 102.405434 -51.28641)
				(arc
					(start 102.481634 -51.362864)
					(mid 103.014366 -52.064252)
					(end 102.312978 -51.53152)
				)
				(xy 102.236524 -51.45532) (xy 102.166674 -51.38547) (xy 102.166674 -51.28641) (xy 102.166674 -51.06162)
				(xy 101.963474 -51.06162) (xy 101.963474 -51.28641) (xy 101.963474 -51.38547) (xy 101.893624 -51.45532)
				(arc
					(start 101.81717 -51.53152)
					(mid 101.115782 -52.064252)
					(end 101.648514 -51.362864)
				)
				(xy 101.724714 -51.28641) (xy 101.724714 -51.06162)
				(arc
					(start 101.430074 -51.06162)
					(mid 100.741734 -51.74996)
					(end 101.430074 -52.4383)
				)
				(arc
					(start 102.700074 -52.4383)
					(mid 103.388414 -51.74996)
					(end 102.700074 -51.06162)
				)
			)
		)
	)
	(zone
		(net "P5V")
		(layer "B.Cu")
		(hatch none 0.5)
		(connect_pads
			(clearance 0.5)
		)
		(min_thickness 0.25)
		(fill yes
			(thermal_gap 0.5)
			(thermal_bridge_width 0.5)
			(island_removal_mode 0)
		)
		(polygon
			(pts
				(xy 13.095986 -19.986498) (xy 12.971272 -20.111212) (xy 12.971272 -21.533612) (xy 13.102336 -21.664676)
				(xy 15.3924 -21.664676) (xy 15.65656 -21.400516) (xy 15.65656 -20.053808) (xy 15.58925 -19.986498)
			)
		)
	)
	(zone
		(layer "B.Cu")
		(hatch none 0.5)
		(connect_pads
			(clearance 0)
		)
		(min_thickness 0.25)
		(keepout
			(tracks allowed)
			(vias allowed)
			(pads allowed)
			(copperpour allowed)
			(footprints allowed)
		)
		(placement
			(enabled no)
			(sheetname "")
		)
		(fill
			(thermal_gap 0.5)
			(thermal_bridge_width 0.5)
			(island_removal_mode 0)
		)
		(polygon
			(pts
				(xy 84.415376 -25.365964) (xy 84.415376 -24.772366) (xy 86.163404 -24.772366) (xy 86.163404 -25.365964)
			)
		)
	)
	(zone
		(layer "B.Cu")
		(hatch none 0.5)
		(connect_pads
			(clearance 0)
		)
		(min_thickness 0.25)
		(keepout
			(tracks allowed)
			(vias allowed)
			(pads allowed)
			(copperpour allowed)
			(footprints not_allowed)
		)
		(placement
			(enabled no)
			(sheetname "")
		)
		(fill
			(thermal_gap 0.5)
			(thermal_bridge_width 0.5)
			(island_removal_mode 0)
		)
		(polygon
			(pts
				(arc
					(start 138.34999 -61.699902)
					(mid 139.999974 -63.349886)
					(end 141.649958 -61.699902)
				)
				(arc
					(start 141.649958 -61.699902)
					(mid 139.999974 -60.049918)
					(end 138.34999 -61.699902)
				)
			)
		)
	)
	(zone
		(layer "B.Cu")
		(hatch none 0.5)
		(connect_pads
			(clearance 0)
		)
		(min_thickness 0.25)
		(keepout
			(tracks allowed)
			(vias allowed)
			(pads allowed)
			(copperpour allowed)
			(footprints allowed)
		)
		(placement
			(enabled no)
			(sheetname "")
		)
		(fill
			(thermal_gap 0.5)
			(thermal_bridge_width 0.5)
			(island_removal_mode 0)
		)
		(polygon
			(pts
				(xy 74.13371 -25.400254) (xy 74.13371 -24.806656) (xy 75.881738 -24.806656) (xy 75.881738 -25.400254)
			)
		)
	)
	(zone
		(layer "B.Cu")
		(hatch none 0.5)
		(connect_pads
			(clearance 0)
		)
		(min_thickness 0.25)
		(keepout
			(tracks allowed)
			(vias allowed)
			(pads allowed)
			(copperpour allowed)
			(footprints not_allowed)
		)
		(placement
			(enabled no)
			(sheetname "")
		)
		(fill
			(thermal_gap 0.5)
			(thermal_bridge_width 0.5)
			(island_removal_mode 0)
		)
		(polygon
			(pts
				(arc
					(start 74.000106 -61.699902)
					(mid 77.0001 -64.699896)
					(end 80.000094 -61.699902)
				)
				(arc
					(start 80.000094 -61.699902)
					(mid 77.0001 -58.699908)
					(end 74.000106 -61.699902)
				)
			)
		)
	)
	(zone
		(net "P12V")
		(layer "B.Cu")
		(hatch none 0.5)
		(connect_pads
			(clearance 0.5)
		)
		(min_thickness 0.25)
		(fill yes
			(thermal_gap 0.5)
			(thermal_bridge_width 0.5)
			(island_removal_mode 0)
		)
		(polygon
			(pts
				(xy 82.442812 -38.848284) (xy 82.315812 -38.975284) (xy 82.315812 -42.227754) (xy 82.737706 -42.649648)
				(xy 86.727792 -42.649648) (xy 86.975696 -42.401744) (xy 86.975696 -38.972744) (xy 86.851236 -38.848284)
			)
		)
	)
	(zone
		(net "P5V")
		(layer "B.Cu")
		(hatch none 0.5)
		(connect_pads
			(clearance 0.5)
		)
		(min_thickness 0.25)
		(fill yes
			(thermal_gap 0.5)
			(thermal_bridge_width 0.5)
			(island_removal_mode 0)
		)
		(polygon
			(pts
				(xy 131.047236 -20.072096) (xy 130.896106 -20.223226) (xy 130.896106 -23.332694) (xy 131.713986 -24.150574)
				(xy 131.713986 -28.008072) (xy 132.073396 -28.367482) (xy 135.05815 -28.367482) (xy 135.278622 -28.14701)
				(xy 135.278622 -21.570696) (xy 133.780022 -20.072096)
			)
		)
		(polygon
			(pts
				(xy 132.384038 -27.324812) (xy 132.180838 -27.324812) (xy 132.180838 -27.528012) (xy 132.384038 -27.528012)
			)
		)
		(polygon
			(pts
				(xy 132.384038 -26.715212) (xy 132.180838 -26.715212) (xy 132.180838 -26.918412) (xy 132.384038 -26.918412)
			)
		)
	)
	(zone
		(net "P5V_SW_L")
		(layer "B.Cu")
		(hatch none 0.5)
		(connect_pads
			(clearance 0.5)
		)
		(min_thickness 0.25)
		(fill yes
			(thermal_gap 0.5)
			(thermal_bridge_width 0.5)
			(island_removal_mode 0)
		)
		(polygon
			(pts
				(xy 65.477136 -8.94334) (xy 65.149476 -9.271) (xy 65.149476 -13.38326) (xy 65.547494 -13.781278)
				(xy 68.596764 -13.781278) (xy 68.788534 -13.589508) (xy 68.788534 -9.19607) (xy 68.535804 -8.94334)
			)
		)
	)
	(zone
		(layer "B.Cu")
		(hatch none 0.5)
		(connect_pads
			(clearance 0)
		)
		(min_thickness 0.25)
		(keepout
			(tracks allowed)
			(vias allowed)
			(pads allowed)
			(copperpour allowed)
			(footprints allowed)
		)
		(placement
			(enabled no)
			(sheetname "")
		)
		(fill
			(thermal_gap 0.5)
			(thermal_bridge_width 0.5)
			(island_removal_mode 0)
		)
		(polygon
			(pts
				(xy 84.238846 -20.73021) (xy 84.238846 -20.136612) (xy 85.986874 -20.136612) (xy 85.986874 -20.73021)
			)
		)
	)
	(zone
		(net "GND")
		(layer "B.Cu")
		(hatch none 0.5)
		(connect_pads
			(clearance 0.5)
		)
		(min_thickness 0.25)
		(fill yes
			(thermal_gap 0.5)
			(thermal_bridge_width 0.5)
			(island_removal_mode 0)
		)
		(polygon
			(pts
				(xy 74.700384 -0.763016) (xy 73.7997 -1.6637) (xy 73.7997 -4.4577) (xy 75.456288 -6.114288) (xy 77.9272 -6.114288)
				(xy 78.3336 -6.520688) (xy 78.3336 -7.454392) (xy 78.349348 -7.454392) (xy 78.349348 -9.284208)
				(xy 78.235556 -9.398) (xy 77.800708 -9.398) (xy 77.699108 -9.4996) (xy 77.699108 -11.190478) (xy 77.597 -11.292586)
				(xy 77.597 -12.0904) (xy 77.7748 -12.2682) (xy 78.5114 -12.2682) (xy 78.764892 -12.014708) (xy 78.764892 -11.43)
				(xy 78.7654 -11.413744) (xy 78.7654 -10.9728) (xy 79.1591 -10.5791) (xy 79.1591 -6.644132) (xy 79.368142 -6.43509)
				(xy 80.010254 -6.43509) (xy 80.274414 -6.69925) (xy 80.478122 -6.69925) (xy 81.37525 -5.802122)
				(xy 81.37525 -3.751326) (xy 83.094576 -2.032) (xy 87.676482 -2.032)
				(arc
					(start 87.69096 -1.98882)
					(mid 88.098687 -1.610024)
					(end 88.638888 -1.743964)
				)
				(xy 90.766392 -1.743964) (xy 90.972386 -1.950212) (xy 91.054174 -2.032) (xy 94.73692 -2.032)
				(arc
					(start 94.73692 -0.999998)
					(mid 94.66751 -0.832426)
					(end 94.499938 -0.763016)
				)
			)
		)
		(polygon
			(pts
				(xy 78.613 -11.2268) (xy 78.4098 -11.2268) (xy 78.4098 -11.43) (xy 78.613 -11.43)
			)
		)
	)
	(zone
		(layer "B.Cu")
		(hatch none 0.5)
		(connect_pads
			(clearance 0)
		)
		(min_thickness 0.25)
		(keepout
			(tracks allowed)
			(vias allowed)
			(pads allowed)
			(copperpour allowed)
			(footprints not_allowed)
		)
		(placement
			(enabled no)
			(sheetname "")
		)
		(fill
			(thermal_gap 0.5)
			(thermal_bridge_width 0.5)
			(island_removal_mode 0)
		)
		(polygon
			(pts
				(arc
					(start 6.999986 -4.19989)
					(mid 3.999992 -1.199896)
					(end 0.999998 -4.19989)
				)
				(arc
					(start 0.999998 -4.19989)
					(mid 3.999992 -7.199884)
					(end 6.999986 -4.19989)
				)
			)
		)
	)
	(zone
		(net "GND")
		(layer "B.Cu")
		(hatch none 0.5)
		(connect_pads
			(clearance 0.5)
		)
		(min_thickness 0.25)
		(fill yes
			(thermal_gap 0.5)
			(thermal_bridge_width 0.5)
			(island_removal_mode 0)
		)
		(polygon
			(pts
				(xy 131.360164 -27.537918) (xy 131.360164 -24.841962) (xy 130.491992 -23.974044) (xy 130.491992 -20.581112)
				(xy 130.030728 -20.119848) (xy 125.410214 -20.119848) (xy 124.972826 -20.557236) (xy 124.972826 -23.64613)
				(xy 123.902978 -24.715978) (xy 123.902978 -28.097734) (xy 123.903232 -28.097988) (xy 123.903232 -31.526734)
				(xy 125.233176 -32.856678) (xy 128.721866 -32.856678) (xy 131.555998 -35.69081) (xy 131.555998 -53.550312)
				(xy 125.58014 -59.52617) (xy 121.07037 -59.52617) (xy 120.5738 -59.0296) (xy 120.5738 -56.39308)
				(xy 119.6848 -55.50408) (xy 112.963452 -55.50408) (xy 110.706154 -57.761378) (xy 84.643722 -57.761378)
				(xy 83.783678 -58.621422) (xy 76.06411 -58.621422) (xy 71.910448 -54.46776) (xy 71.910448 -43.818048)
				(xy 71.6788 -43.5864) (xy 70.517004 -43.5864) (xy 70.263004 -43.8404) (xy 70.263004 -53.38191) (xy 70.262242 -53.382672)
				(arc
					(start 70.262242 -64.200024)
					(mid 70.331876 -64.368134)
					(end 70.499986 -64.437768)
				)
				(arc
					(start 142.500096 -64.437768)
					(mid 142.668206 -64.368134)
					(end 142.73784 -64.200024)
				)
				(xy 142.73784 -55.953406) (xy 142.737078 -55.952644) (xy 142.737078 -18.483326) (xy 142.73784 -18.483326)
				(arc
					(start 142.73784 -0.999998)
					(mid 142.668206 -0.831888)
					(end 142.500096 -0.762254)
				)
				(arc
					(start 136.500108 -0.762254)
					(mid 136.331998 -0.831888)
					(end 136.262364 -0.999998)
				)
				(xy 136.262364 -28.01874) (xy 135.208518 -29.072586) (xy 132.376672 -29.072586) (xy 132.371592 -29.067252)
				(xy 132.12572 -29.067252) (xy 131.36118 -28.302712) (xy 131.36118 -27.538934)
			)
		)
		(polygon
			(pts
				(xy 124.599192 -27.328876) (xy 124.395992 -27.328876) (xy 124.395992 -27.532076) (xy 124.599192 -27.532076)
			)
		)
		(polygon
			(pts
				(xy 130.860038 -27.324812) (xy 130.656838 -27.324812) (xy 130.656838 -27.528012) (xy 130.860038 -27.528012)
			)
		)
		(polygon
			(pts
				(xy 124.599192 -26.719276) (xy 124.395992 -26.719276) (xy 124.395992 -26.922476) (xy 124.599192 -26.922476)
			)
		)
		(polygon
			(pts
				(xy 130.860038 -26.715212) (xy 130.656838 -26.715212) (xy 130.656838 -26.918412) (xy 130.860038 -26.918412)
			)
		)
	)
	(zone
		(net "P12V")
		(layer "B.Cu")
		(hatch none 0.5)
		(connect_pads
			(clearance 0.5)
		)
		(min_thickness 0.25)
		(fill yes
			(thermal_gap 0.5)
			(thermal_bridge_width 0.5)
			(island_removal_mode 0)
		)
		(polygon
			(pts
				(xy 88.42375 -10.16) (xy 88.29675 -10.287) (xy 88.29675 -13.62075) (xy 88.519 -13.843) (xy 91.681808 -13.843)
				(xy 91.935808 -13.589) (xy 91.935808 -10.287) (xy 91.808808 -10.16)
			)
		)
	)
	(zone
		(layer "B.Cu")
		(hatch none 0.5)
		(connect_pads
			(clearance 0)
		)
		(min_thickness 0.25)
		(keepout
			(tracks allowed)
			(vias allowed)
			(pads allowed)
			(copperpour allowed)
			(footprints not_allowed)
		)
		(placement
			(enabled no)
			(sheetname "")
		)
		(fill
			(thermal_gap 0.5)
			(thermal_bridge_width 0.5)
			(island_removal_mode 0)
		)
		(polygon
			(pts
				(arc
					(start 136.99998 -3.50012)
					(mid 139.999974 -6.500114)
					(end 142.999968 -3.50012)
				)
				(arc
					(start 142.999968 -3.50012)
					(mid 139.999974 -0.500126)
					(end 136.99998 -3.50012)
				)
			)
		)
	)
	(zone
		(layer "B.Cu")
		(hatch none 0.5)
		(connect_pads
			(clearance 0)
		)
		(min_thickness 0.25)
		(keepout
			(tracks allowed)
			(vias allowed)
			(pads allowed)
			(copperpour allowed)
			(footprints allowed)
		)
		(placement
			(enabled no)
			(sheetname "")
		)
		(fill
			(thermal_gap 0.5)
			(thermal_bridge_width 0.5)
			(island_removal_mode 0)
		)
		(polygon
			(pts
				(xy 78.185264 -20.865846) (xy 78.185264 -20.272248) (xy 79.933292 -20.272248) (xy 79.933292 -20.865846)
			)
		)
	)
	(zone
		(layer "B.Cu")
		(hatch none 0.5)
		(connect_pads
			(clearance 0)
		)
		(min_thickness 0.25)
		(keepout
			(tracks allowed)
			(vias allowed)
			(pads allowed)
			(copperpour allowed)
			(footprints allowed)
		)
		(placement
			(enabled no)
			(sheetname "")
		)
		(fill
			(thermal_gap 0.5)
			(thermal_bridge_width 0.5)
			(island_removal_mode 0)
		)
		(polygon
			(pts
				(xy 81.649824 -23.233126) (xy 81.649824 -22.639528) (xy 83.397852 -22.639528) (xy 83.397852 -23.233126)
			)
		)
	)
	(zone
		(layer "B.Cu")
		(hatch none 0.5)
		(connect_pads
			(clearance 0)
		)
		(min_thickness 0.25)
		(keepout
			(tracks allowed)
			(vias allowed)
			(pads allowed)
			(copperpour allowed)
			(footprints allowed)
		)
		(placement
			(enabled no)
			(sheetname "")
		)
		(fill
			(thermal_gap 0.5)
			(thermal_bridge_width 0.5)
			(island_removal_mode 0)
		)
		(polygon
			(pts
				(xy 81.496408 -20.720558) (xy 81.496408 -20.12696) (xy 83.244436 -20.12696) (xy 83.244436 -20.720558)
			)
		)
	)
	(zone
		(layer "B.Cu")
		(hatch none 0.5)
		(connect_pads
			(clearance 0)
		)
		(min_thickness 0.25)
		(keepout
			(tracks not_allowed)
			(vias allowed)
			(pads allowed)
			(copperpour not_allowed)
			(footprints allowed)
		)
		(placement
			(enabled no)
			(sheetname "")
		)
		(fill
			(thermal_gap 0.5)
			(thermal_bridge_width 0.5)
			(island_removal_mode 0)
		)
		(polygon
			(pts
				(arc
					(start 87.092536 -23.446994)
					(mid 86.581996 -22.936454)
					(end 86.071456 -23.446994)
				)
				(xy 86.071456 -23.614634) (xy 86.245446 -23.614634)
				(arc
					(start 86.329012 -23.531322)
					(mid 86.770559 -23.258431)
					(end 86.497668 -23.699978)
				)
				(xy 86.414356 -23.783544) (xy 86.344506 -23.853394) (xy 86.245446 -23.853394) (xy 86.071456 -23.853394)
				(xy 86.071456 -24.056594) (xy 86.245446 -24.056594) (xy 86.344506 -24.056594) (xy 86.414356 -24.126444)
				(arc
					(start 86.497668 -24.21001)
					(mid 86.770559 -24.651557)
					(end 86.329012 -24.378666)
				)
				(xy 86.245446 -24.295354) (xy 86.071456 -24.295354)
				(arc
					(start 86.071456 -24.46274)
					(mid 86.581869 -24.973534)
					(end 87.092536 -24.462994)
				)
			)
		)
	)
	(zone
		(layer "B.Cu")
		(hatch none 0.5)
		(connect_pads
			(clearance 0)
		)
		(min_thickness 0.25)
		(keepout
			(tracks allowed)
			(vias allowed)
			(pads allowed)
			(copperpour allowed)
			(footprints not_allowed)
		)
		(placement
			(enabled no)
			(sheetname "")
		)
		(fill
			(thermal_gap 0.5)
			(thermal_bridge_width 0.5)
			(island_removal_mode 0)
		)
		(polygon
			(pts
				(arc
					(start 6.999986 -4.020058)
					(mid 3.999992 -1.020064)
					(end 0.999998 -4.020058)
				)
				(arc
					(start 0.999998 -4.020058)
					(mid 3.999992 -7.020052)
					(end 6.999986 -4.020058)
				)
			)
		)
	)
	(zone
		(layer "B.Cu")
		(hatch none 0.5)
		(connect_pads
			(clearance 0)
		)
		(min_thickness 0.25)
		(keepout
			(tracks allowed)
			(vias allowed)
			(pads allowed)
			(copperpour allowed)
			(footprints allowed)
		)
		(placement
			(enabled no)
			(sheetname "")
		)
		(fill
			(thermal_gap 0.5)
			(thermal_bridge_width 0.5)
			(island_removal_mode 0)
		)
		(polygon
			(pts
				(xy 74.086974 -20.865846) (xy 74.086974 -20.272248) (xy 75.835002 -20.272248) (xy 75.835002 -20.865846)
			)
		)
	)
	(zone
		(net "P12V")
		(layer "B.Cu")
		(hatch none 0.5)
		(connect_pads
			(clearance 0.5)
		)
		(min_thickness 0.25)
		(fill yes
			(thermal_gap 0.5)
			(thermal_bridge_width 0.5)
			(island_removal_mode 0)
		)
		(polygon
			(pts
				(xy 121.703338 -20.116038) (xy 121.38152 -20.437856) (xy 121.38152 -27.681428) (xy 121.894854 -28.194762)
				(xy 123.358656 -28.194762) (xy 123.57354 -27.979624) (xy 123.57354 -24.569674) (xy 124.401834 -23.74138)
				(xy 124.401834 -20.38477) (xy 124.133102 -20.116038)
			)
		)
		(polygon
			(pts
				(xy 123.075192 -27.328876) (xy 122.871992 -27.328876) (xy 122.871992 -27.532076) (xy 123.075192 -27.532076)
			)
		)
		(polygon
			(pts
				(xy 123.075192 -26.719276) (xy 122.871992 -26.719276) (xy 122.871992 -26.922476) (xy 123.075192 -26.922476)
			)
		)
	)
	(zone
		(layer "B.Cu")
		(hatch none 0.5)
		(connect_pads
			(clearance 0)
		)
		(min_thickness 0.25)
		(keepout
			(tracks allowed)
			(vias allowed)
			(pads allowed)
			(copperpour allowed)
			(footprints allowed)
		)
		(placement
			(enabled no)
			(sheetname "")
		)
		(fill
			(thermal_gap 0.5)
			(thermal_bridge_width 0.5)
			(island_removal_mode 0)
		)
		(polygon
			(pts
				(xy 78.571598 -26.475182) (xy 77.978 -26.475182) (xy 77.978 -24.727154) (xy 78.571598 -24.727154)
			)
		)
	)
	(zone
		(layer "B.Cu")
		(hatch none 0.5)
		(connect_pads
			(clearance 0)
		)
		(min_thickness 0.25)
		(keepout
			(tracks allowed)
			(vias allowed)
			(pads allowed)
			(copperpour allowed)
			(footprints not_allowed)
		)
		(placement
			(enabled no)
			(sheetname "")
		)
		(fill
			(thermal_gap 0.5)
			(thermal_bridge_width 0.5)
			(island_removal_mode 0)
		)
		(polygon
			(pts
				(arc
					(start 75.350116 -61.699902)
					(mid 77.0001 -63.349886)
					(end 78.650084 -61.699902)
				)
				(arc
					(start 78.650084 -61.699902)
					(mid 77.0001 -60.049918)
					(end 75.350116 -61.699902)
				)
			)
		)
	)
	(zone
		(layer "B.Cu")
		(hatch none 0.5)
		(connect_pads
			(clearance 0)
		)
		(min_thickness 0.25)
		(keepout
			(tracks allowed)
			(vias allowed)
			(pads allowed)
			(copperpour allowed)
			(footprints not_allowed)
		)
		(placement
			(enabled no)
			(sheetname "")
		)
		(fill
			(thermal_gap 0.5)
			(thermal_bridge_width 0.5)
			(island_removal_mode 0)
		)
		(polygon
			(pts
				(arc
					(start 80.000094 -61.699902)
					(mid 77.0001 -58.699908)
					(end 74.000106 -61.699902)
				)
				(arc
					(start 74.000106 -61.699902)
					(mid 77.0001 -64.699896)
					(end 80.000094 -61.699902)
				)
			)
		)
	)
	(zone
		(layer "B.Cu")
		(hatch none 0.5)
		(connect_pads
			(clearance 0)
		)
		(min_thickness 0.25)
		(keepout
			(tracks allowed)
			(vias allowed)
			(pads allowed)
			(copperpour allowed)
			(footprints allowed)
		)
		(placement
			(enabled no)
			(sheetname "")
		)
		(fill
			(thermal_gap 0.5)
			(thermal_bridge_width 0.5)
			(island_removal_mode 0)
		)
		(polygon
			(pts
				(xy 75.42149 -23.11781) (xy 75.42149 -22.524212) (xy 77.169518 -22.524212) (xy 77.169518 -23.11781)
			)
		)
	)
	(zone
		(net "P5V_SW_R")
		(layer "B.Cu")
		(hatch none 0.5)
		(connect_pads
			(clearance 0.5)
		)
		(min_thickness 0.25)
		(fill yes
			(thermal_gap 0.5)
			(thermal_bridge_width 0.5)
			(island_removal_mode 0)
		)
		(polygon
			(pts
				(xy 77.552296 -47.501556) (xy 77.269086 -47.784766) (xy 77.269086 -51.856132) (xy 77.460348 -52.047394)
				(xy 81.181448 -52.047394) (xy 81.564988 -51.663854) (xy 81.564988 -47.689008) (xy 81.377536 -47.501556)
			)
		)
	)
	(zone
		(layer "B.Cu")
		(hatch none 0.5)
		(connect_pads
			(clearance 0)
		)
		(min_thickness 0.25)
		(keepout
			(tracks allowed)
			(vias allowed)
			(pads allowed)
			(copperpour allowed)
			(footprints not_allowed)
		)
		(placement
			(enabled no)
			(sheetname "")
		)
		(fill
			(thermal_gap 0.5)
			(thermal_bridge_width 0.5)
			(island_removal_mode 0)
		)
		(polygon
			(pts
				(arc
					(start 74.000106 -3.50012)
					(mid 77.0001 -6.500114)
					(end 80.000094 -3.50012)
				)
				(arc
					(start 80.000094 -3.50012)
					(mid 77.0001 -0.500126)
					(end 74.000106 -3.50012)
				)
			)
		)
	)
	(zone
		(layer "B.Cu")
		(hatch none 0.5)
		(connect_pads
			(clearance 0)
		)
		(min_thickness 0.25)
		(keepout
			(tracks not_allowed)
			(vias allowed)
			(pads allowed)
			(copperpour not_allowed)
			(footprints allowed)
		)
		(placement
			(enabled no)
			(sheetname "")
		)
		(fill
			(thermal_gap 0.5)
			(thermal_bridge_width 0.5)
			(island_removal_mode 0)
		)
		(polygon
			(pts
				(arc
					(start 28.387802 -2.768346)
					(mid 29.08919 -2.235614)
					(end 28.556458 -2.937002)
				)
				(xy 28.513024 -2.98069) (xy 28.513024 -3.238246)
				(arc
					(start 28.774898 -3.238246)
					(mid 29.463238 -2.549906)
					(end 28.774898 -1.861566)
				)
				(arc
					(start 27.504898 -1.861566)
					(mid 26.816558 -2.549906)
					(end 27.504898 -3.238246)
				)
				(xy 27.832304 -3.238246) (xy 27.832304 -3.046222)
				(arc
					(start 27.723338 -2.937002)
					(mid 27.190606 -2.235614)
					(end 27.891994 -2.768346)
				)
				(xy 28.001214 -2.877312) (xy 28.071064 -2.947162) (xy 28.071064 -3.046222) (xy 28.071064 -3.238246)
				(xy 28.274264 -3.238246) (xy 28.274264 -2.98069) (xy 28.274264 -2.88163) (xy 28.344114 -2.81178)
			)
		)
	)
	(zone
		(net "GND")
		(layer "B.Cu")
		(hatch none 0.5)
		(connect_pads
			(clearance 0.5)
		)
		(min_thickness 0.25)
		(fill yes
			(thermal_gap 0.5)
			(thermal_bridge_width 0.5)
			(island_removal_mode 0)
		)
		(polygon
			(pts
				(xy 72.517 -36.6268) (xy 72.0344 -37.1094) (xy 72.0344 -41.3766) (xy 72.9234 -42.2656) (xy 74.676 -42.2656)
				(xy 74.749152 -42.192448) (xy 74.749152 -36.877752) (xy 74.4982 -36.6268)
			)
		)
		(polygon
			(pts
				(xy 74.2442 -41.4528) (xy 74.041 -41.4528) (xy 74.041 -41.656) (xy 74.2442 -41.656)
			)
		)
	)
	(zone
		(layer "B.Cu")
		(hatch none 0.5)
		(connect_pads
			(clearance 0)
		)
		(min_thickness 0.25)
		(keepout
			(tracks not_allowed)
			(vias allowed)
			(pads allowed)
			(copperpour not_allowed)
			(footprints allowed)
		)
		(placement
			(enabled no)
			(sheetname "")
		)
		(fill
			(thermal_gap 0.5)
			(thermal_bridge_width 0.5)
			(island_removal_mode 0)
		)
		(polygon
			(pts
				(xy 102.40772 -34.361628) (xy 102.40772 -34.588704)
				(arc
					(start 102.481634 -34.662872)
					(mid 103.014366 -35.36426)
					(end 102.312978 -34.831528)
				)
				(xy 102.23881 -34.757614) (xy 102.16896 -34.687764) (xy 102.16896 -34.588704) (xy 102.16896 -34.361628)
				(xy 101.96576 -34.361628) (xy 101.96576 -34.584132) (xy 101.96576 -34.683192) (xy 101.89591 -34.753042)
				(arc
					(start 101.81717 -34.831528)
					(mid 101.115782 -35.36426)
					(end 101.648514 -34.662872)
				)
				(xy 101.727 -34.584132) (xy 101.727 -34.361628)
				(arc
					(start 101.430074 -34.361628)
					(mid 100.741734 -35.049968)
					(end 101.430074 -35.738308)
				)
				(arc
					(start 102.700074 -35.738308)
					(mid 103.388414 -35.049968)
					(end 102.700074 -34.361628)
				)
			)
		)
	)
	(zone
		(layer "B.Cu")
		(hatch none 0.5)
		(connect_pads
			(clearance 0)
		)
		(min_thickness 0.25)
		(keepout
			(tracks allowed)
			(vias allowed)
			(pads allowed)
			(copperpour allowed)
			(footprints allowed)
		)
		(placement
			(enabled no)
			(sheetname "")
		)
		(fill
			(thermal_gap 0.5)
			(thermal_bridge_width 0.5)
			(island_removal_mode 0)
		)
		(polygon
			(pts
				(xy 76.782422 -23.138384) (xy 76.782422 -22.544786) (xy 78.53045 -22.544786) (xy 78.53045 -23.138384)
			)
		)
	)
	(zone
		(net "GND")
		(layer "B.Cu")
		(hatch none 0.5)
		(connect_pads
			(clearance 0.5)
		)
		(min_thickness 0.25)
		(fill yes
			(thermal_gap 0.5)
			(thermal_bridge_width 0.5)
			(island_removal_mode 0)
		)
		(polygon
			(pts
				(xy 81.656428 -12.63523) (xy 81.569814 -12.721844) (xy 81.569814 -13.650976) (xy 81.317338 -13.903452)
				(xy 81.317338 -14.57071) (xy 81.56321 -14.816582) (xy 83.978242 -14.816582) (xy 84.11464 -14.680184)
				(xy 84.11464 -14.14018) (xy 84.015834 -14.041374) (xy 83.269328 -14.041374) (xy 82.775298 -13.547344)
				(xy 82.775298 -12.70889) (xy 82.701638 -12.63523)
			)
		)
		(polygon
			(pts
				(xy 82.281522 -13.136626) (xy 82.078322 -13.136626) (xy 82.078322 -13.339826) (xy 82.281522 -13.339826)
			)
		)
	)
	(zone
		(net "P5V")
		(layer "B.Cu")
		(hatch none 0.5)
		(connect_pads
			(clearance 0.5)
		)
		(min_thickness 0.25)
		(fill yes
			(thermal_gap 0.5)
			(thermal_bridge_width 0.5)
			(island_removal_mode 0)
		)
		(polygon
			(pts
				(xy 82.476086 -48.768) (xy 82.349086 -48.895) (xy 82.349086 -52.14747) (xy 82.77098 -52.569364)
				(xy 86.098634 -52.569364) (xy 86.644988 -52.02301) (xy 86.644988 -49.179988) (xy 86.233 -48.768)
			)
		)
	)
	(zone
		(layer "B.Cu")
		(hatch none 0.5)
		(connect_pads
			(clearance 0)
		)
		(min_thickness 0.25)
		(keepout
			(tracks allowed)
			(vias allowed)
			(pads allowed)
			(copperpour allowed)
			(footprints not_allowed)
		)
		(placement
			(enabled no)
			(sheetname "")
		)
		(fill
			(thermal_gap 0.5)
			(thermal_bridge_width 0.5)
			(island_removal_mode 0)
		)
		(polygon
			(pts
				(arc
					(start 136.99998 -61.699902)
					(mid 139.999974 -64.699896)
					(end 142.999968 -61.699902)
				)
				(arc
					(start 142.999968 -61.699902)
					(mid 139.999974 -58.699908)
					(end 136.99998 -61.699902)
				)
			)
		)
	)
	(zone
		(layer "B.Cu")
		(hatch none 0.5)
		(connect_pads
			(clearance 0)
		)
		(min_thickness 0.25)
		(keepout
			(tracks allowed)
			(vias allowed)
			(pads allowed)
			(copperpour allowed)
			(footprints not_allowed)
		)
		(placement
			(enabled no)
			(sheetname "")
		)
		(fill
			(thermal_gap 0.5)
			(thermal_bridge_width 0.5)
			(island_removal_mode 0)
		)
		(polygon
			(pts
				(arc
					(start 2.350008 -4.020058)
					(mid 3.999992 -5.670042)
					(end 5.649976 -4.020058)
				)
				(arc
					(start 5.649976 -4.020058)
					(mid 3.999992 -2.370074)
					(end 2.350008 -4.020058)
				)
			)
		)
	)
	(zone
		(layer "B.Cu")
		(hatch none 0.5)
		(connect_pads
			(clearance 0)
		)
		(min_thickness 0.25)
		(keepout
			(tracks allowed)
			(vias allowed)
			(pads allowed)
			(copperpour allowed)
			(footprints not_allowed)
		)
		(placement
			(enabled no)
			(sheetname "")
		)
		(fill
			(thermal_gap 0.5)
			(thermal_bridge_width 0.5)
			(island_removal_mode 0)
		)
		(polygon
			(pts
				(arc
					(start 138.34999 -3.50012)
					(mid 139.999974 -5.150104)
					(end 141.649958 -3.50012)
				)
				(arc
					(start 141.649958 -3.50012)
					(mid 139.999974 -1.850136)
					(end 138.34999 -3.50012)
				)
			)
		)
	)
	(zone
		(layer "B.Cu")
		(hatch none 0.5)
		(connect_pads
			(clearance 0)
		)
		(min_thickness 0.25)
		(keepout
			(tracks allowed)
			(vias allowed)
			(pads allowed)
			(copperpour allowed)
			(footprints allowed)
		)
		(placement
			(enabled no)
			(sheetname "")
		)
		(fill
			(thermal_gap 0.5)
			(thermal_bridge_width 0.5)
			(island_removal_mode 0)
		)
		(polygon
			(pts
				(xy 74.324972 -54.53761) (xy 74.324972 -53.860954) (xy 75.88631 -53.860954) (xy 75.88631 -54.53761)
			)
		)
	)
	(zone
		(layer "B.Cu")
		(hatch none 0.5)
		(connect_pads
			(clearance 0)
		)
		(min_thickness 0.25)
		(keepout
			(tracks allowed)
			(vias allowed)
			(pads allowed)
			(copperpour allowed)
			(footprints not_allowed)
		)
		(placement
			(enabled no)
			(sheetname "")
		)
		(fill
			(thermal_gap 0.5)
			(thermal_bridge_width 0.5)
			(island_removal_mode 0)
		)
		(polygon
			(pts
				(arc
					(start 2.350008 -17.020032)
					(mid 3.999992 -18.670016)
					(end 5.649976 -17.020032)
				)
				(arc
					(start 5.649976 -17.020032)
					(mid 3.999992 -15.370048)
					(end 2.350008 -17.020032)
				)
			)
		)
	)
	(zone
		(layer "B.Cu")
		(hatch none 0.5)
		(connect_pads
			(clearance 0)
		)
		(min_thickness 0.25)
		(keepout
			(tracks not_allowed)
			(vias allowed)
			(pads allowed)
			(copperpour not_allowed)
			(footprints allowed)
		)
		(placement
			(enabled no)
			(sheetname "")
		)
		(fill
			(thermal_gap 0.5)
			(thermal_bridge_width 0.5)
			(island_removal_mode 0)
		)
		(polygon
			(pts
				(xy 83.500976 -25.19807) (xy 83.500976 -25.37206)
				(arc
					(start 83.584288 -25.455626)
					(mid 83.857179 -25.897173)
					(end 83.415632 -25.624282)
				)
				(xy 83.332066 -25.54097) (xy 83.262216 -25.47112) (xy 83.262216 -25.37206) (xy 83.262216 -25.19807)
				(xy 83.059016 -25.19807) (xy 83.059016 -25.37206) (xy 83.059016 -25.47112) (xy 82.989166 -25.54097)
				(arc
					(start 82.9056 -25.624282)
					(mid 82.464053 -25.897173)
					(end 82.736944 -25.455626)
				)
				(xy 82.820256 -25.37206) (xy 82.820256 -25.19807)
				(arc
					(start 82.65287 -25.19807)
					(mid 82.142076 -25.708483)
					(end 82.652616 -26.21915)
				)
				(arc
					(start 83.668616 -26.21915)
					(mid 84.179156 -25.70861)
					(end 83.668616 -25.19807)
				)
			)
		)
	)
	(zone
		(layer "B.Cu")
		(hatch none 0.5)
		(connect_pads
			(clearance 0)
		)
		(min_thickness 0.25)
		(keepout
			(tracks allowed)
			(vias allowed)
			(pads allowed)
			(copperpour allowed)
			(footprints allowed)
		)
		(placement
			(enabled no)
			(sheetname "")
		)
		(fill
			(thermal_gap 0.5)
			(thermal_bridge_width 0.5)
			(island_removal_mode 0)
		)
		(polygon
			(pts
				(xy 84.357972 -23.265892) (xy 84.357972 -22.672294) (xy 86.106 -22.672294) (xy 86.106 -23.265892)
			)
		)
	)
	(zone
		(layer "B.Cu")
		(hatch none 0.5)
		(connect_pads
			(clearance 0)
		)
		(min_thickness 0.25)
		(keepout
			(tracks allowed)
			(vias allowed)
			(pads allowed)
			(copperpour allowed)
			(footprints not_allowed)
		)
		(placement
			(enabled no)
			(sheetname "")
		)
		(fill
			(thermal_gap 0.5)
			(thermal_bridge_width 0.5)
			(island_removal_mode 0)
		)
		(polygon
			(pts
				(arc
					(start 142.500096 -65.200022)
					(mid 143.207201 -64.907129)
					(end 143.500094 -64.200024)
				)
				(arc
					(start 143.500094 -0.999998)
					(mid 143.207201 -0.292893)
					(end 142.500096 0)
				)
				(arc
					(start 136.500108 0)
					(mid 135.793003 -0.292893)
					(end 135.50011 -0.999998)
				)
				(arc
					(start 135.50011 -18.050002)
					(mid 135.207217 -18.757107)
					(end 134.500112 -19.05)
				)
				(arc
					(start 119.350028 -19.05)
					(mid 118.642923 -19.342893)
					(end 118.35003 -20.049998)
				)
				(arc
					(start 118.35003 -23.999952)
					(mid 118.057137 -24.707057)
					(end 117.350032 -24.99995)
				)
				(arc
					(start 96.499934 -24.99995)
					(mid 95.792829 -24.707057)
					(end 95.499936 -23.999952)
				)
				(arc
					(start 95.499936 -0.999998)
					(mid 95.207043 -0.292893)
					(end 94.499938 0)
				)
				(arc
					(start 0.999998 0)
					(mid 0.292893 -0.292893)
					(end 0 -0.999998)
				)
				(arc
					(start 0 -22.200108)
					(mid 0.292893 -22.907213)
					(end 0.999998 -23.200106)
				)
				(arc
					(start 48.999902 -23.200106)
					(mid 49.353619 -23.34641)
					(end 49.500028 -23.699978)
				)
				(arc
					(start 49.500028 -24.200104)
					(mid 49.646437 -24.553567)
					(end 49.9999 -24.699976)
				)
				(arc
					(start 68.49999 -24.699976)
					(mid 69.207095 -24.992869)
					(end 69.499988 -25.699974)
				)
				(arc
					(start 69.499988 -64.200024)
					(mid 69.792881 -64.907129)
					(end 70.499986 -65.200022)
				)
			)
		)
	)
	(zone
		(layer "B.Cu")
		(hatch none 0.5)
		(connect_pads
			(clearance 0)
		)
		(min_thickness 0.25)
		(keepout
			(tracks allowed)
			(vias allowed)
			(pads allowed)
			(copperpour allowed)
			(footprints not_allowed)
		)
		(placement
			(enabled no)
			(sheetname "")
		)
		(fill
			(thermal_gap 0.5)
			(thermal_bridge_width 0.5)
			(island_removal_mode 0)
		)
		(polygon
			(pts
				(arc
					(start 6.999986 -17.020032)
					(mid 3.999992 -14.020038)
					(end 0.999998 -17.020032)
				)
				(arc
					(start 0.999998 -17.020032)
					(mid 3.999992 -20.020026)
					(end 6.999986 -17.020032)
				)
			)
		)
	)
	(zone
		(net "P5V")
		(layer "B.Cu")
		(hatch none 0.5)
		(connect_pads
			(clearance 0.5)
		)
		(min_thickness 0.25)
		(fill yes
			(thermal_gap 0.5)
			(thermal_bridge_width 0.5)
			(island_removal_mode 0)
		)
		(polygon
			(pts
				(xy 70.579488 -10.40257) (xy 70.197472 -10.784586) (xy 70.197472 -14.06144) (xy 70.549008 -14.412976)
				(xy 71.842884 -14.412976) (xy 72.769222 -15.339314) (xy 73.590912 -15.339314) (xy 73.708768 -15.221458)
				(xy 73.708768 -14.412976) (xy 74.478388 -13.643356) (xy 74.478388 -10.76198) (xy 74.119232 -10.40257)
			)
		)
		(polygon
			(pts
				(xy 72.752966 -14.340078) (xy 72.549766 -14.340078) (xy 72.549766 -14.543278) (xy 72.752966 -14.543278)
			)
		)
	)
	(zone
		(net "P3V3")
		(layer "B.Cu")
		(hatch none 0.5)
		(connect_pads
			(clearance 0.5)
		)
		(min_thickness 0.25)
		(fill yes
			(thermal_gap 0.5)
			(thermal_bridge_width 0.5)
			(island_removal_mode 0)
		)
		(polygon
			(pts
				(xy 128.706372 -41.309798) (xy 128.363218 -41.652952) (xy 128.363218 -50.949606) (xy 128.597914 -51.184302)
				(xy 128.597914 -52.05984) (xy 127.866902 -52.790852) (xy 126.5809 -52.790852) (xy 121.67616 -57.695592)
				(xy 121.67616 -58.83021) (xy 121.975372 -59.129422) (xy 124.461778 -59.129422) (xy 130.421126 -53.170074)
				(xy 130.421126 -41.742868) (xy 129.988056 -41.309798)
			)
		)
	)
	(zone
		(layer "B.Cu")
		(hatch none 0.5)
		(connect_pads
			(clearance 0)
		)
		(min_thickness 0.25)
		(keepout
			(tracks allowed)
			(vias allowed)
			(pads allowed)
			(copperpour allowed)
			(footprints allowed)
		)
		(placement
			(enabled no)
			(sheetname "")
		)
		(fill
			(thermal_gap 0.5)
			(thermal_bridge_width 0.5)
			(island_removal_mode 0)
		)
		(polygon
			(pts
				(xy 75.36815 -9.101074) (xy 75.36815 -8.55091) (xy 76.639674 -8.55091) (xy 76.639674 -9.101074)
			)
		)
	)
	(zone
		(net "P12V_SW_L")
		(layer "B.Cu")
		(hatch none 0.5)
		(connect_pads
			(clearance 0.5)
		)
		(min_thickness 0.25)
		(fill yes
			(thermal_gap 0.5)
			(thermal_bridge_width 0.5)
			(island_removal_mode 0)
		)
		(polygon
			(pts
				(xy 83.316064 -9.058656) (xy 83.21675 -9.157716) (xy 83.100672 -9.273794) (xy 83.100672 -13.433806)
				(xy 83.382866 -13.716) (xy 86.741 -13.716) (xy 86.855808 -13.601192) (xy 86.855808 -9.164828) (xy 86.749636 -9.058656)
			)
		)
	)
	(zone
		(layers "B.Cu" "In2.Cu" "In3.Cu")
		(hatch none 0.5)
		(connect_pads
			(clearance 0)
		)
		(min_thickness 0.25)
		(keepout
			(tracks not_allowed)
			(vias allowed)
			(pads allowed)
			(copperpour not_allowed)
			(footprints allowed)
		)
		(placement
			(enabled no)
			(sheetname "")
		)
		(fill yes
			(thermal_gap 0.5)
			(thermal_bridge_width 0.5)
			(island_removal_mode 0)
		)
		(polygon
			(pts
				(arc
					(start 97.620074 -51.06162)
					(mid 96.931734 -51.74996)
					(end 97.620074 -52.4383)
				)
				(arc
					(start 98.890074 -52.4383)
					(mid 99.375905 -52.237587)
					(end 99.578414 -51.7525)
				)
				(arc
					(start 99.334574 -51.7525)
					(mid 98.890074 -52.194467)
					(end 98.445574 -51.7525)
				)
				(arc
					(start 98.064574 -51.7525)
					(mid 97.620074 -52.194467)
					(end 97.175574 -51.7525)
				)
				(arc
					(start 97.175574 -51.74996)
					(mid 97.620074 -51.30546)
					(end 98.064574 -51.74996)
				)
				(arc
					(start 98.445574 -51.74996)
					(mid 98.890074 -51.30546)
					(end 99.334574 -51.74996)
				)
				(arc
					(start 99.578414 -51.74996)
					(mid 99.376804 -51.26323)
					(end 98.890074 -51.06162)
				)
			)
		)
	)
	(zone
		(layers "B.Cu" "In2.Cu" "In3.Cu")
		(hatch none 0.5)
		(connect_pads
			(clearance 0)
		)
		(min_thickness 0.25)
		(keepout
			(tracks not_allowed)
			(vias allowed)
			(pads allowed)
			(copperpour not_allowed)
			(footprints allowed)
		)
		(placement
			(enabled no)
			(sheetname "")
		)
		(fill yes
			(thermal_gap 0.5)
			(thermal_bridge_width 0.5)
			(island_removal_mode 0)
		)
		(polygon
			(pts
				(arc
					(start 97.620074 -34.361628)
					(mid 96.931734 -35.049968)
					(end 97.620074 -35.738308)
				)
				(arc
					(start 98.890074 -35.738308)
					(mid 99.375905 -35.537595)
					(end 99.578414 -35.052508)
				)
				(arc
					(start 99.334574 -35.052508)
					(mid 98.890074 -35.494475)
					(end 98.445574 -35.052508)
				)
				(arc
					(start 98.064574 -35.052508)
					(mid 97.620074 -35.494475)
					(end 97.175574 -35.052508)
				)
				(arc
					(start 97.175574 -35.049968)
					(mid 97.620074 -34.605468)
					(end 98.064574 -35.049968)
				)
				(arc
					(start 98.445574 -35.049968)
					(mid 98.890074 -34.605468)
					(end 99.334574 -35.049968)
				)
				(arc
					(start 99.578414 -35.049968)
					(mid 99.376804 -34.563238)
					(end 98.890074 -34.361628)
				)
			)
		)
	)
	(zone
		(net "GND")
		(layer "In1.Cu")
		(hatch none 0.5)
		(connect_pads
			(clearance 0.5)
		)
		(min_thickness 0.25)
		(fill yes
			(thermal_gap 0.5)
			(thermal_bridge_width 0.5)
			(island_removal_mode 0)
		)
		(polygon
			(pts
				(arc
					(start 0.999998 -0.763016)
					(mid 0.832426 -0.832426)
					(end 0.763016 -0.999998)
				)
				(arc
					(start 0.763016 -22.200108)
					(mid 0.832426 -22.36768)
					(end 0.999998 -22.43709)
				)
				(arc
					(start 49.000156 -22.43709)
					(mid 49.893242 -22.806966)
					(end 50.263044 -23.699978)
				)
				(xy 50.263044 -23.93696)
				(arc
					(start 68.49999 -23.93696)
					(mid 69.746629 -24.453335)
					(end 70.263004 -25.699974)
				)
				(arc
					(start 70.263004 -64.200024)
					(mid 70.332414 -64.367596)
					(end 70.499986 -64.437006)
				)
				(arc
					(start 142.500096 -64.437006)
					(mid 142.667668 -64.367596)
					(end 142.737078 -64.200024)
				)
				(arc
					(start 142.737078 -0.999998)
					(mid 142.667668 -0.832426)
					(end 142.500096 -0.763016)
				)
				(arc
					(start 136.500108 -0.763016)
					(mid 136.332536 -0.832426)
					(end 136.263126 -0.999998)
				)
				(arc
					(start 136.263126 -18.050002)
					(mid 135.746751 -19.296641)
					(end 134.500112 -19.813016)
				)
				(arc
					(start 119.350028 -19.813016)
					(mid 119.182456 -19.882426)
					(end 119.113046 -20.049998)
				)
				(arc
					(start 119.113046 -23.999952)
					(mid 118.596671 -25.246591)
					(end 117.350032 -25.762966)
				)
				(arc
					(start 96.499934 -25.762966)
					(mid 95.253295 -25.246591)
					(end 94.73692 -23.999952)
				)
				(arc
					(start 94.73692 -0.999998)
					(mid 94.66751 -0.832426)
					(end 94.499938 -0.763016)
				)
			)
		)
	)
	(zone
		(layers "In1.Cu" "In4.Cu")
		(hatch none 0.5)
		(connect_pads
			(clearance 0)
		)
		(min_thickness 0.25)
		(keepout
			(tracks not_allowed)
			(vias allowed)
			(pads allowed)
			(copperpour not_allowed)
			(footprints allowed)
		)
		(placement
			(enabled no)
			(sheetname "")
		)
		(fill yes
			(thermal_gap 0.5)
			(thermal_bridge_width 0.5)
			(island_removal_mode 0)
		)
		(polygon
			(pts
				(arc
					(start 87.092536 -23.446994)
					(mid 86.581996 -22.936454)
					(end 86.071456 -23.446994)
				)
				(arc
					(start 86.071456 -24.46274)
					(mid 86.581869 -24.973534)
					(end 87.092536 -24.462994)
				)
			)
		)
	)
	(zone
		(layers "In1.Cu" "In4.Cu")
		(hatch none 0.5)
		(connect_pads
			(clearance 0)
		)
		(min_thickness 0.25)
		(keepout
			(tracks not_allowed)
			(vias allowed)
			(pads allowed)
			(copperpour not_allowed)
			(footprints allowed)
		)
		(placement
			(enabled no)
			(sheetname "")
		)
		(fill yes
			(thermal_gap 0.5)
			(thermal_bridge_width 0.5)
			(island_removal_mode 0)
		)
		(polygon
			(pts
				(arc
					(start 27.504898 -13.161772)
					(mid 26.816558 -13.850112)
					(end 27.504898 -14.538452)
				)
				(arc
					(start 28.774898 -14.538452)
					(mid 29.463238 -13.850112)
					(end 28.774898 -13.161772)
				)
			)
		)
	)
	(zone
		(layers "In1.Cu" "In4.Cu")
		(hatch none 0.5)
		(connect_pads
			(clearance 0)
		)
		(min_thickness 0.25)
		(keepout
			(tracks not_allowed)
			(vias allowed)
			(pads allowed)
			(copperpour not_allowed)
			(footprints allowed)
		)
		(placement
			(enabled no)
			(sheetname "")
		)
		(fill yes
			(thermal_gap 0.5)
			(thermal_bridge_width 0.5)
			(island_removal_mode 0)
		)
		(polygon
			(pts
				(arc
					(start 125.339856 -22.524974)
					(mid 125.493535 -21.366337)
					(end 126.651512 -21.20773)
				)
				(arc
					(start 126.750826 -21.108416)
					(mid 125.396197 -21.268997)
					(end 125.240542 -22.624288)
				)
			)
		)
	)
	(zone
		(layers "In1.Cu" "In4.Cu")
		(hatch none 0.5)
		(connect_pads
			(clearance 0)
		)
		(min_thickness 0.25)
		(keepout
			(tracks not_allowed)
			(vias allowed)
			(pads allowed)
			(copperpour not_allowed)
			(footprints allowed)
		)
		(placement
			(enabled no)
			(sheetname "")
		)
		(fill yes
			(thermal_gap 0.5)
			(thermal_bridge_width 0.5)
			(island_removal_mode 0)
		)
		(polygon
			(pts
				(arc
					(start 101.430074 -51.06162)
					(mid 100.741734 -51.74996)
					(end 101.430074 -52.4383)
				)
				(arc
					(start 102.700074 -52.4383)
					(mid 103.388414 -51.74996)
					(end 102.700074 -51.06162)
				)
			)
		)
	)
	(zone
		(layers "In1.Cu" "In4.Cu")
		(hatch none 0.5)
		(connect_pads
			(clearance 0)
		)
		(min_thickness 0.25)
		(keepout
			(tracks not_allowed)
			(vias allowed)
			(pads allowed)
			(copperpour not_allowed)
			(footprints allowed)
		)
		(placement
			(enabled no)
			(sheetname "")
		)
		(fill yes
			(thermal_gap 0.5)
			(thermal_bridge_width 0.5)
			(island_removal_mode 0)
		)
		(polygon
			(pts
				(arc
					(start 97.620074 -51.06162)
					(mid 96.931734 -51.74996)
					(end 97.620074 -52.4383)
				)
				(arc
					(start 98.890074 -52.4383)
					(mid 99.578414 -51.74996)
					(end 98.890074 -51.06162)
				)
			)
		)
	)
	(zone
		(layers "In1.Cu" "In4.Cu")
		(hatch none 0.5)
		(connect_pads
			(clearance 0)
		)
		(min_thickness 0.25)
		(keepout
			(tracks not_allowed)
			(vias allowed)
			(pads allowed)
			(copperpour not_allowed)
			(footprints allowed)
		)
		(placement
			(enabled no)
			(sheetname "")
		)
		(fill yes
			(thermal_gap 0.5)
			(thermal_bridge_width 0.5)
			(island_removal_mode 0)
		)
		(polygon
			(pts
				(arc
					(start 101.430074 -34.361628)
					(mid 100.741734 -35.049968)
					(end 101.430074 -35.738308)
				)
				(arc
					(start 102.700074 -35.738308)
					(mid 103.388414 -35.049968)
					(end 102.700074 -34.361628)
				)
			)
		)
	)
	(zone
		(layers "In1.Cu" "In4.Cu")
		(hatch none 0.5)
		(connect_pads
			(clearance 0)
		)
		(min_thickness 0.25)
		(keepout
			(tracks not_allowed)
			(vias allowed)
			(pads allowed)
			(copperpour not_allowed)
			(footprints allowed)
		)
		(placement
			(enabled no)
			(sheetname "")
		)
		(fill yes
			(thermal_gap 0.5)
			(thermal_bridge_width 0.5)
			(island_removal_mode 0)
		)
		(polygon
			(pts
				(arc
					(start 128.340104 -22.524974)
					(mid 128.493783 -21.366337)
					(end 129.65176 -21.20773)
				)
				(arc
					(start 129.751074 -21.108416)
					(mid 128.396445 -21.268997)
					(end 128.24079 -22.624288)
				)
			)
		)
	)
	(zone
		(layers "In1.Cu" "In4.Cu")
		(hatch none 0.5)
		(connect_pads
			(clearance 0)
		)
		(min_thickness 0.25)
		(keepout
			(tracks not_allowed)
			(vias allowed)
			(pads allowed)
			(copperpour not_allowed)
			(footprints allowed)
		)
		(placement
			(enabled no)
			(sheetname "")
		)
		(fill yes
			(thermal_gap 0.5)
			(thermal_bridge_width 0.5)
			(island_removal_mode 0)
		)
		(polygon
			(pts
				(arc
					(start 127.019812 -21.575014)
					(mid 126.866133 -22.733651)
					(end 125.708156 -22.892258)
				)
				(arc
					(start 125.608842 -22.991572)
					(mid 126.963471 -22.830991)
					(end 127.119126 -21.4757)
				)
			)
		)
	)
	(zone
		(layers "In1.Cu" "In4.Cu")
		(hatch none 0.5)
		(connect_pads
			(clearance 0)
		)
		(min_thickness 0.25)
		(keepout
			(tracks not_allowed)
			(vias allowed)
			(pads allowed)
			(copperpour not_allowed)
			(footprints allowed)
		)
		(placement
			(enabled no)
			(sheetname "")
		)
		(fill yes
			(thermal_gap 0.5)
			(thermal_bridge_width 0.5)
			(island_removal_mode 0)
		)
		(polygon
			(pts
				(arc
					(start 24.964898 -3.238246)
					(mid 25.653238 -2.549906)
					(end 24.964898 -1.861566)
				)
				(arc
					(start 23.694898 -1.861566)
					(mid 23.006558 -2.549906)
					(end 23.694898 -3.238246)
				)
			)
		)
	)
	(zone
		(layers "In1.Cu" "In4.Cu")
		(hatch none 0.5)
		(connect_pads
			(clearance 0)
		)
		(min_thickness 0.25)
		(keepout
			(tracks not_allowed)
			(vias allowed)
			(pads allowed)
			(copperpour not_allowed)
			(footprints allowed)
		)
		(placement
			(enabled no)
			(sheetname "")
		)
		(fill yes
			(thermal_gap 0.5)
			(thermal_bridge_width 0.5)
			(island_removal_mode 0)
		)
		(polygon
			(pts
				(arc
					(start 130.02006 -21.575014)
					(mid 129.866381 -22.733651)
					(end 128.708404 -22.892258)
				)
				(arc
					(start 128.60909 -22.991572)
					(mid 129.963719 -22.830991)
					(end 130.119374 -21.4757)
				)
			)
		)
	)
	(zone
		(layers "In1.Cu" "In4.Cu")
		(hatch none 0.5)
		(connect_pads
			(clearance 0)
		)
		(min_thickness 0.25)
		(keepout
			(tracks not_allowed)
			(vias allowed)
			(pads allowed)
			(copperpour not_allowed)
			(footprints allowed)
		)
		(placement
			(enabled no)
			(sheetname "")
		)
		(fill yes
			(thermal_gap 0.5)
			(thermal_bridge_width 0.5)
			(island_removal_mode 0)
		)
		(polygon
			(pts
				(arc
					(start 97.620074 -34.361628)
					(mid 96.931734 -35.049968)
					(end 97.620074 -35.738308)
				)
				(arc
					(start 98.890074 -35.738308)
					(mid 99.578414 -35.049968)
					(end 98.890074 -34.361628)
				)
			)
		)
	)
	(zone
		(layers "In1.Cu" "In4.Cu")
		(hatch none 0.5)
		(connect_pads
			(clearance 0)
		)
		(min_thickness 0.25)
		(keepout
			(tracks not_allowed)
			(vias allowed)
			(pads allowed)
			(copperpour not_allowed)
			(footprints allowed)
		)
		(placement
			(enabled no)
			(sheetname "")
		)
		(fill yes
			(thermal_gap 0.5)
			(thermal_bridge_width 0.5)
			(island_removal_mode 0)
		)
		(polygon
			(pts
				(arc
					(start 23.694898 -13.161772)
					(mid 23.006558 -13.850112)
					(end 23.694898 -14.538452)
				)
				(arc
					(start 24.964898 -14.538452)
					(mid 25.653238 -13.850112)
					(end 24.964898 -13.161772)
				)
			)
		)
	)
	(zone
		(layers "In1.Cu" "In4.Cu")
		(hatch none 0.5)
		(connect_pads
			(clearance 0)
		)
		(min_thickness 0.25)
		(keepout
			(tracks not_allowed)
			(vias allowed)
			(pads allowed)
			(copperpour not_allowed)
			(footprints allowed)
		)
		(placement
			(enabled no)
			(sheetname "")
		)
		(fill yes
			(thermal_gap 0.5)
			(thermal_bridge_width 0.5)
			(island_removal_mode 0)
		)
		(polygon
			(pts
				(arc
					(start 82.65287 -25.19807)
					(mid 82.142076 -25.708483)
					(end 82.652616 -26.21915)
				)
				(arc
					(start 83.668616 -26.21915)
					(mid 84.179156 -25.70861)
					(end 83.668616 -25.19807)
				)
			)
		)
	)
	(zone
		(layers "In1.Cu" "In4.Cu")
		(hatch none 0.5)
		(connect_pads
			(clearance 0)
		)
		(min_thickness 0.25)
		(keepout
			(tracks not_allowed)
			(vias allowed)
			(pads allowed)
			(copperpour not_allowed)
			(footprints allowed)
		)
		(placement
			(enabled no)
			(sheetname "")
		)
		(fill yes
			(thermal_gap 0.5)
			(thermal_bridge_width 0.5)
			(island_removal_mode 0)
		)
		(polygon
			(pts
				(arc
					(start 27.504898 -1.861566)
					(mid 26.816558 -2.549906)
					(end 27.504898 -3.238246)
				)
				(arc
					(start 28.774898 -3.238246)
					(mid 29.463238 -2.549906)
					(end 28.774898 -1.861566)
				)
			)
		)
	)
	(zone
		(layers "In1.Cu" "In4.Cu")
		(hatch none 0.5)
		(connect_pads
			(clearance 0)
		)
		(min_thickness 0.25)
		(keepout
			(tracks not_allowed)
			(vias allowed)
			(pads allowed)
			(copperpour not_allowed)
			(footprints allowed)
		)
		(placement
			(enabled no)
			(sheetname "")
		)
		(fill yes
			(thermal_gap 0.5)
			(thermal_bridge_width 0.5)
			(island_removal_mode 0)
		)
		(polygon
			(pts
				(arc
					(start 87.639652 -21.195538)
					(mid 87.129112 -20.684998)
					(end 86.618572 -21.195538)
				)
				(arc
					(start 86.618572 -22.211284)
					(mid 87.128985 -22.722078)
					(end 87.639652 -22.211538)
				)
			)
		)
	)
	(zone
		(layers "In1.Cu" "In4.Cu")
		(hatch none 0.5)
		(connect_pads
			(clearance 0)
		)
		(min_thickness 0.25)
		(keepout
			(tracks not_allowed)
			(vias allowed)
			(pads allowed)
			(copperpour not_allowed)
			(footprints allowed)
		)
		(placement
			(enabled no)
			(sheetname "")
		)
		(fill yes
			(thermal_gap 0.5)
			(thermal_bridge_width 0.5)
			(island_removal_mode 0)
		)
		(polygon
			(pts
				(arc
					(start 83.597496 -21.166836)
					(mid 83.086956 -20.656296)
					(end 82.576416 -21.166836)
				)
				(arc
					(start 82.576416 -22.182582)
					(mid 83.086829 -22.693376)
					(end 83.597496 -22.182836)
				)
			)
		)
	)
	(zone
		(layers "In1.Cu" "In4.Cu")
		(hatch none 0.5)
		(connect_pads
			(clearance 0)
		)
		(min_thickness 0.25)
		(keepout
			(tracks not_allowed)
			(vias allowed)
			(pads allowed)
			(copperpour not_allowed)
			(footprints allowed)
		)
		(placement
			(enabled no)
			(sheetname "")
		)
		(fill yes
			(thermal_gap 0.5)
			(thermal_bridge_width 0.5)
			(island_removal_mode 0)
		)
		(polygon
			(pts
				(arc
					(start 95.999554 -40.986964)
					(mid 95.10744 -41.356648)
					(end 94.737936 -42.248836)
				)
				(arc
					(start 94.737936 -45.748956)
					(mid 95.107604 -46.64116)
					(end 95.999808 -47.010828)
				)
				(arc
					(start 123.000008 -47.010828)
					(mid 123.892286 -46.641234)
					(end 124.26188 -45.748956)
				)
				(arc
					(start 124.26188 -42.248836)
					(mid 123.892286 -41.356558)
					(end 123.000008 -40.986964)
				)
			)
		)
	)
	(zone
		(net "GND")
		(layer "In2.Cu")
		(hatch none 0.5)
		(connect_pads
			(clearance 0.5)
		)
		(min_thickness 0.25)
		(fill yes
			(thermal_gap 0.5)
			(thermal_bridge_width 0.5)
			(island_removal_mode 0)
		)
		(polygon
			(pts
				(arc
					(start 136.500108 -0.762254)
					(mid 136.331998 -0.831888)
					(end 136.262364 -0.999998)
				)
				(arc
					(start 136.262364 -18.050002)
					(mid 136.146342 -18.678905)
					(end 135.813546 -19.225006)
				)
				(arc
					(start 135.813546 -19.225006)
					(mid 135.781171 -19.315412)
					(end 135.82142 -19.402552)
				)
				(arc
					(start 135.82142 -19.402552)
					(mid 135.492896 -20.976377)
					(end 134.249414 -19.957288)
				)
				(arc
					(start 134.249414 -19.957288)
					(mid 134.219663 -19.85606)
					(end 134.123684 -19.812254)
				)
				(xy 130.958336 -19.812254) (xy 130.958336 -19.813016) (xy 126.2507 -19.813016) (xy 125.565916 -20.4978)
				(xy 125.565916 -20.740624) (xy 125.56363 -20.740624)
				(arc
					(start 125.56363 -20.80895)
					(mid 125.619137 -20.913916)
					(end 125.737112 -20.92706)
				)
				(arc
					(start 125.737112 -20.92706)
					(mid 127.38689 -22.049994)
					(end 125.737112 -23.172928)
				)
				(arc
					(start 125.737112 -23.172928)
					(mid 125.619178 -23.186132)
					(end 125.56363 -23.291038)
				)
				(xy 125.56363 -29.072332) (xy 123.73737 -30.898592)
				(arc
					(start 123.73737 -34.298128)
					(mid 123.80038 -34.407829)
					(end 123.926854 -34.408618)
				)
				(arc
					(start 123.926854 -34.408618)
					(mid 124.403975 -34.321761)
					(end 124.831856 -34.550096)
				)
				(arc
					(start 124.831856 -34.550096)
					(mid 124.925074 -34.590891)
					(end 125.018292 -34.550096)
				)
				(arc
					(start 125.018292 -34.550096)
					(mid 125.560074 -34.312811)
					(end 126.101856 -34.550096)
				)
				(arc
					(start 126.101856 -34.550096)
					(mid 126.195074 -34.590891)
					(end 126.288292 -34.550096)
				)
				(arc
					(start 126.288292 -34.550096)
					(mid 126.830074 -34.312811)
					(end 127.371856 -34.550096)
				)
				(arc
					(start 127.371856 -34.550096)
					(mid 127.465074 -34.590891)
					(end 127.558292 -34.550096)
				)
				(arc
					(start 127.558292 -34.550096)
					(mid 128.837231 -35.049968)
					(end 127.558292 -35.54984)
				)
				(arc
					(start 127.558292 -35.54984)
					(mid 127.465074 -35.509045)
					(end 127.371856 -35.54984)
				)
				(arc
					(start 127.371856 -35.54984)
					(mid 126.830074 -35.787125)
					(end 126.288292 -35.54984)
				)
				(arc
					(start 126.288292 -35.54984)
					(mid 126.195074 -35.509045)
					(end 126.101856 -35.54984)
				)
				(arc
					(start 126.101856 -35.54984)
					(mid 125.560074 -35.787125)
					(end 125.018292 -35.54984)
				)
				(arc
					(start 125.018292 -35.54984)
					(mid 124.925074 -35.509045)
					(end 124.831856 -35.54984)
				)
				(arc
					(start 124.831856 -35.54984)
					(mid 124.40399 -35.778269)
					(end 123.926854 -35.691318)
				)
				(arc
					(start 123.926854 -35.691318)
					(mid 123.800413 -35.692164)
					(end 123.73737 -35.801808)
				)
				(arc
					(start 123.73737 -40.86606)
					(mid 124.34375 -41.44253)
					(end 124.567188 -42.248836)
				)
				(arc
					(start 124.567188 -45.748956)
					(mid 124.343827 -46.555308)
					(end 123.73737 -47.131732)
				)
				(arc
					(start 123.73737 -50.99812)
					(mid 123.80038 -51.107821)
					(end 123.926854 -51.10861)
				)
				(arc
					(start 123.926854 -51.10861)
					(mid 124.403975 -51.021753)
					(end 124.831856 -51.250088)
				)
				(arc
					(start 124.831856 -51.250088)
					(mid 124.925074 -51.290883)
					(end 125.018292 -51.250088)
				)
				(arc
					(start 125.018292 -51.250088)
					(mid 125.560074 -51.012803)
					(end 126.101856 -51.250088)
				)
				(arc
					(start 126.101856 -51.250088)
					(mid 126.195074 -51.290883)
					(end 126.288292 -51.250088)
				)
				(arc
					(start 126.288292 -51.250088)
					(mid 126.830074 -51.012803)
					(end 127.371856 -51.250088)
				)
				(arc
					(start 127.371856 -51.250088)
					(mid 127.465074 -51.290883)
					(end 127.558292 -51.250088)
				)
				(arc
					(start 127.558292 -51.250088)
					(mid 128.837231 -51.74996)
					(end 127.558292 -52.249832)
				)
				(arc
					(start 127.558292 -52.249832)
					(mid 127.465074 -52.209037)
					(end 127.371856 -52.249832)
				)
				(arc
					(start 127.371856 -52.249832)
					(mid 126.830074 -52.487117)
					(end 126.288292 -52.249832)
				)
				(arc
					(start 126.288292 -52.249832)
					(mid 126.195074 -52.209037)
					(end 126.101856 -52.249832)
				)
				(arc
					(start 126.101856 -52.249832)
					(mid 125.560074 -52.487117)
					(end 125.018292 -52.249832)
				)
				(arc
					(start 125.018292 -52.249832)
					(mid 124.925074 -52.209037)
					(end 124.831856 -52.249832)
				)
				(arc
					(start 124.831856 -52.249832)
					(mid 124.40399 -52.478261)
					(end 123.926854 -52.39131)
				)
				(arc
					(start 123.926854 -52.39131)
					(mid 123.800413 -52.392156)
					(end 123.73737 -52.5018)
				)
				(xy 123.73737 -58.724038) (xy 123.060206 -59.401202) (xy 79.582264 -59.401202) (xy 72.807068 -52.626006)
				(xy 72.807068 -31.659068) (xy 72.644 -31.496) (xy 70.517004 -31.496) (xy 70.263004 -31.75)
				(arc
					(start 70.263004 -64.200024)
					(mid 70.332414 -64.367596)
					(end 70.499986 -64.437006)
				)
				(arc
					(start 142.500096 -64.437006)
					(mid 142.667668 -64.367596)
					(end 142.737078 -64.200024)
				)
				(xy 142.737078 -27.059128) (xy 142.73784 -27.059128)
				(arc
					(start 142.73784 -0.999998)
					(mid 142.668206 -0.831888)
					(end 142.500096 -0.762254)
				)
			)
		)
	)
	(zone
		(net "P5V_SW_R")
		(layer "In2.Cu")
		(hatch none 0.5)
		(connect_pads
			(clearance 0.5)
		)
		(min_thickness 0.25)
		(fill yes
			(thermal_gap 0.5)
			(thermal_bridge_width 0.5)
			(island_removal_mode 0)
		)
		(polygon
			(pts
				(xy 85.001354 -43.312334) (xy 85.54847 -43.312334) (xy 86.38032 -43.312334) (xy 87.406226 -42.286428)
				(xy 87.406226 -35.97529) (xy 88.087454 -35.294062) (xy 90.067384 -33.314132) (xy 120.783096 -33.314132)
				(xy 121.220484 -33.75152) (xy 121.220484 -37.065966) (xy 121.220484 -40.591994) (xy 120.877076 -40.935402)
				(xy 95.31731 -40.935402) (xy 94.557342 -41.69537) (xy 94.557342 -46.63059) (xy 95.358712 -47.43196)
				(xy 120.156224 -47.43196) (xy 121.258838 -48.534574) (xy 121.258838 -53.0606) (xy 121.258838 -53.84673)
				(xy 120.77954 -54.326028) (xy 119.99341 -54.326028) (xy 96.250506 -54.326028) (xy 95.02267 -55.553864)
				(xy 94.315534 -56.261) (xy 83.785964 -56.261) (xy 83.078828 -55.553864) (xy 79.494888 -51.969924)
				(xy 79.494888 -51.952652) (xy 79.122778 -51.580542) (xy 79.122778 -43.981624) (xy 79.494888 -43.609514)
				(xy 79.792322 -43.31208) (xy 85.0011 -43.31208)
			)
		)
	)
	(zone
		(layer "In2.Cu")
		(hatch none 0.5)
		(connect_pads
			(clearance 0)
		)
		(min_thickness 0.25)
		(keepout
			(tracks not_allowed)
			(vias allowed)
			(pads allowed)
			(copperpour not_allowed)
			(footprints allowed)
		)
		(placement
			(enabled no)
			(sheetname "")
		)
		(fill
			(thermal_gap 0.5)
			(thermal_bridge_width 0.5)
			(island_removal_mode 0)
		)
		(polygon
			(pts
				(arc
					(start 24.596852 -2.799334)
					(mid 25.27928 -2.235524)
					(end 24.71547 -2.917952)
				)
				(xy 24.56815 -3.065272) (xy 24.56815 -3.238246)
				(arc
					(start 24.964898 -3.238246)
					(mid 25.653238 -2.549906)
					(end 24.964898 -1.861566)
				)
				(arc
					(start 23.694898 -1.861566)
					(mid 23.006558 -2.549906)
					(end 23.694898 -3.238246)
				)
				(xy 24.08047 -3.238246) (xy 24.08047 -3.054096)
				(arc
					(start 23.944326 -2.917952)
					(mid 23.380516 -2.235524)
					(end 24.062944 -2.799334)
				)
				(xy 24.199088 -2.935478) (xy 24.24811 -2.9845) (xy 24.24811 -3.054096) (xy 24.24811 -3.238246) (xy 24.40051 -3.238246)
				(xy 24.40051 -3.065272) (xy 24.40051 -2.995676) (xy 24.449532 -2.946654)
			)
		)
	)
	(zone
		(layer "In2.Cu")
		(hatch none 0.5)
		(connect_pads
			(clearance 0)
		)
		(min_thickness 0.25)
		(keepout
			(tracks not_allowed)
			(vias allowed)
			(pads allowed)
			(copperpour not_allowed)
			(footprints allowed)
		)
		(placement
			(enabled no)
			(sheetname "")
		)
		(fill
			(thermal_gap 0.5)
			(thermal_bridge_width 0.5)
			(island_removal_mode 0)
		)
		(polygon
			(pts
				(xy 83.404456 -26.05913) (xy 83.40979 -26.067004) (xy 83.404456 -26.092658) (xy 83.404456 -26.119074)
				(xy 83.397852 -26.125678) (xy 83.378802 -26.21915)
				(arc
					(start 83.668616 -26.21915)
					(mid 84.179156 -25.70861)
					(end 83.668616 -25.19807)
				)
				(arc
					(start 82.65287 -25.19807)
					(mid 82.142076 -25.708483)
					(end 82.652616 -26.21915)
				)
				(xy 82.857594 -26.21915) (xy 82.891376 -26.16835) (xy 82.916776 -26.043636) (xy 82.916776 -25.885648)
				(arc
					(start 82.879692 -25.848564)
					(mid 82.388935 -25.668326)
					(end 82.911188 -25.642824)
				)
				(xy 82.942176 -25.673812) (xy 83.035394 -25.76703) (xy 83.084416 -25.816052) (xy 83.084416 -25.885648)
				(xy 83.084416 -26.026872) (xy 83.08975 -26.034746) (xy 83.084416 -26.0604) (xy 83.084416 -26.086816)
				(xy 83.077558 -26.09342) (xy 83.055714 -26.201116) (xy 83.05927 -26.218388) (xy 83.058762 -26.21915)
				(xy 83.207606 -26.21915) (xy 83.236816 -26.075894) (xy 83.236816 -25.885648) (xy 83.236816 -25.816052)
				(xy 83.285838 -25.76703) (xy 83.379056 -25.673812)
				(arc
					(start 83.410044 -25.642824)
					(mid 83.932365 -25.668316)
					(end 83.44154 -25.848564)
				)
				(xy 83.404456 -25.885648)
			)
		)
	)
	(zone
		(net "P3V3")
		(layer "In2.Cu")
		(hatch none 0.5)
		(connect_pads
			(clearance 0.5)
		)
		(min_thickness 0.25)
		(fill yes
			(thermal_gap 0.5)
			(thermal_bridge_width 0.5)
			(island_removal_mode 0)
		)
		(polygon
			(pts
				(xy 82.094324 -13.513054) (xy 76.341986 -13.513054) (xy 73.695814 -16.159226) (xy 72.277224 -16.159226)
				(xy 69.880226 -16.159226) (xy 68.989194 -15.268194) (xy 68.989194 -12.803632) (xy 68.989194 -5.767324)
				(xy 68.989194 -4.54279) (xy 67.301872 -2.855468) (xy 67.301872 -2.232152) (xy 67.714622 -1.819402)
				(xy 69.709538 -1.819402) (xy 71.797164 -3.907028) (xy 73.120758 -5.230622) (xy 76.51369 -8.623554)
				(xy 78.326742 -8.623554) (xy 82.640932 -4.309364) (xy 84.653882 -4.309364) (xy 85.09508 -4.750562)
				(xy 85.09508 -6.006084) (xy 84.308696 -6.792468) (xy 84.308696 -7.981442) (xy 82.851752 -9.438386)
				(xy 82.851752 -12.755626)
			)
		)
	)
	(zone
		(layer "In2.Cu")
		(hatch none 0.5)
		(connect_pads
			(clearance 0)
		)
		(min_thickness 0.25)
		(keepout
			(tracks not_allowed)
			(vias allowed)
			(pads allowed)
			(copperpour not_allowed)
			(footprints allowed)
		)
		(placement
			(enabled no)
			(sheetname "")
		)
		(fill
			(thermal_gap 0.5)
			(thermal_bridge_width 0.5)
			(island_removal_mode 0)
		)
		(polygon
			(pts
				(arc
					(start 86.70163 -23.685246)
					(mid 86.39348 -23.258478)
					(end 86.820248 -23.566628)
				)
				(xy 86.994492 -23.740872) (xy 87.092536 -23.740872)
				(arc
					(start 87.092536 -23.446994)
					(mid 86.581996 -22.936454)
					(end 86.071456 -23.446994)
				)
				(arc
					(start 86.071456 -24.46274)
					(mid 86.581869 -24.973534)
					(end 87.092536 -24.462994)
				)
				(xy 87.092536 -24.228552) (xy 86.935056 -24.228552)
				(arc
					(start 86.820248 -24.34336)
					(mid 86.39348 -24.65151)
					(end 86.70163 -24.224742)
				)
				(xy 86.816438 -24.109934) (xy 86.86546 -24.060912) (xy 86.935056 -24.060912) (xy 87.092536 -24.060912)
				(xy 87.092536 -23.908512) (xy 86.994492 -23.908512) (xy 86.924896 -23.908512) (xy 86.875874 -23.85949)
			)
		)
	)
	(zone
		(net "P12V")
		(layer "In2.Cu")
		(hatch none 0.5)
		(connect_pads
			(clearance 0.5)
		)
		(min_thickness 0.25)
		(fill yes
			(thermal_gap 0.5)
			(thermal_bridge_width 0.5)
			(island_removal_mode 0)
		)
		(polygon
			(pts
				(xy 121.105422 -20.726146) (xy 119.112284 -22.719284)
				(arc
					(start 119.112284 -23.999952)
					(mid 118.596132 -25.246052)
					(end 117.350032 -25.762204)
				)
				(xy 96.499934 -25.762204) (xy 95.496634 -25.762204) (xy 94.231206 -24.496776) (xy 94.231206 -10.541)
				(xy 93.69425 -10.004044) (xy 87.865458 -10.004044) (xy 87.481918 -10.387584) (xy 87.481918 -13.378688)
				(xy 87.481918 -17.965674) (xy 89.32545 -19.809206) (xy 89.32545 -23.79472) (xy 83.633564 -29.486606)
				(xy 82.350102 -30.770068) (xy 79.093314 -34.026856) (xy 79.093314 -42.301668) (xy 79.572612 -42.780966)
				(xy 82.930238 -42.780966) (xy 83.937856 -42.780966) (xy 83.941412 -42.777156) (xy 86.32063 -42.777156)
				(xy 86.930484 -42.167302) (xy 86.930484 -35.683952) (xy 90.318082 -32.296354) (xy 121.195592 -32.296354)
				(xy 122.434604 -31.057342) (xy 123.06173 -30.430216) (xy 124.864622 -28.627324) (xy 124.864622 -20.7264)
				(xy 124.289312 -20.150836) (xy 121.680732 -20.150836)
			)
		)
	)
	(zone
		(layer "In2.Cu")
		(hatch none 0.5)
		(connect_pads
			(clearance 0)
		)
		(min_thickness 0.25)
		(keepout
			(tracks not_allowed)
			(vias allowed)
			(pads allowed)
			(copperpour not_allowed)
			(footprints allowed)
		)
		(placement
			(enabled no)
			(sheetname "")
		)
		(fill
			(thermal_gap 0.5)
			(thermal_bridge_width 0.5)
			(island_removal_mode 0)
		)
		(polygon
			(pts
				(arc
					(start 130.349244 -22.049994)
					(mid 128.01092 -22.049994)
					(end 130.349244 -22.049994)
				)
			)
		)
		(polygon
			(pts
				(arc
					(start 130.142234 -22.049994)
					(mid 128.21793 -22.049994)
					(end 130.142234 -22.049994)
				)
			)
		)
	)
	(zone
		(layer "In2.Cu")
		(hatch none 0.5)
		(connect_pads
			(clearance 0)
		)
		(min_thickness 0.25)
		(keepout
			(tracks not_allowed)
			(vias allowed)
			(pads allowed)
			(copperpour not_allowed)
			(footprints allowed)
		)
		(placement
			(enabled no)
			(sheetname "")
		)
		(fill
			(thermal_gap 0.5)
			(thermal_bridge_width 0.5)
			(island_removal_mode 0)
		)
		(polygon
			(pts
				(arc
					(start 24.596852 -14.09954)
					(mid 25.27928 -13.53573)
					(end 24.71547 -14.218158)
				)
				(xy 24.61133 -14.322298) (xy 24.61133 -14.538452)
				(arc
					(start 24.964898 -14.538452)
					(mid 25.653238 -13.850112)
					(end 24.964898 -13.161772)
				)
				(arc
					(start 23.694898 -13.161772)
					(mid 23.006558 -13.850112)
					(end 23.694898 -14.538452)
				)
				(xy 24.12365 -14.538452) (xy 24.12365 -14.397482)
				(arc
					(start 23.944326 -14.218158)
					(mid 23.380516 -13.53573)
					(end 24.062944 -14.09954)
				)
				(xy 24.242268 -14.278864) (xy 24.29129 -14.327886) (xy 24.29129 -14.397482) (xy 24.29129 -14.538452)
				(xy 24.44369 -14.538452) (xy 24.44369 -14.322298) (xy 24.44369 -14.252702) (xy 24.492712 -14.20368)
			)
		)
	)
	(zone
		(net "GND")
		(layer "In2.Cu")
		(hatch none 0.5)
		(connect_pads
			(clearance 0.5)
		)
		(min_thickness 0.25)
		(fill yes
			(thermal_gap 0.5)
			(thermal_bridge_width 0.5)
			(island_removal_mode 0)
		)
		(polygon
			(pts
				(arc
					(start 78.175104 -1.004824)
					(mid 78.828556 -1.435336)
					(end 79.334868 -2.032)
				)
				(xy 85.204808 -2.032) (xy 88.265 -2.032) (xy 88.519 -2.286) (xy 88.519 -3.683) (xy 87.757 -4.445)
				(xy 85.905594 -4.445) (xy 85.524594 -4.826) (xy 85.524594 -7.91337) (xy 86.716362 -9.105138) (xy 93.467936 -9.105138)
				(xy 94.73692 -9.105138)
				(arc
					(start 94.73692 -0.999998)
					(mid 94.66751 -0.832426)
					(end 94.499938 -0.763016)
				)
				(xy 78.229206 -0.763016)
				(arc
					(start 78.102206 -0.890016)
					(mid 78.121958 -0.958036)
					(end 78.175104 -1.004824)
				)
			)
		)
	)
	(zone
		(net "GND")
		(layer "In2.Cu")
		(hatch none 0.5)
		(connect_pads
			(clearance 0.5)
		)
		(min_thickness 0.25)
		(fill yes
			(thermal_gap 0.5)
			(thermal_bridge_width 0.5)
			(island_removal_mode 0)
		)
		(polygon
			(pts
				(xy 55.501794 -22.667976) (xy 53.310536 -20.476464) (xy 25.826212 -20.476464) (xy 25.39111 -20.041362)
				(xy 23.5458 -18.196052) (xy 17.629886 -18.196052)
				(arc
					(start 16.08836 -16.654526)
					(mid 15.993488 -16.617568)
					(end 15.901924 -16.662146)
				)
				(arc
					(start 15.901924 -16.662146)
					(mid 15.080207 -16.695447)
					(end 15.113508 -15.87373)
				)
				(arc
					(start 15.113508 -15.87373)
					(mid 15.15814 -15.782169)
					(end 15.121128 -15.687294)
				)
				(xy 14.962124 -15.52829) (xy 14.962124 -8.918956) (xy 15.887446 -7.993634)
				(arc
					(start 15.887446 -4.28117)
					(mid 15.814063 -3.819906)
					(end 15.887446 -3.358642)
				)
				(xy 15.887446 -0.933196) (xy 15.717266 -0.763016)
				(arc
					(start 0.999998 -0.763016)
					(mid 0.832426 -0.832426)
					(end 0.763016 -0.999998)
				)
				(arc
					(start 0.763016 -22.200108)
					(mid 0.832426 -22.36768)
					(end 0.999998 -22.43709)
				)
				(arc
					(start 49.000156 -22.43709)
					(mid 49.893242 -22.806966)
					(end 50.263044 -23.699978)
				)
				(xy 50.263044 -23.93696) (xy 55.245 -23.93696) (xy 55.501794 -23.680166)
			)
		)
	)
	(zone
		(net "P5V_SW_L")
		(layer "In2.Cu")
		(hatch none 0.5)
		(connect_pads
			(clearance 0.5)
		)
		(min_thickness 0.25)
		(fill yes
			(thermal_gap 0.5)
			(thermal_bridge_width 0.5)
			(island_removal_mode 0)
		)
		(polygon
			(pts
				(xy 55.059834 -15.96771) (xy 45.549312 -15.96771) (xy 44.590716 -15.009114) (xy 44.590716 -2.354326)
				(xy 45.03166 -1.913382) (xy 65.700656 -1.913382) (xy 68.136008 -4.348734) (xy 68.136008 -14.088618)
				(xy 67.67576 -14.548866) (xy 56.478678 -14.548866)
			)
		)
	)
	(zone
		(net "P3V3")
		(layer "In2.Cu")
		(hatch none 0.5)
		(connect_pads
			(clearance 0.5)
		)
		(min_thickness 0.25)
		(fill yes
			(thermal_gap 0.5)
			(thermal_bridge_width 0.5)
			(island_removal_mode 0)
		)
		(polygon
			(pts
				(xy 122.972322 -58.95467) (xy 81.425796 -58.95467) (xy 80.03667 -58.95467) (xy 74.884788 -53.802788)
				(xy 73.650094 -52.568094) (xy 73.650094 -33.188656) (xy 74.323194 -32.515556) (xy 75.330812 -32.515556)
				(xy 76.089002 -32.515556) (xy 76.921868 -32.515556) (xy 76.95184 -32.545528) (xy 77.695298 -33.288986)
				(xy 77.695298 -50.985928) (xy 81.963514 -55.254144) (xy 83.382104 -56.672734) (xy 122.991372 -56.672734)
				(xy 123.394216 -57.075578) (xy 123.374912 -57.094882) (xy 123.374912 -58.55208) (xy 123.01093 -58.916062)
			)
		)
	)
	(zone
		(layer "In2.Cu")
		(hatch none 0.5)
		(connect_pads
			(clearance 0)
		)
		(min_thickness 0.25)
		(keepout
			(tracks not_allowed)
			(vias allowed)
			(pads allowed)
			(copperpour not_allowed)
			(footprints allowed)
		)
		(placement
			(enabled no)
			(sheetname "")
		)
		(fill
			(thermal_gap 0.5)
			(thermal_bridge_width 0.5)
			(island_removal_mode 0)
		)
		(polygon
			(pts
				(arc
					(start 126.179834 -23.219156)
					(mid 126.179834 -20.880832)
					(end 126.179834 -23.219156)
				)
			)
		)
		(polygon
			(pts
				(arc
					(start 126.179834 -21.087842)
					(mid 126.179834 -23.012146)
					(end 126.179834 -21.087842)
				)
			)
		)
	)
	(zone
		(layers "In2.Cu" "In3.Cu")
		(hatch none 0.5)
		(connect_pads
			(clearance 0)
		)
		(min_thickness 0.25)
		(keepout
			(tracks not_allowed)
			(vias allowed)
			(pads allowed)
			(copperpour not_allowed)
			(footprints allowed)
		)
		(placement
			(enabled no)
			(sheetname "")
		)
		(fill yes
			(thermal_gap 0.5)
			(thermal_bridge_width 0.5)
			(island_removal_mode 0)
		)
		(polygon
			(pts
				(arc
					(start 83.597496 -21.166836)
					(mid 83.086956 -20.656296)
					(end 82.576416 -21.166836)
				)
				(arc
					(start 82.576416 -22.182582)
					(mid 83.085559 -22.693374)
					(end 83.597496 -22.185376)
				)
				(arc
					(start 83.353656 -22.185376)
					(mid 83.086956 -22.449548)
					(end 82.820256 -22.185376)
				)
				(arc
					(start 82.820256 -22.182836)
					(mid 83.086956 -21.916136)
					(end 83.353656 -22.182836)
				)
				(xy 83.597496 -22.182836) (xy 83.597496 -21.169376)
				(arc
					(start 83.353656 -21.169376)
					(mid 83.086956 -21.433548)
					(end 82.820256 -21.169376)
				)
				(arc
					(start 82.820256 -21.166836)
					(mid 83.086956 -20.900136)
					(end 83.353656 -21.166836)
				)
			)
		)
	)
	(zone
		(layers "In2.Cu" "In3.Cu")
		(hatch none 0.5)
		(connect_pads
			(clearance 0)
		)
		(min_thickness 0.25)
		(keepout
			(tracks not_allowed)
			(vias allowed)
			(pads allowed)
			(copperpour not_allowed)
			(footprints allowed)
		)
		(placement
			(enabled no)
			(sheetname "")
		)
		(fill yes
			(thermal_gap 0.5)
			(thermal_bridge_width 0.5)
			(island_removal_mode 0)
		)
		(polygon
			(pts
				(arc
					(start 79.757778 -3.50012)
					(mid 74.242422 -3.50012)
					(end 79.757778 -3.50012)
				)
			)
		)
	)
	(zone
		(layers "In2.Cu" "In3.Cu")
		(hatch none 0.5)
		(connect_pads
			(clearance 0)
		)
		(min_thickness 0.25)
		(keepout
			(tracks not_allowed)
			(vias allowed)
			(pads allowed)
			(copperpour not_allowed)
			(footprints allowed)
		)
		(placement
			(enabled no)
			(sheetname "")
		)
		(fill yes
			(thermal_gap 0.5)
			(thermal_bridge_width 0.5)
			(island_removal_mode 0)
		)
		(polygon
			(pts
				(arc
					(start 87.639652 -21.195538)
					(mid 87.129112 -20.684998)
					(end 86.618572 -21.195538)
				)
				(arc
					(start 86.618572 -22.211284)
					(mid 87.127715 -22.722076)
					(end 87.639652 -22.214078)
				)
				(arc
					(start 87.395812 -22.214078)
					(mid 87.129112 -22.47825)
					(end 86.862412 -22.214078)
				)
				(arc
					(start 86.862412 -22.211538)
					(mid 87.129112 -21.944838)
					(end 87.395812 -22.211538)
				)
				(xy 87.639652 -22.211538) (xy 87.639652 -21.198078)
				(arc
					(start 87.395812 -21.198078)
					(mid 87.129112 -21.46225)
					(end 86.862412 -21.198078)
				)
				(arc
					(start 86.862412 -21.195538)
					(mid 87.129112 -20.928838)
					(end 87.395812 -21.195538)
				)
			)
		)
	)
	(zone
		(net "GND")
		(layer "In3.Cu")
		(hatch none 0.5)
		(connect_pads
			(clearance 0.5)
		)
		(min_thickness 0.25)
		(fill yes
			(thermal_gap 0.5)
			(thermal_bridge_width 0.5)
			(island_removal_mode 0)
		)
		(polygon
			(pts
				(arc
					(start 136.500108 -0.763016)
					(mid 136.332536 -0.832426)
					(end 136.263126 -0.999998)
				)
				(arc
					(start 136.263126 -18.050002)
					(mid 136.147033 -18.679184)
					(end 135.814054 -19.225514)
				)
				(xy 135.814054 -21.161248) (xy 141.468094 -26.815288) (xy 141.468094 -58.518298) (xy 136.591802 -63.39459)
				(xy 84.736432 -63.39459) (xy 80.50911 -59.167268) (xy 71.713344 -59.167268)
				(arc
					(start 70.47992 -57.933844)
					(mid 70.341493 -57.906157)
					(end 70.263004 -58.023506)
				)
				(arc
					(start 70.263004 -64.200024)
					(mid 70.332414 -64.367596)
					(end 70.499986 -64.437006)
				)
				(xy 134.204202 -64.437006) (xy 134.20344 -64.437768)
				(arc
					(start 142.500096 -64.437768)
					(mid 142.668206 -64.368134)
					(end 142.73784 -64.200024)
				)
				(xy 142.73784 -57.648348) (xy 142.737078 -57.648348)
				(arc
					(start 142.737078 -0.999998)
					(mid 142.667668 -0.832426)
					(end 142.500096 -0.763016)
				)
			)
		)
	)
	(zone
		(layer "In3.Cu")
		(hatch none 0.5)
		(connect_pads
			(clearance 0)
		)
		(min_thickness 0.25)
		(keepout
			(tracks not_allowed)
			(vias allowed)
			(pads allowed)
			(copperpour not_allowed)
			(footprints allowed)
		)
		(placement
			(enabled no)
			(sheetname "")
		)
		(fill
			(thermal_gap 0.5)
			(thermal_bridge_width 0.5)
			(island_removal_mode 0)
		)
		(polygon
			(pts
				(arc
					(start 126.179834 -23.219156)
					(mid 126.179834 -20.880832)
					(end 126.179834 -23.219156)
				)
			)
		)
	)
	(zone
		(net "P12V")
		(layer "In3.Cu")
		(hatch none 0.5)
		(connect_pads
			(clearance 0.5)
		)
		(min_thickness 0.25)
		(fill yes
			(thermal_gap 0.5)
			(thermal_bridge_width 0.5)
			(island_removal_mode 0)
		)
		(polygon
			(pts
				(xy 88.189562 -18.670016) (xy 87.472774 -17.953228) (xy 87.472774 -10.453878) (xy 87.914226 -10.012426)
				(xy 93.869764 -10.012426) (xy 94.228158 -10.37082) (xy 94.228158 -26.059892) (xy 94.228158 -26.765504)
				(xy 93.040454 -27.953208) (xy 88.906096 -27.953208) (xy 88.189562 -27.236674) (xy 88.189562 -26.604468)
			)
		)
	)
	(zone
		(net "P12V_SW_L")
		(layer "In3.Cu")
		(hatch none 0.5)
		(connect_pads
			(clearance 0.5)
		)
		(min_thickness 0.25)
		(fill yes
			(thermal_gap 0.5)
			(thermal_bridge_width 0.5)
			(island_removal_mode 0)
		)
		(polygon
			(pts
				(xy 52.681886 -0.820166) (xy 51.972464 -1.529588)
				(arc
					(start 51.972464 -1.894586)
					(mid 52.081388 -1.963355)
					(end 52.17668 -2.050034)
				)
				(arc
					(start 52.17668 -2.050034)
					(mid 52.269898 -2.090829)
					(end 52.363116 -2.050034)
				)
				(arc
					(start 52.363116 -2.050034)
					(mid 52.904898 -1.812749)
					(end 53.44668 -2.050034)
				)
				(arc
					(start 53.44668 -2.050034)
					(mid 53.539898 -2.090829)
					(end 53.633116 -2.050034)
				)
				(arc
					(start 53.633116 -2.050034)
					(mid 54.912055 -2.549906)
					(end 53.633116 -3.049778)
				)
				(arc
					(start 53.633116 -3.049778)
					(mid 53.539898 -3.008983)
					(end 53.44668 -3.049778)
				)
				(arc
					(start 53.44668 -3.049778)
					(mid 52.904898 -3.287063)
					(end 52.363116 -3.049778)
				)
				(arc
					(start 52.363116 -3.049778)
					(mid 52.269898 -3.008983)
					(end 52.17668 -3.049778)
				)
				(arc
					(start 52.17668 -3.049778)
					(mid 52.08139 -3.136459)
					(end 51.972464 -3.205226)
				)
				(arc
					(start 51.972464 -13.194792)
					(mid 52.081388 -13.263561)
					(end 52.17668 -13.35024)
				)
				(arc
					(start 52.17668 -13.35024)
					(mid 52.269898 -13.391035)
					(end 52.363116 -13.35024)
				)
				(arc
					(start 52.363116 -13.35024)
					(mid 52.904898 -13.112955)
					(end 53.44668 -13.35024)
				)
				(arc
					(start 53.44668 -13.35024)
					(mid 53.539898 -13.391035)
					(end 53.633116 -13.35024)
				)
				(arc
					(start 53.633116 -13.35024)
					(mid 54.912055 -13.850112)
					(end 53.633116 -14.349984)
				)
				(arc
					(start 53.633116 -14.349984)
					(mid 53.539898 -14.309189)
					(end 53.44668 -14.349984)
				)
				(arc
					(start 53.44668 -14.349984)
					(mid 52.904898 -14.587269)
					(end 52.363116 -14.349984)
				)
				(arc
					(start 52.363116 -14.349984)
					(mid 52.269898 -14.309189)
					(end 52.17668 -14.349984)
				)
				(arc
					(start 52.17668 -14.349984)
					(mid 52.08139 -14.436665)
					(end 51.972464 -14.505432)
				)
				(xy 51.972464 -14.721332) (xy 52.471066 -15.219934)
				(arc
					(start 56.201564 -15.219934)
					(mid 56.730489 -14.248862)
					(end 57.827164 -14.391386)
				)
				(arc
					(start 57.827164 -14.391386)
					(mid 57.931333 -14.42234)
					(end 58.02122 -14.361414)
				)
				(arc
					(start 58.02122 -14.361414)
					(mid 59.705446 -13.690315)
					(end 60.785502 -15.146528)
				)
				(xy 61.663072 -15.146528) (xy 65.278 -11.5316) (xy 68.326 -11.5316) (xy 72.755506 -11.5316) (xy 75.066906 -13.843)
				(xy 75.066906 -13.859002) (xy 76.465684 -15.25778) (xy 84.605876 -15.25778) (xy 85.295994 -14.567662)
				(xy 85.295994 -7.702042) (xy 85.295994 -6.369558) (xy 85.295994 -2.6416) (xy 85.295994 -1.148588)
				(xy 84.967572 -0.820166) (xy 75.656186 -0.820166)
			)
		)
	)
	(zone
		(net "GND")
		(layer "In3.Cu")
		(hatch none 0.5)
		(connect_pads
			(clearance 0.5)
		)
		(min_thickness 0.25)
		(fill yes
			(thermal_gap 0.5)
			(thermal_bridge_width 0.5)
			(island_removal_mode 0)
		)
		(polygon
			(pts
				(xy 51.378612 -0.763016)
				(arc
					(start 0.999998 -0.763016)
					(mid 0.832426 -0.832426)
					(end 0.763016 -0.999998)
				)
				(arc
					(start 0.763016 -22.200108)
					(mid 0.832426 -22.36768)
					(end 0.999998 -22.43709)
				)
				(xy 12.02436 -22.43709) (xy 12.16787 -22.29358) (xy 12.16787 -21.231606) (xy 12.16787 -18.881852)
				(xy 12.16787 -17.411192) (xy 12.456668 -17.122394) (xy 13.927328 -17.122394) (xy 44.979082 -17.122394)
				(xy 47.83709 -14.264386) (xy 51.16322 -14.264386) (xy 51.378612 -14.048994) (xy 51.378612 -9.433814)
				(xy 51.378612 -1.858772)
			)
		)
	)
	(zone
		(net "P12V_SW_R")
		(layer "In3.Cu")
		(hatch none 0.5)
		(connect_pads
			(clearance 0.5)
		)
		(min_thickness 0.25)
		(fill yes
			(thermal_gap 0.5)
			(thermal_bridge_width 0.5)
			(island_removal_mode 0)
		)
		(polygon
			(pts
				(xy 129.836672 -35.200082) (xy 129.836672 -53.231288) (xy 129.549144 -53.518816) (xy 128.907032 -53.518816)
				(xy 126.586742 -53.518816) (xy 126.318518 -53.250592) (xy 126.318518 -51.237642) (xy 125.963426 -50.88255)
				(xy 124.027184 -50.88255) (xy 88.78951 -50.88255) (xy 82.111596 -44.204636) (xy 80.34274 -44.204636)
				(xy 79.77759 -43.639486) (xy 79.77759 -35.620452) (xy 80.877918 -34.520124) (xy 129.156714 -34.520124)
			)
		)
	)
	(zone
		(layer "In3.Cu")
		(hatch none 0.5)
		(connect_pads
			(clearance 0)
		)
		(min_thickness 0.25)
		(keepout
			(tracks not_allowed)
			(vias allowed)
			(pads allowed)
			(copperpour not_allowed)
			(footprints allowed)
		)
		(placement
			(enabled no)
			(sheetname "")
		)
		(fill
			(thermal_gap 0.5)
			(thermal_bridge_width 0.5)
			(island_removal_mode 0)
		)
		(polygon
			(pts
				(arc
					(start 130.349244 -22.049994)
					(mid 128.01092 -22.049994)
					(end 130.349244 -22.049994)
				)
			)
		)
	)
	(zone
		(net "P5V")
		(layer "In3.Cu")
		(hatch none 0.5)
		(connect_pads
			(clearance 0.5)
		)
		(min_thickness 0.25)
		(fill yes
			(thermal_gap 0.5)
			(thermal_bridge_width 0.5)
			(island_removal_mode 0)
		)
		(polygon
			(pts
				(xy 61.6204 -16.129) (xy 57.1246 -16.129) (xy 56.5658 -15.5702) (xy 47.55388 -15.5702) (xy 46.99508 -16.129)
				(xy 45.72 -17.40408) (xy 12.981686 -17.40408) (xy 12.627864 -17.757902) (xy 12.627864 -22.015704)
				(xy 13.050012 -22.437852)
				(arc
					(start 49.000156 -22.437852)
					(mid 49.892704 -22.807505)
					(end 50.262282 -23.699978)
				)
				(xy 50.262282 -23.937722)
				(arc
					(start 68.49999 -23.937722)
					(mid 69.74609 -24.453874)
					(end 70.262242 -25.699974)
				)
				(xy 70.262242 -57.28462) (xy 71.77913 -58.801508) (xy 80.71358 -58.801508) (xy 84.94776 -63.035688)
				(xy 136.53135 -63.035688) (xy 141.031214 -58.535824) (xy 141.031214 -26.970482) (xy 134.035546 -19.97456)
				(xy 121.29135 -19.97456) (xy 120.240298 -21.025612) (xy 119.648478 -21.025612) (xy 119.113046 -21.561044)
				(arc
					(start 119.113046 -23.999952)
					(mid 118.596671 -25.246591)
					(end 117.350032 -25.762966)
				)
				(xy 99.770184 -25.762966) (xy 95.795846 -25.762966) (xy 93.159326 -28.399486) (xy 88.668352 -28.399486)
				(xy 87.555578 -27.286712) (xy 87.555578 -26.68778) (xy 87.555578 -18.808192) (xy 86.811104 -18.063718)
				(xy 86.811104 -16.547084) (xy 85.956394 -15.692374) (xy 76.406756 -15.692374) (xy 74.64552 -13.931138)
				(xy 72.550782 -11.8364) (xy 68.475606 -11.8364) (xy 67.5132 -11.8364) (xy 67.1322 -12.2174) (xy 67.1322 -13.5636)
				(xy 66.7004 -13.9954) (xy 63.754 -13.9954)
			)
		)
	)
	(zone
		(net "GND")
		(layer "In4.Cu")
		(hatch none 0.5)
		(connect_pads
			(clearance 0.5)
		)
		(min_thickness 0.25)
		(fill yes
			(thermal_gap 0.5)
			(thermal_bridge_width 0.5)
			(island_removal_mode 0)
		)
		(polygon
			(pts
				(arc
					(start 0.999998 -0.763016)
					(mid 0.832426 -0.832426)
					(end 0.763016 -0.999998)
				)
				(arc
					(start 0.763016 -22.200108)
					(mid 0.832426 -22.36768)
					(end 0.999998 -22.43709)
				)
				(arc
					(start 49.000156 -22.43709)
					(mid 49.893242 -22.806966)
					(end 50.263044 -23.699978)
				)
				(xy 50.263044 -23.93696)
				(arc
					(start 68.49999 -23.93696)
					(mid 69.746629 -24.453335)
					(end 70.263004 -25.699974)
				)
				(arc
					(start 70.263004 -64.200024)
					(mid 70.332414 -64.367596)
					(end 70.499986 -64.437006)
				)
				(arc
					(start 142.500096 -64.437006)
					(mid 142.667668 -64.367596)
					(end 142.737078 -64.200024)
				)
				(arc
					(start 142.737078 -0.999998)
					(mid 142.667668 -0.832426)
					(end 142.500096 -0.763016)
				)
				(arc
					(start 136.500108 -0.763016)
					(mid 136.332536 -0.832426)
					(end 136.263126 -0.999998)
				)
				(arc
					(start 136.263126 -18.050002)
					(mid 135.746751 -19.296641)
					(end 134.500112 -19.813016)
				)
				(arc
					(start 119.350028 -19.813016)
					(mid 119.182456 -19.882426)
					(end 119.113046 -20.049998)
				)
				(arc
					(start 119.113046 -23.999952)
					(mid 118.596671 -25.246591)
					(end 117.350032 -25.762966)
				)
				(arc
					(start 96.499934 -25.762966)
					(mid 95.253295 -25.246591)
					(end 94.73692 -23.999952)
				)
				(arc
					(start 94.73692 -0.999998)
					(mid 94.66751 -0.832426)
					(end 94.499938 -0.763016)
				)
			)
		)
		(polygon
			(pts
				(arc
					(start 102.700074 -52.4383)
					(mid 103.388414 -51.74996)
					(end 102.700074 -51.06162)
				)
				(arc
					(start 101.430074 -51.06162)
					(mid 100.741734 -51.74996)
					(end 101.430074 -52.4383)
				)
			)
		)
		(polygon
			(pts
				(arc
					(start 98.890074 -52.4383)
					(mid 99.578414 -51.74996)
					(end 98.890074 -51.06162)
				)
				(arc
					(start 97.620074 -51.06162)
					(mid 96.931734 -51.74996)
					(end 97.620074 -52.4383)
				)
			)
		)
		(polygon
			(pts
				(arc
					(start 102.700074 -35.738308)
					(mid 103.388414 -35.049968)
					(end 102.700074 -34.361628)
				)
				(arc
					(start 101.430074 -34.361628)
					(mid 100.741734 -35.049968)
					(end 101.430074 -35.738308)
				)
			)
		)
		(polygon
			(pts
				(arc
					(start 98.890074 -35.738308)
					(mid 99.578414 -35.049968)
					(end 98.890074 -34.361628)
				)
				(arc
					(start 97.620074 -34.361628)
					(mid 96.931734 -35.049968)
					(end 97.620074 -35.738308)
				)
			)
		)
		(polygon
			(pts
				(arc
					(start 83.668616 -26.21915)
					(mid 84.179156 -25.70861)
					(end 83.668616 -25.19807)
				)
				(arc
					(start 82.652362 -25.19807)
					(mid 82.142076 -25.708737)
					(end 82.652616 -26.21915)
				)
			)
		)
		(polygon
			(pts
				(xy 85.111844 -23.40229) (xy 83.918044 -23.40229) (xy 83.918044 -24.507698) (xy 85.111844 -24.507698)
			)
		)
		(polygon
			(pts
				(xy 82.411824 -23.40229) (xy 81.218024 -23.40229) (xy 81.218024 -24.507698) (xy 82.411824 -24.507698)
			)
		)
		(polygon
			(pts
				(xy 78.881732 -23.40229) (xy 77.687932 -23.40229) (xy 77.687932 -24.507698) (xy 78.881732 -24.507698)
			)
		)
		(polygon
			(pts
				(xy 76.181712 -23.40229) (xy 74.987912 -23.40229) (xy 74.987912 -24.507698) (xy 76.181712 -24.507698)
			)
		)
		(polygon
			(pts
				(arc
					(start 86.071456 -24.463248)
					(mid 86.582123 -24.973534)
					(end 87.092536 -24.462994)
				)
				(arc
					(start 87.092536 -23.446994)
					(mid 86.581996 -22.936454)
					(end 86.071456 -23.446994)
				)
			)
		)
		(polygon
			(pts
				(xy 85.111844 -21.152104) (xy 83.918044 -21.152104) (xy 83.918044 -22.257766) (xy 85.111844 -22.257766)
			)
		)
		(polygon
			(pts
				(xy 82.411824 -21.152104) (xy 81.218024 -21.152104) (xy 81.218024 -22.257766) (xy 82.411824 -22.257766)
			)
		)
		(polygon
			(pts
				(xy 78.881732 -21.152104) (xy 77.687932 -21.152104) (xy 77.687932 -22.257766) (xy 78.881732 -22.257766)
			)
		)
		(polygon
			(pts
				(xy 76.181712 -21.152104) (xy 74.987912 -21.152104) (xy 74.987912 -22.257766) (xy 76.181712 -22.257766)
			)
		)
		(polygon
			(pts
				(arc
					(start 86.618572 -22.211792)
					(mid 87.129239 -22.722078)
					(end 87.639652 -22.211538)
				)
				(arc
					(start 87.639652 -21.195538)
					(mid 87.129112 -20.684998)
					(end 86.618572 -21.195538)
				)
			)
		)
		(polygon
			(pts
				(arc
					(start 82.576416 -22.18309)
					(mid 83.087083 -22.693376)
					(end 83.597496 -22.182836)
				)
				(arc
					(start 83.597496 -21.166836)
					(mid 83.086956 -20.656296)
					(end 82.576416 -21.166836)
				)
			)
		)
		(polygon
			(pts
				(arc
					(start 28.774898 -14.538452)
					(mid 29.463238 -13.850112)
					(end 28.774898 -13.161772)
				)
				(arc
					(start 27.504898 -13.161772)
					(mid 26.816558 -13.850112)
					(end 27.504898 -14.538452)
				)
			)
		)
		(polygon
			(pts
				(arc
					(start 24.964898 -14.538452)
					(mid 25.653238 -13.850112)
					(end 24.964898 -13.161772)
				)
				(arc
					(start 23.694898 -13.161772)
					(mid 23.006558 -13.850112)
					(end 23.694898 -14.538452)
				)
			)
		)
		(polygon
			(pts
				(arc
					(start 28.774898 -3.238246)
					(mid 29.463238 -2.549906)
					(end 28.774898 -1.861566)
				)
				(arc
					(start 27.504898 -1.861566)
					(mid 26.816558 -2.549906)
					(end 27.504898 -3.238246)
				)
			)
		)
		(polygon
			(pts
				(arc
					(start 24.964898 -3.238246)
					(mid 25.653238 -2.549906)
					(end 24.964898 -1.861566)
				)
				(arc
					(start 23.694898 -1.861566)
					(mid 23.006558 -2.549906)
					(end 23.694898 -3.238246)
				)
			)
		)
	)
	(zone
		(layer "In4.Cu")
		(hatch none 0.5)
		(connect_pads
			(clearance 0)
		)
		(min_thickness 0.25)
		(keepout
			(tracks not_allowed)
			(vias allowed)
			(pads allowed)
			(copperpour not_allowed)
			(footprints allowed)
		)
		(placement
			(enabled no)
			(sheetname "")
		)
		(fill
			(thermal_gap 0.5)
			(thermal_bridge_width 0.5)
			(island_removal_mode 0)
		)
		(polygon
			(pts
				(xy 77.687932 -21.152104) (xy 78.881732 -21.152104) (xy 78.881732 -22.257766) (xy 77.687932 -22.257766)
			)
		)
	)
	(zone
		(layer "In4.Cu")
		(hatch none 0.5)
		(connect_pads
			(clearance 0)
		)
		(min_thickness 0.25)
		(keepout
			(tracks not_allowed)
			(vias allowed)
			(pads allowed)
			(copperpour not_allowed)
			(footprints allowed)
		)
		(placement
			(enabled no)
			(sheetname "")
		)
		(fill
			(thermal_gap 0.5)
			(thermal_bridge_width 0.5)
			(island_removal_mode 0)
		)
		(polygon
			(pts
				(xy 77.687932 -23.40229) (xy 78.881732 -23.40229) (xy 78.881732 -24.507698) (xy 77.687932 -24.507698)
			)
		)
	)
	(zone
		(layer "In4.Cu")
		(hatch none 0.5)
		(connect_pads
			(clearance 0)
		)
		(min_thickness 0.25)
		(keepout
			(tracks not_allowed)
			(vias allowed)
			(pads allowed)
			(copperpour not_allowed)
			(footprints allowed)
		)
		(placement
			(enabled no)
			(sheetname "")
		)
		(fill
			(thermal_gap 0.5)
			(thermal_bridge_width 0.5)
			(island_removal_mode 0)
		)
		(polygon
			(pts
				(xy 83.918044 -21.152104) (xy 85.111844 -21.152104) (xy 85.111844 -22.257766) (xy 83.918044 -22.257766)
			)
		)
	)
	(zone
		(layer "In4.Cu")
		(hatch none 0.5)
		(connect_pads
			(clearance 0)
		)
		(min_thickness 0.25)
		(keepout
			(tracks not_allowed)
			(vias allowed)
			(pads allowed)
			(copperpour not_allowed)
			(footprints allowed)
		)
		(placement
			(enabled no)
			(sheetname "")
		)
		(fill
			(thermal_gap 0.5)
			(thermal_bridge_width 0.5)
			(island_removal_mode 0)
		)
		(polygon
			(pts
				(xy 83.918044 -23.40229) (xy 85.111844 -23.40229) (xy 85.111844 -24.507698) (xy 83.918044 -24.507698)
			)
		)
	)
	(zone
		(layer "In4.Cu")
		(hatch none 0.5)
		(connect_pads
			(clearance 0)
		)
		(min_thickness 0.25)
		(keepout
			(tracks not_allowed)
			(vias allowed)
			(pads allowed)
			(copperpour not_allowed)
			(footprints allowed)
		)
		(placement
			(enabled no)
			(sheetname "")
		)
		(fill
			(thermal_gap 0.5)
			(thermal_bridge_width 0.5)
			(island_removal_mode 0)
		)
		(polygon
			(pts
				(xy 74.987912 -23.40229) (xy 76.181712 -23.40229) (xy 76.181712 -24.507698) (xy 74.987912 -24.507698)
			)
		)
	)
	(zone
		(layer "In4.Cu")
		(hatch none 0.5)
		(connect_pads
			(clearance 0)
		)
		(min_thickness 0.25)
		(keepout
			(tracks not_allowed)
			(vias allowed)
			(pads allowed)
			(copperpour not_allowed)
			(footprints allowed)
		)
		(placement
			(enabled no)
			(sheetname "")
		)
		(fill
			(thermal_gap 0.5)
			(thermal_bridge_width 0.5)
			(island_removal_mode 0)
		)
		(polygon
			(pts
				(xy 81.218024 -23.40229) (xy 82.411824 -23.40229) (xy 82.411824 -24.507698) (xy 81.218024 -24.507698)
			)
		)
	)
	(zone
		(layer "In4.Cu")
		(hatch none 0.5)
		(connect_pads
			(clearance 0)
		)
		(min_thickness 0.25)
		(keepout
			(tracks not_allowed)
			(vias allowed)
			(pads allowed)
			(copperpour not_allowed)
			(footprints allowed)
		)
		(placement
			(enabled no)
			(sheetname "")
		)
		(fill
			(thermal_gap 0.5)
			(thermal_bridge_width 0.5)
			(island_removal_mode 0)
		)
		(polygon
			(pts
				(xy 74.987912 -21.152104) (xy 76.181712 -21.152104) (xy 76.181712 -22.257766) (xy 74.987912 -22.257766)
			)
		)
	)
	(zone
		(layer "In4.Cu")
		(hatch none 0.5)
		(connect_pads
			(clearance 0)
		)
		(min_thickness 0.25)
		(keepout
			(tracks not_allowed)
			(vias allowed)
			(pads allowed)
			(copperpour not_allowed)
			(footprints allowed)
		)
		(placement
			(enabled no)
			(sheetname "")
		)
		(fill
			(thermal_gap 0.5)
			(thermal_bridge_width 0.5)
			(island_removal_mode 0)
		)
		(polygon
			(pts
				(xy 81.218024 -21.152104) (xy 82.411824 -21.152104) (xy 82.411824 -22.257766) (xy 81.218024 -22.257766)
			)
		)
	)
	(zone
		(layer "Cmts.User")
		(hatch none 0.5)
		(connect_pads
			(clearance 0)
		)
		(min_thickness 0.25)
		(keepout
			(tracks allowed)
			(vias allowed)
			(pads allowed)
			(copperpour allowed)
			(footprints allowed)
		)
		(placement
			(enabled no)
			(sheetname "")
		)
		(fill
			(thermal_gap 0.5)
			(thermal_bridge_width 0.5)
			(island_removal_mode 0)
		)
		(polygon
			(pts
				(xy 100.99421 -35.475164) (xy 100.99421 -34.623502) (xy 103.159306 -34.623502) (xy 103.159306 -35.475164)
			)
		)
	)
	(zone
		(layer "Cmts.User")
		(hatch none 0.5)
		(connect_pads
			(clearance 0)
		)
		(min_thickness 0.25)
		(keepout
			(tracks allowed)
			(vias allowed)
			(pads allowed)
			(copperpour allowed)
			(footprints allowed)
		)
		(placement
			(enabled no)
			(sheetname "")
		)
		(fill
			(thermal_gap 0.5)
			(thermal_bridge_width 0.5)
			(island_removal_mode 0)
		)
		(polygon
			(pts
				(xy 82.756248 -22.490176) (xy 82.756248 -20.83308) (xy 83.36153 -20.83308) (xy 83.36153 -22.490176)
			)
		)
	)
	(zone
		(layer "Cmts.User")
		(hatch none 0.5)
		(connect_pads
			(clearance 0)
		)
		(min_thickness 0.25)
		(keepout
			(tracks allowed)
			(vias allowed)
			(pads allowed)
			(copperpour allowed)
			(footprints allowed)
		)
		(placement
			(enabled no)
			(sheetname "")
		)
		(fill
			(thermal_gap 0.5)
			(thermal_bridge_width 0.5)
			(island_removal_mode 0)
		)
		(polygon
			(pts
				(xy 100.992686 -52.190142) (xy 100.992686 -51.33848) (xy 103.157782 -51.33848) (xy 103.157782 -52.190142)
			)
		)
	)
	(zone
		(layer "Cmts.User")
		(hatch none 0.5)
		(connect_pads
			(clearance 0)
		)
		(min_thickness 0.25)
		(keepout
			(tracks allowed)
			(vias allowed)
			(pads allowed)
			(copperpour allowed)
			(footprints allowed)
		)
		(placement
			(enabled no)
			(sheetname "")
		)
		(fill
			(thermal_gap 0.5)
			(thermal_bridge_width 0.5)
			(island_removal_mode 0)
		)
		(polygon
			(pts
				(xy 97.1931 -52.174648) (xy 97.1931 -51.322986) (xy 99.358196 -51.322986) (xy 99.358196 -52.174648)
			)
		)
	)
	(zone
		(layer "Cmts.User")
		(hatch none 0.5)
		(connect_pads
			(clearance 0)
		)
		(min_thickness 0.25)
		(keepout
			(tracks allowed)
			(vias allowed)
			(pads allowed)
			(copperpour allowed)
			(footprints allowed)
		)
		(placement
			(enabled no)
			(sheetname "")
		)
		(fill
			(thermal_gap 0.5)
			(thermal_bridge_width 0.5)
			(island_removal_mode 0)
		)
		(polygon
			(pts
				(xy 97.226882 -35.483546) (xy 97.226882 -34.631884) (xy 99.391978 -34.631884) (xy 99.391978 -35.483546)
			)
		)
	)
	(zone
		(layer "Cmts.User")
		(hatch none 0.5)
		(connect_pads
			(clearance 0)
		)
		(min_thickness 0.25)
		(keepout
			(tracks allowed)
			(vias allowed)
			(pads allowed)
			(copperpour allowed)
			(footprints allowed)
		)
		(placement
			(enabled no)
			(sheetname "")
		)
		(fill
			(thermal_gap 0.5)
			(thermal_bridge_width 0.5)
			(island_removal_mode 0)
		)
		(polygon
			(pts
				(xy 82.347054 -25.409398) (xy 84.00415 -25.409398) (xy 84.00415 -26.01468) (xy 82.347054 -26.01468)
			)
		)
	)
	(zone
		(layer "Cmts.User")
		(hatch none 0.5)
		(connect_pads
			(clearance 0)
		)
		(min_thickness 0.25)
		(keepout
			(tracks allowed)
			(vias allowed)
			(pads allowed)
			(copperpour allowed)
			(footprints allowed)
		)
		(placement
			(enabled no)
			(sheetname "")
		)
		(fill
			(thermal_gap 0.5)
			(thermal_bridge_width 0.5)
			(island_removal_mode 0)
		)
		(polygon
			(pts
				(xy 27.064462 -2.998216) (xy 27.064462 -2.146554) (xy 29.229558 -2.146554) (xy 29.229558 -2.998216)
			)
		)
	)
	(zone
		(layer "Cmts.User")
		(hatch none 0.5)
		(connect_pads
			(clearance 0)
		)
		(min_thickness 0.25)
		(keepout
			(tracks allowed)
			(vias allowed)
			(pads allowed)
			(copperpour allowed)
			(footprints allowed)
		)
		(placement
			(enabled no)
			(sheetname "")
		)
		(fill
			(thermal_gap 0.5)
			(thermal_bridge_width 0.5)
			(island_removal_mode 0)
		)
		(polygon
			(pts
				(xy 86.275672 -24.783542) (xy 86.275672 -23.126446) (xy 86.880954 -23.126446) (xy 86.880954 -24.783542)
			)
		)
	)
	(zone
		(layer "Cmts.User")
		(hatch none 0.5)
		(connect_pads
			(clearance 0)
		)
		(min_thickness 0.25)
		(keepout
			(tracks allowed)
			(vias allowed)
			(pads allowed)
			(copperpour allowed)
			(footprints allowed)
		)
		(placement
			(enabled no)
			(sheetname "")
		)
		(fill
			(thermal_gap 0.5)
			(thermal_bridge_width 0.5)
			(island_removal_mode 0)
		)
		(polygon
			(pts
				(xy 86.829646 -22.531324) (xy 86.829646 -20.874228) (xy 87.434928 -20.874228) (xy 87.434928 -22.531324)
			)
		)
	)
	(zone
		(layer "Cmts.User")
		(hatch none 0.5)
		(connect_pads
			(clearance 0)
		)
		(min_thickness 0.25)
		(keepout
			(tracks allowed)
			(vias allowed)
			(pads allowed)
			(copperpour allowed)
			(footprints allowed)
		)
		(placement
			(enabled no)
			(sheetname "")
		)
		(fill
			(thermal_gap 0.5)
			(thermal_bridge_width 0.5)
			(island_removal_mode 0)
		)
		(polygon
			(pts
				(xy 23.257764 -2.967228) (xy 23.257764 -2.115566) (xy 25.42286 -2.115566) (xy 25.42286 -2.967228)
			)
		)
	)
	(zone
		(layer "Cmts.User")
		(hatch none 0.5)
		(connect_pads
			(clearance 0)
		)
		(min_thickness 0.25)
		(keepout
			(tracks allowed)
			(vias allowed)
			(pads allowed)
			(copperpour allowed)
			(footprints allowed)
		)
		(placement
			(enabled no)
			(sheetname "")
		)
		(fill
			(thermal_gap 0.5)
			(thermal_bridge_width 0.5)
			(island_removal_mode 0)
		)
		(polygon
			(pts
				(xy 23.268178 -14.261084) (xy 23.268178 -13.409422) (xy 25.433274 -13.409422) (xy 25.433274 -14.261084)
			)
		)
	)
	(zone
		(layer "Cmts.User")
		(hatch none 0.5)
		(connect_pads
			(clearance 0)
		)
		(min_thickness 0.25)
		(keepout
			(tracks allowed)
			(vias allowed)
			(pads allowed)
			(copperpour allowed)
			(footprints allowed)
		)
		(placement
			(enabled no)
			(sheetname "")
		)
		(fill
			(thermal_gap 0.5)
			(thermal_bridge_width 0.5)
			(island_removal_mode 0)
		)
		(polygon
			(pts
				(xy 27.02052 -14.281658) (xy 27.02052 -13.429996) (xy 29.185616 -13.429996) (xy 29.185616 -14.281658)
			)
		)
	)
)
